G04 ================== begin FILE IDENTIFICATION RECORD ==================*
G04 Layout Name:  13919-sa.brd*
G04 Film Name:    13919-sa_X_Y*
G04 File Format:  Gerber RS274X*
G04 File Origin:  Cadence Allegro 16.5-S039*
G04 Origin Date:  Fri Nov 22 15:26:57 2013*
G04 *
G04 Layer:  BOARD GEOMETRY/PANEL_DRAWING*
G04 *
G04 Offset:    (0.00 0.00)*
G04 Mirror:    No*
G04 Mode:      Positive*
G04 Rotation:  0*
G04 FullContactRelief:  No*
G04 UndefLineWidth:     6.00*
G04 ================== end FILE IDENTIFICATION RECORD ====================*
%FSLAX35Y35*MOIN*%
%IR0*IPPOS*OFA0.00000B0.00000*MIA0B0*SFA1.00000B1.00000*%
%ADD10C,.006*%
G75*
%LPD*%
G75*
G54D10*
G01X-329267Y-367117D02*
Y-361211D01*
X-326462D01*
G01X-327495Y-364065D02*
X-329267D01*
G01X-326388Y-130896D02*
X-329341D01*
Y-124990D01*
X-326388D01*
G01X-327569Y-127844D02*
X-329341D01*
G01X-329488Y105324D02*
Y111230D01*
X-328012D01*
X-327422Y110935D01*
X-326979Y110541D01*
X-326610Y109950D01*
X-326314Y109261D01*
X-326241Y108277D01*
X-326314Y107293D01*
X-326610Y106604D01*
X-326979Y106013D01*
X-327422Y105619D01*
X-328012Y105324D01*
X-329488D01*
G01X-326241Y346959D02*
X-326683Y347254D01*
X-327200Y347451D01*
X-327791D01*
X-328455Y347156D01*
X-328972Y346664D01*
X-329341Y346073D01*
X-329636Y345089D01*
X-329710Y344203D01*
X-329562Y343317D01*
X-329341Y342726D01*
X-328898Y342135D01*
X-328381Y341742D01*
X-327865Y341545D01*
X-327348D01*
X-326831Y341742D01*
X-326388Y342037D01*
X-326019Y342431D01*
G01X-327274Y580915D02*
X-326979Y581210D01*
X-326757Y581702D01*
X-326610Y582391D01*
X-326757Y582982D01*
X-327052Y583376D01*
X-327569Y583671D01*
X-329562D01*
Y577765D01*
X-327126D01*
X-326610Y578159D01*
X-326314Y578749D01*
X-326167Y579438D01*
X-326314Y580127D01*
X-326757Y580718D01*
X-327274Y580915D01*
X-329562D01*
G01X-329710Y813986D02*
X-327865Y819892D01*
X-326019Y813986D01*
G01X-326683Y816053D02*
X-329046D01*
G01X-249912Y-437195D02*
Y-431289D01*
X-250797Y-432470D01*
G01Y-437195D02*
X-249026D01*
G01X-249912Y923435D02*
Y929341D01*
X-250797Y928160D01*
G01Y923435D02*
X-249026D01*
G01X-87572Y3908D02*
X-88356Y3647D01*
X-88944Y2993D01*
X-89336Y2208D01*
X-89631Y1162D01*
X-89729Y-15D01*
X-89631Y-1191D01*
X-89336Y-2237D01*
X-88944Y-3022D01*
X-88356Y-3676D01*
X-87572Y-3937D01*
X-86787Y-3676D01*
X-86199Y-3022D01*
X-85807Y-2237D01*
X-85512Y-1191D01*
X-85414Y-15D01*
X-85512Y1162D01*
X-85807Y2208D01*
X-86199Y2993D01*
X-86787Y3647D01*
X-87572Y3908D01*
G01X-79728Y-4198D02*
X-79924Y-4068D01*
Y-3806D01*
X-79728Y-3676D01*
X-79531Y-3806D01*
Y-4068D01*
X-79728Y-4198D01*
G01X-71884Y3908D02*
X-72668Y3647D01*
X-73256Y2993D01*
X-73648Y2208D01*
X-73943Y1162D01*
X-74041Y-15D01*
X-73943Y-1191D01*
X-73648Y-2237D01*
X-73256Y-3022D01*
X-72668Y-3676D01*
X-71884Y-3937D01*
X-71099Y-3676D01*
X-70511Y-3022D01*
X-70119Y-2237D01*
X-69824Y-1191D01*
X-69726Y-15D01*
X-69824Y1162D01*
X-70119Y2208D01*
X-70511Y2993D01*
X-71099Y3647D01*
X-71884Y3908D01*
G01X-64040D02*
X-64824Y3647D01*
X-65412Y2993D01*
X-65804Y2208D01*
X-66099Y1162D01*
X-66197Y-15D01*
X-66099Y-1191D01*
X-65804Y-2237D01*
X-65412Y-3022D01*
X-64824Y-3676D01*
X-64040Y-3937D01*
X-63255Y-3676D01*
X-62667Y-3022D01*
X-62275Y-2237D01*
X-61980Y-1191D01*
X-61882Y-15D01*
X-61980Y1162D01*
X-62275Y2208D01*
X-62667Y2993D01*
X-63255Y3647D01*
X-64040Y3908D01*
G01X-88089Y-17134D02*
Y-11937D01*
X-85621D01*
G01X-86530Y-14449D02*
X-88089D01*
G01X-81658Y-13669D02*
Y-17134D01*
G01Y-12284D02*
X-81788Y-12197D01*
Y-12024D01*
X-81658Y-11937D01*
X-81528Y-12024D01*
Y-12197D01*
X-81658Y-12284D01*
G01X-75292Y-11937D02*
Y-17134D01*
G01Y-16355D02*
X-75551Y-16788D01*
X-75941Y-17047D01*
X-76396Y-17134D01*
X-76916Y-16961D01*
X-77306Y-16528D01*
X-77565Y-16008D01*
X-77630Y-15402D01*
X-77565Y-14795D01*
X-77306Y-14276D01*
X-76916Y-13843D01*
X-76396Y-13669D01*
X-75941Y-13756D01*
X-75616Y-13929D01*
X-75292Y-14276D01*
G01X-72368Y-13669D02*
Y-16095D01*
X-72109Y-16701D01*
X-71719Y-17047D01*
X-71264Y-17134D01*
X-70809Y-17047D01*
X-70419Y-16701D01*
X-70160Y-16095D01*
G01Y-17134D02*
Y-13669D01*
G01X-65028Y-14102D02*
X-65482Y-13756D01*
X-65872Y-13669D01*
X-66392Y-13843D01*
X-66782Y-14189D01*
X-67041Y-14795D01*
X-67107Y-15402D01*
X-67041Y-16008D01*
X-66782Y-16528D01*
X-66392Y-16961D01*
X-65872Y-17134D01*
X-65417Y-16961D01*
X-65028Y-16614D01*
G01X-60870Y-13669D02*
Y-17134D01*
G01Y-12284D02*
X-61000Y-12197D01*
Y-12024D01*
X-60870Y-11937D01*
X-60740Y-12024D01*
Y-12197D01*
X-60870Y-12284D01*
G01X-54504Y-17134D02*
Y-13669D01*
G01Y-14276D02*
X-54763Y-13929D01*
X-55153Y-13756D01*
X-55608Y-13669D01*
X-56063Y-13843D01*
X-56453Y-14189D01*
X-56713Y-14709D01*
X-56842Y-15402D01*
X-56713Y-16095D01*
X-56453Y-16614D01*
X-56063Y-16961D01*
X-55608Y-17134D01*
X-55153Y-17047D01*
X-54763Y-16788D01*
X-54504Y-16441D01*
G01X-50476Y-17134D02*
Y-11937D01*
G01X-41771Y-17134D02*
Y-11937D01*
X-40082Y-16268D01*
X-38393Y-11937D01*
Y-17134D01*
G01X-33716D02*
Y-13669D01*
G01Y-14276D02*
X-33975Y-13929D01*
X-34365Y-13756D01*
X-34820Y-13669D01*
X-35275Y-13843D01*
X-35665Y-14189D01*
X-35925Y-14709D01*
X-36054Y-15402D01*
X-35925Y-16095D01*
X-35665Y-16614D01*
X-35275Y-16961D01*
X-34820Y-17134D01*
X-34365Y-17047D01*
X-33975Y-16788D01*
X-33716Y-16441D01*
G01X-30598Y-17134D02*
Y-13669D01*
G01Y-14362D02*
X-30273Y-14016D01*
X-29948Y-13756D01*
X-29493Y-13669D01*
X-29168Y-13756D01*
X-28778Y-14016D01*
G01X-25595Y-17134D02*
Y-11937D01*
G01X-23517Y-13669D02*
X-25595Y-15662D01*
G01X-24751Y-14882D02*
X-23387Y-17134D01*
G01X-15071Y-13669D02*
X-13123Y-17134D01*
G01Y-13669D02*
X-15071Y-17134D01*
G01X-5132Y-16095D02*
X-4743Y-16701D01*
X-4223Y-17047D01*
X-3638Y-17134D01*
X-3118Y-17047D01*
X-2599Y-16614D01*
X-2274Y-16095D01*
X-2209Y-15575D01*
X-2339Y-14969D01*
X-2793Y-14536D01*
X-3248Y-14362D01*
X-3833D01*
G01X-3248D02*
X-2858Y-14102D01*
X-2534Y-13669D01*
X-2404Y-13150D01*
X-2534Y-12630D01*
X-2858Y-12197D01*
X-3443Y-11937D01*
X-4028Y-12024D01*
X-4613Y-12370D01*
G01X-90424Y109394D02*
X-89835Y110178D01*
X-89149Y110570D01*
X-88364Y110701D01*
X-87384Y110440D01*
X-86697Y109786D01*
X-86501Y109001D01*
X-86599Y108217D01*
X-86992Y107563D01*
X-88953Y106255D01*
X-89835Y105340D01*
X-90424Y104032D01*
X-90620Y102856D01*
X-86501D01*
G01X-80913D02*
X-80717Y104556D01*
X-80422Y105994D01*
X-80030Y107302D01*
X-79540Y108740D01*
X-78755Y110701D01*
X-82678D01*
G01X-72873Y102595D02*
X-73069Y102725D01*
Y102987D01*
X-72873Y103117D01*
X-72676Y102987D01*
Y102725D01*
X-72873Y102595D01*
G01X-65029Y102856D02*
Y110701D01*
X-66205Y109132D01*
G01Y102856D02*
X-63852D01*
G01X-57185Y110701D02*
X-57969Y110440D01*
X-58557Y109786D01*
X-58949Y109001D01*
X-59244Y107955D01*
X-59342Y106778D01*
X-59244Y105602D01*
X-58949Y104556D01*
X-58557Y103771D01*
X-57969Y103117D01*
X-57185Y102856D01*
X-56400Y103117D01*
X-55812Y103771D01*
X-55420Y104556D01*
X-55125Y105602D01*
X-55027Y106778D01*
X-55125Y107955D01*
X-55420Y109001D01*
X-55812Y109786D01*
X-56400Y110440D01*
X-57185Y110701D01*
G01X-90004Y117268D02*
X-89415Y118052D01*
X-88729Y118444D01*
X-87944Y118575D01*
X-86964Y118314D01*
X-86277Y117660D01*
X-86081Y116875D01*
X-86179Y116091D01*
X-86572Y115437D01*
X-88533Y114129D01*
X-89415Y113214D01*
X-90004Y111906D01*
X-90200Y110730D01*
X-86081D01*
G01X-81963Y111645D02*
X-81277Y110991D01*
X-80493Y110730D01*
X-79708Y110991D01*
X-79022Y111776D01*
X-78532Y112953D01*
X-78335Y114129D01*
Y115568D01*
X-78532Y116744D01*
X-79022Y117790D01*
X-79610Y118314D01*
X-80297Y118575D01*
X-81081Y118314D01*
X-81669Y117790D01*
X-82061Y117006D01*
X-82258Y115960D01*
X-82061Y115045D01*
X-81571Y114129D01*
X-80983Y113606D01*
X-80297Y113476D01*
X-79512Y113737D01*
X-78924Y114391D01*
X-78335Y115568D01*
G01X-72453Y110469D02*
X-72649Y110599D01*
Y110861D01*
X-72453Y110991D01*
X-72256Y110861D01*
Y110599D01*
X-72453Y110469D01*
G01X-64609Y110730D02*
Y118575D01*
X-65785Y117006D01*
G01Y110730D02*
X-63432D01*
G01X-56765Y118575D02*
X-57549Y118314D01*
X-58137Y117660D01*
X-58529Y116875D01*
X-58824Y115829D01*
X-58922Y114652D01*
X-58824Y113476D01*
X-58529Y112430D01*
X-58137Y111645D01*
X-57549Y110991D01*
X-56765Y110730D01*
X-55980Y110991D01*
X-55392Y111645D01*
X-55000Y112430D01*
X-54705Y113476D01*
X-54607Y114652D01*
X-54705Y115829D01*
X-55000Y116875D01*
X-55392Y117660D01*
X-55980Y118314D01*
X-56765Y118575D01*
G01X-92698Y218499D02*
X-92109Y217846D01*
X-91423Y217454D01*
X-90541Y217323D01*
X-89658Y217584D01*
X-88972Y218107D01*
X-88481Y219023D01*
X-88383Y220069D01*
X-88579Y221115D01*
X-89070Y221769D01*
X-89756Y222291D01*
X-90442Y222422D01*
X-91129Y222291D01*
X-92011Y221769D01*
X-91717Y225168D01*
X-89070D01*
G01X-84560Y220592D02*
X-83873Y221507D01*
X-83285Y222030D01*
X-82500Y222291D01*
X-81814Y222030D01*
X-81324Y221507D01*
X-80932Y220722D01*
X-80833Y219807D01*
X-80932Y219023D01*
X-81324Y218238D01*
X-81912Y217584D01*
X-82598Y217323D01*
X-83383Y217584D01*
X-84069Y218369D01*
X-84461Y219546D01*
X-84560Y220853D01*
X-84363Y222553D01*
X-84069Y223468D01*
X-83579Y224383D01*
X-82893Y225037D01*
X-82206Y225168D01*
X-81520Y224907D01*
X-81030Y224253D01*
G01X-74853Y217062D02*
X-75049Y217192D01*
Y217454D01*
X-74853Y217584D01*
X-74656Y217454D01*
Y217192D01*
X-74853Y217062D01*
G01X-68872Y223861D02*
X-68283Y224645D01*
X-67597Y225037D01*
X-66812Y225168D01*
X-65832Y224907D01*
X-65145Y224253D01*
X-64949Y223468D01*
X-65047Y222684D01*
X-65440Y222030D01*
X-67401Y220722D01*
X-68283Y219807D01*
X-68872Y218499D01*
X-69068Y217323D01*
X-64949D01*
G01X-59165Y225168D02*
X-59949Y224907D01*
X-60537Y224253D01*
X-60929Y223468D01*
X-61224Y222422D01*
X-61322Y221245D01*
X-61224Y220069D01*
X-60929Y219023D01*
X-60537Y218238D01*
X-59949Y217584D01*
X-59165Y217323D01*
X-58380Y217584D01*
X-57792Y218238D01*
X-57400Y219023D01*
X-57105Y220069D01*
X-57007Y221245D01*
X-57105Y222422D01*
X-57400Y223468D01*
X-57792Y224253D01*
X-58380Y224907D01*
X-59165Y225168D01*
G01X-91564Y232279D02*
X-90975Y231626D01*
X-90289Y231234D01*
X-89407Y231103D01*
X-88524Y231364D01*
X-87838Y231887D01*
X-87347Y232803D01*
X-87249Y233849D01*
X-87445Y234895D01*
X-87936Y235549D01*
X-88622Y236071D01*
X-89308Y236202D01*
X-89995Y236071D01*
X-90877Y235549D01*
X-90583Y238948D01*
X-87936D01*
G01X-83229Y232018D02*
X-82543Y231364D01*
X-81759Y231103D01*
X-80974Y231364D01*
X-80288Y232149D01*
X-79798Y233326D01*
X-79601Y234502D01*
Y235941D01*
X-79798Y237117D01*
X-80288Y238163D01*
X-80876Y238687D01*
X-81563Y238948D01*
X-82347Y238687D01*
X-82935Y238163D01*
X-83327Y237379D01*
X-83524Y236333D01*
X-83327Y235418D01*
X-82837Y234502D01*
X-82249Y233979D01*
X-81563Y233849D01*
X-80778Y234110D01*
X-80190Y234764D01*
X-79601Y235941D01*
G01X-73719Y230842D02*
X-73915Y230972D01*
Y231234D01*
X-73719Y231364D01*
X-73522Y231234D01*
Y230972D01*
X-73719Y230842D01*
G01X-66071Y231103D02*
X-65875Y232803D01*
X-65580Y234241D01*
X-65188Y235549D01*
X-64698Y236987D01*
X-63913Y238948D01*
X-67836D01*
G01X-58031D02*
X-58815Y238687D01*
X-59403Y238033D01*
X-59795Y237248D01*
X-60090Y236202D01*
X-60188Y235025D01*
X-60090Y233849D01*
X-59795Y232803D01*
X-59403Y232018D01*
X-58815Y231364D01*
X-58031Y231103D01*
X-57246Y231364D01*
X-56658Y232018D01*
X-56266Y232803D01*
X-55971Y233849D01*
X-55873Y235025D01*
X-55971Y236202D01*
X-56266Y237248D01*
X-56658Y238033D01*
X-57246Y238687D01*
X-58031Y238948D01*
G01X-90324Y345670D02*
X-89637Y345801D01*
X-88853Y346193D01*
X-88362Y346846D01*
X-88166Y347762D01*
X-88362Y348677D01*
X-88951Y349462D01*
X-89833Y349854D01*
X-90814D01*
X-91402Y350116D01*
X-91892Y350769D01*
X-92088Y351684D01*
X-91794Y352600D01*
X-91108Y353254D01*
X-90324Y353515D01*
X-89539Y353254D01*
X-88853Y352600D01*
X-88559Y351684D01*
X-88755Y350769D01*
X-89245Y350116D01*
X-89833Y349854D01*
X-90814D01*
X-91696Y349462D01*
X-92285Y348677D01*
X-92481Y347762D01*
X-92285Y346846D01*
X-91794Y346193D01*
X-91010Y345801D01*
X-90324Y345670D01*
G01X-82480D02*
X-81793Y345801D01*
X-81009Y346193D01*
X-80518Y346846D01*
X-80322Y347762D01*
X-80518Y348677D01*
X-81107Y349462D01*
X-81989Y349854D01*
X-82970D01*
X-83558Y350116D01*
X-84048Y350769D01*
X-84244Y351684D01*
X-83950Y352600D01*
X-83264Y353254D01*
X-82480Y353515D01*
X-81695Y353254D01*
X-81009Y352600D01*
X-80715Y351684D01*
X-80911Y350769D01*
X-81401Y350116D01*
X-81989Y349854D01*
X-82970D01*
X-83852Y349462D01*
X-84441Y348677D01*
X-84637Y347762D01*
X-84441Y346846D01*
X-83950Y346193D01*
X-83166Y345801D01*
X-82480Y345670D01*
G01X-74636Y345409D02*
X-74832Y345539D01*
Y345801D01*
X-74636Y345931D01*
X-74439Y345801D01*
Y345539D01*
X-74636Y345409D01*
G01X-66792Y345670D02*
X-66105Y345801D01*
X-65321Y346193D01*
X-64830Y346846D01*
X-64634Y347762D01*
X-64830Y348677D01*
X-65419Y349462D01*
X-66301Y349854D01*
X-67282D01*
X-67870Y350116D01*
X-68360Y350769D01*
X-68556Y351684D01*
X-68262Y352600D01*
X-67576Y353254D01*
X-66792Y353515D01*
X-66007Y353254D01*
X-65321Y352600D01*
X-65027Y351684D01*
X-65223Y350769D01*
X-65713Y350116D01*
X-66301Y349854D01*
X-67282D01*
X-68164Y349462D01*
X-68753Y348677D01*
X-68949Y347762D01*
X-68753Y346846D01*
X-68262Y346193D01*
X-67478Y345801D01*
X-66792Y345670D01*
G01X-58948Y353515D02*
X-59732Y353254D01*
X-60320Y352600D01*
X-60712Y351815D01*
X-61007Y350769D01*
X-61105Y349592D01*
X-61007Y348416D01*
X-60712Y347370D01*
X-60320Y346585D01*
X-59732Y345931D01*
X-58948Y345670D01*
X-58163Y345931D01*
X-57575Y346585D01*
X-57183Y347370D01*
X-56888Y348416D01*
X-56790Y349592D01*
X-56888Y350769D01*
X-57183Y351815D01*
X-57575Y352600D01*
X-58163Y353254D01*
X-58948Y353515D01*
G01X-90123Y337796D02*
X-89436Y337927D01*
X-88652Y338319D01*
X-88161Y338972D01*
X-87965Y339888D01*
X-88161Y340803D01*
X-88750Y341588D01*
X-89632Y341980D01*
X-90613D01*
X-91201Y342242D01*
X-91691Y342895D01*
X-91887Y343810D01*
X-91593Y344726D01*
X-90907Y345380D01*
X-90123Y345641D01*
X-89338Y345380D01*
X-88652Y344726D01*
X-88358Y343810D01*
X-88554Y342895D01*
X-89044Y342242D01*
X-89632Y341980D01*
X-90613D01*
X-91495Y341588D01*
X-92084Y340803D01*
X-92280Y339888D01*
X-92084Y338972D01*
X-91593Y338319D01*
X-90809Y337927D01*
X-90123Y337796D01*
G01X-84142Y341065D02*
X-83455Y341980D01*
X-82867Y342503D01*
X-82082Y342764D01*
X-81396Y342503D01*
X-80906Y341980D01*
X-80514Y341195D01*
X-80415Y340280D01*
X-80514Y339496D01*
X-80906Y338711D01*
X-81494Y338057D01*
X-82180Y337796D01*
X-82965Y338057D01*
X-83651Y338842D01*
X-84043Y340019D01*
X-84142Y341326D01*
X-83945Y343026D01*
X-83651Y343941D01*
X-83161Y344856D01*
X-82475Y345510D01*
X-81788Y345641D01*
X-81102Y345380D01*
X-80612Y344726D01*
G01X-74435Y337535D02*
X-74631Y337665D01*
Y337927D01*
X-74435Y338057D01*
X-74238Y337927D01*
Y337665D01*
X-74435Y337535D01*
G01X-66591Y337796D02*
X-65904Y337927D01*
X-65120Y338319D01*
X-64629Y338972D01*
X-64433Y339888D01*
X-64629Y340803D01*
X-65218Y341588D01*
X-66100Y341980D01*
X-67081D01*
X-67669Y342242D01*
X-68159Y342895D01*
X-68355Y343810D01*
X-68061Y344726D01*
X-67375Y345380D01*
X-66591Y345641D01*
X-65806Y345380D01*
X-65120Y344726D01*
X-64826Y343810D01*
X-65022Y342895D01*
X-65512Y342242D01*
X-66100Y341980D01*
X-67081D01*
X-67963Y341588D01*
X-68552Y340803D01*
X-68748Y339888D01*
X-68552Y338972D01*
X-68061Y338319D01*
X-67277Y337927D01*
X-66591Y337796D01*
G01X-58747Y345641D02*
X-59531Y345380D01*
X-60119Y344726D01*
X-60511Y343941D01*
X-60806Y342895D01*
X-60904Y341718D01*
X-60806Y340542D01*
X-60511Y339496D01*
X-60119Y338711D01*
X-59531Y338057D01*
X-58747Y337796D01*
X-57962Y338057D01*
X-57374Y338711D01*
X-56982Y339496D01*
X-56687Y340542D01*
X-56589Y341718D01*
X-56687Y342895D01*
X-56982Y343941D01*
X-57374Y344726D01*
X-57962Y345380D01*
X-58747Y345641D01*
G01X-95833Y466142D02*
Y473987D01*
X-97009Y472418D01*
G01Y466142D02*
X-94656D01*
G01X-87989D02*
Y473987D01*
X-89165Y472418D01*
G01Y466142D02*
X-86812D01*
G01X-81811Y467057D02*
X-81125Y466403D01*
X-80341Y466142D01*
X-79556Y466403D01*
X-78870Y467188D01*
X-78380Y468365D01*
X-78183Y469541D01*
Y470980D01*
X-78380Y472156D01*
X-78870Y473202D01*
X-79458Y473726D01*
X-80145Y473987D01*
X-80929Y473726D01*
X-81517Y473202D01*
X-81909Y472418D01*
X-82106Y471372D01*
X-81909Y470457D01*
X-81419Y469541D01*
X-80831Y469018D01*
X-80145Y468888D01*
X-79360Y469149D01*
X-78772Y469803D01*
X-78183Y470980D01*
G01X-72301Y465881D02*
X-72497Y466011D01*
Y466273D01*
X-72301Y466403D01*
X-72104Y466273D01*
Y466011D01*
X-72301Y465881D01*
G01X-63280Y466142D02*
Y473987D01*
X-66908Y468365D01*
X-62005D01*
G01X-56613Y473987D02*
X-57397Y473726D01*
X-57985Y473072D01*
X-58377Y472287D01*
X-58672Y471241D01*
X-58770Y470064D01*
X-58672Y468888D01*
X-58377Y467842D01*
X-57985Y467057D01*
X-57397Y466403D01*
X-56613Y466142D01*
X-55828Y466403D01*
X-55240Y467057D01*
X-54848Y467842D01*
X-54553Y468888D01*
X-54455Y470064D01*
X-54553Y471241D01*
X-54848Y472287D01*
X-55240Y473072D01*
X-55828Y473726D01*
X-56613Y473987D01*
G01X-95411Y452363D02*
Y460208D01*
X-96587Y458639D01*
G01Y452363D02*
X-94234D01*
G01X-87567D02*
Y460208D01*
X-88743Y458639D01*
G01Y452363D02*
X-86390D01*
G01X-81880Y453539D02*
X-81291Y452886D01*
X-80605Y452494D01*
X-79723Y452363D01*
X-78840Y452624D01*
X-78154Y453147D01*
X-77663Y454063D01*
X-77565Y455109D01*
X-77761Y456155D01*
X-78252Y456809D01*
X-78938Y457331D01*
X-79624Y457462D01*
X-80311Y457331D01*
X-81193Y456809D01*
X-80899Y460208D01*
X-78252D01*
G01X-71879Y452102D02*
X-72075Y452232D01*
Y452494D01*
X-71879Y452624D01*
X-71682Y452494D01*
Y452232D01*
X-71879Y452102D01*
G01X-65701Y453278D02*
X-65015Y452624D01*
X-64231Y452363D01*
X-63446Y452624D01*
X-62760Y453409D01*
X-62270Y454586D01*
X-62073Y455762D01*
Y457201D01*
X-62270Y458377D01*
X-62760Y459423D01*
X-63348Y459947D01*
X-64035Y460208D01*
X-64819Y459947D01*
X-65407Y459423D01*
X-65799Y458639D01*
X-65996Y457593D01*
X-65799Y456678D01*
X-65309Y455762D01*
X-64721Y455239D01*
X-64035Y455109D01*
X-63250Y455370D01*
X-62662Y456024D01*
X-62073Y457201D01*
G01X-56191Y460208D02*
X-56975Y459947D01*
X-57563Y459293D01*
X-57955Y458508D01*
X-58250Y457462D01*
X-58348Y456285D01*
X-58250Y455109D01*
X-57955Y454063D01*
X-57563Y453278D01*
X-56975Y452624D01*
X-56191Y452363D01*
X-55406Y452624D01*
X-54818Y453278D01*
X-54426Y454063D01*
X-54131Y455109D01*
X-54033Y456285D01*
X-54131Y457462D01*
X-54426Y458508D01*
X-54818Y459293D01*
X-55406Y459947D01*
X-56191Y460208D01*
G01X-93876Y581109D02*
Y588954D01*
X-95052Y587385D01*
G01Y581109D02*
X-92699D01*
G01X-84855D02*
Y588954D01*
X-88483Y583332D01*
X-83580D01*
G01X-78188Y581109D02*
X-77501Y581240D01*
X-76717Y581632D01*
X-76226Y582285D01*
X-76030Y583201D01*
X-76226Y584116D01*
X-76815Y584901D01*
X-77697Y585293D01*
X-78678D01*
X-79266Y585555D01*
X-79756Y586208D01*
X-79952Y587123D01*
X-79658Y588039D01*
X-78972Y588693D01*
X-78188Y588954D01*
X-77403Y588693D01*
X-76717Y588039D01*
X-76423Y587123D01*
X-76619Y586208D01*
X-77109Y585555D01*
X-77697Y585293D01*
X-78678D01*
X-79560Y584901D01*
X-80149Y584116D01*
X-80345Y583201D01*
X-80149Y582285D01*
X-79658Y581632D01*
X-78874Y581240D01*
X-78188Y581109D01*
G01X-70344Y580848D02*
X-70540Y580978D01*
Y581240D01*
X-70344Y581370D01*
X-70147Y581240D01*
Y580978D01*
X-70344Y580848D01*
G01X-64657Y582285D02*
X-64068Y581632D01*
X-63382Y581240D01*
X-62500Y581109D01*
X-61617Y581370D01*
X-60931Y581893D01*
X-60440Y582809D01*
X-60342Y583855D01*
X-60538Y584901D01*
X-61029Y585555D01*
X-61715Y586077D01*
X-62401Y586208D01*
X-63088Y586077D01*
X-63970Y585555D01*
X-63676Y588954D01*
X-61029D01*
G01X-54656D02*
X-55440Y588693D01*
X-56028Y588039D01*
X-56420Y587254D01*
X-56715Y586208D01*
X-56813Y585031D01*
X-56715Y583855D01*
X-56420Y582809D01*
X-56028Y582024D01*
X-55440Y581370D01*
X-54656Y581109D01*
X-53871Y581370D01*
X-53283Y582024D01*
X-52891Y582809D01*
X-52596Y583855D01*
X-52498Y585031D01*
X-52596Y586208D01*
X-52891Y587254D01*
X-53283Y588039D01*
X-53871Y588693D01*
X-54656Y588954D01*
G01X-93937Y573235D02*
Y581080D01*
X-95113Y579511D01*
G01Y573235D02*
X-92760D01*
G01X-84916D02*
Y581080D01*
X-88544Y575458D01*
X-83641D01*
G01X-80112Y576504D02*
X-79425Y577419D01*
X-78837Y577942D01*
X-78052Y578203D01*
X-77366Y577942D01*
X-76876Y577419D01*
X-76484Y576634D01*
X-76385Y575719D01*
X-76484Y574935D01*
X-76876Y574150D01*
X-77464Y573496D01*
X-78150Y573235D01*
X-78935Y573496D01*
X-79621Y574281D01*
X-80013Y575458D01*
X-80112Y576765D01*
X-79915Y578465D01*
X-79621Y579380D01*
X-79131Y580295D01*
X-78445Y580949D01*
X-77758Y581080D01*
X-77072Y580819D01*
X-76582Y580165D01*
G01X-70405Y572974D02*
X-70601Y573104D01*
Y573366D01*
X-70405Y573496D01*
X-70208Y573366D01*
Y573104D01*
X-70405Y572974D01*
G01X-64718Y574411D02*
X-64129Y573758D01*
X-63443Y573366D01*
X-62561Y573235D01*
X-61678Y573496D01*
X-60992Y574019D01*
X-60501Y574935D01*
X-60403Y575981D01*
X-60599Y577027D01*
X-61090Y577681D01*
X-61776Y578203D01*
X-62462Y578334D01*
X-63149Y578203D01*
X-64031Y577681D01*
X-63737Y581080D01*
X-61090D01*
G01X-54717D02*
X-55501Y580819D01*
X-56089Y580165D01*
X-56481Y579380D01*
X-56776Y578334D01*
X-56874Y577157D01*
X-56776Y575981D01*
X-56481Y574935D01*
X-56089Y574150D01*
X-55501Y573496D01*
X-54717Y573235D01*
X-53932Y573496D01*
X-53344Y574150D01*
X-52952Y574935D01*
X-52657Y575981D01*
X-52559Y577157D01*
X-52657Y578334D01*
X-52952Y579380D01*
X-53344Y580165D01*
X-53932Y580819D01*
X-54717Y581080D01*
G01X-89997Y687402D02*
Y695247D01*
X-91173Y693678D01*
G01Y687402D02*
X-88820D01*
G01X-82349D02*
X-82153Y689102D01*
X-81858Y690540D01*
X-81466Y691848D01*
X-80976Y693286D01*
X-80191Y695247D01*
X-84114D01*
G01X-76466Y688578D02*
X-75877Y687925D01*
X-75191Y687533D01*
X-74309Y687402D01*
X-73426Y687663D01*
X-72740Y688186D01*
X-72249Y689102D01*
X-72151Y690148D01*
X-72347Y691194D01*
X-72838Y691848D01*
X-73524Y692370D01*
X-74210Y692501D01*
X-74897Y692370D01*
X-75779Y691848D01*
X-75485Y695247D01*
X-72838D01*
G01X-66465Y687141D02*
X-66661Y687271D01*
Y687533D01*
X-66465Y687663D01*
X-66268Y687533D01*
Y687271D01*
X-66465Y687141D01*
G01X-60484Y690671D02*
X-59797Y691586D01*
X-59209Y692109D01*
X-58424Y692370D01*
X-57738Y692109D01*
X-57248Y691586D01*
X-56856Y690801D01*
X-56757Y689886D01*
X-56856Y689102D01*
X-57248Y688317D01*
X-57836Y687663D01*
X-58522Y687402D01*
X-59307Y687663D01*
X-59993Y688448D01*
X-60385Y689625D01*
X-60484Y690932D01*
X-60287Y692632D01*
X-59993Y693547D01*
X-59503Y694462D01*
X-58817Y695116D01*
X-58130Y695247D01*
X-57444Y694986D01*
X-56954Y694332D01*
G01X-50777Y695247D02*
X-51561Y694986D01*
X-52149Y694332D01*
X-52541Y693547D01*
X-52836Y692501D01*
X-52934Y691324D01*
X-52836Y690148D01*
X-52541Y689102D01*
X-52149Y688317D01*
X-51561Y687663D01*
X-50777Y687402D01*
X-49992Y687663D01*
X-49404Y688317D01*
X-49012Y689102D01*
X-48717Y690148D01*
X-48619Y691324D01*
X-48717Y692501D01*
X-49012Y693547D01*
X-49404Y694332D01*
X-49992Y694986D01*
X-50777Y695247D01*
G01X-68086Y-432273D02*
X-67643Y-431683D01*
X-67126Y-431387D01*
X-66536Y-431289D01*
X-65798Y-431486D01*
X-65281Y-431978D01*
X-65133Y-432569D01*
X-65207Y-433159D01*
X-65502Y-433651D01*
X-66979Y-434636D01*
X-67643Y-435325D01*
X-68086Y-436309D01*
X-68234Y-437195D01*
X-65133D01*
G01X-24179Y741991D02*
X-23918Y741207D01*
X-23264Y740619D01*
X-22479Y740227D01*
X-21433Y739932D01*
X-20256Y739834D01*
X-19080Y739932D01*
X-18034Y740227D01*
X-17249Y740619D01*
X-16595Y741207D01*
X-16334Y741991D01*
X-16595Y742776D01*
X-17249Y743364D01*
X-18034Y743756D01*
X-19080Y744051D01*
X-20256Y744149D01*
X-21433Y744051D01*
X-22479Y743756D01*
X-23264Y743364D01*
X-23918Y742776D01*
X-24179Y741991D01*
G01X-16073Y749835D02*
X-16203Y749639D01*
X-16465D01*
X-16595Y749835D01*
X-16465Y750032D01*
X-16203D01*
X-16073Y749835D01*
G01X-24179Y757679D02*
X-23918Y756895D01*
X-23264Y756307D01*
X-22479Y755915D01*
X-21433Y755620D01*
X-20256Y755522D01*
X-19080Y755620D01*
X-18034Y755915D01*
X-17249Y756307D01*
X-16595Y756895D01*
X-16334Y757679D01*
X-16595Y758464D01*
X-17249Y759052D01*
X-18034Y759444D01*
X-19080Y759739D01*
X-20256Y759837D01*
X-21433Y759739D01*
X-22479Y759444D01*
X-23264Y759052D01*
X-23918Y758464D01*
X-24179Y757679D01*
G01Y765523D02*
X-23918Y764739D01*
X-23264Y764151D01*
X-22479Y763759D01*
X-21433Y763464D01*
X-20256Y763366D01*
X-19080Y763464D01*
X-18034Y763759D01*
X-17249Y764151D01*
X-16595Y764739D01*
X-16334Y765523D01*
X-16595Y766308D01*
X-17249Y766896D01*
X-18034Y767288D01*
X-19080Y767583D01*
X-20256Y767681D01*
X-21433Y767583D01*
X-22479Y767288D01*
X-23264Y766896D01*
X-23918Y766308D01*
X-24179Y765523D01*
G01X-68086Y928357D02*
X-67643Y928947D01*
X-67126Y929243D01*
X-66536Y929341D01*
X-65798Y929144D01*
X-65281Y928652D01*
X-65133Y928061D01*
X-65207Y927471D01*
X-65502Y926979D01*
X-66979Y925994D01*
X-67643Y925305D01*
X-68086Y924321D01*
X-68234Y923435D01*
X-65133D01*
G01X2761Y739253D02*
X3414Y739842D01*
X3806Y740528D01*
X3937Y741410D01*
X3676Y742293D01*
X3153Y742979D01*
X2237Y743470D01*
X1191Y743568D01*
X145Y743372D01*
X-509Y742881D01*
X-1031Y742195D01*
X-1162Y741509D01*
X-1031Y740822D01*
X-509Y739940D01*
X-3908Y740234D01*
Y742881D01*
G01X4198Y749254D02*
X4068Y749058D01*
X3806D01*
X3676Y749254D01*
X3806Y749451D01*
X4068D01*
X4198Y749254D01*
G01X3937Y757098D02*
X-3908D01*
X-2339Y755922D01*
G01X3937D02*
Y758275D01*
G01X2761Y762785D02*
X3414Y763374D01*
X3806Y764060D01*
X3937Y764942D01*
X3676Y765825D01*
X3153Y766511D01*
X2237Y767002D01*
X1191Y767100D01*
X145Y766904D01*
X-509Y766413D01*
X-1031Y765727D01*
X-1162Y765041D01*
X-1031Y764354D01*
X-509Y763472D01*
X-3908Y763766D01*
Y766413D01*
G01X104921Y-436014D02*
X105363Y-436703D01*
X105954Y-437097D01*
X106618Y-437195D01*
X107209Y-437097D01*
X107799Y-436605D01*
X108168Y-436014D01*
X108242Y-435423D01*
X108095Y-434734D01*
X107578Y-434242D01*
X107061Y-434045D01*
X106397D01*
G01X107061D02*
X107504Y-433750D01*
X107873Y-433258D01*
X108021Y-432667D01*
X107873Y-432076D01*
X107504Y-431584D01*
X106840Y-431289D01*
X106175Y-431387D01*
X105511Y-431781D01*
G01X104921Y924616D02*
X105363Y923927D01*
X105954Y923533D01*
X106618Y923435D01*
X107209Y923533D01*
X107799Y924025D01*
X108168Y924616D01*
X108242Y925207D01*
X108095Y925896D01*
X107578Y926388D01*
X107061Y926585D01*
X106397D01*
G01X107061D02*
X107504Y926880D01*
X107873Y927372D01*
X108021Y927963D01*
X107873Y928554D01*
X107504Y929046D01*
X106840Y929341D01*
X106175Y929243D01*
X105511Y928849D01*
G01X188086Y50491D02*
Y25491D01*
G01X180841Y50491D02*
X195331D01*
G01X183286Y152864D02*
Y177864D01*
G01X190531Y152864D02*
X176041D01*
G01X190729Y303436D02*
Y278436D01*
G01X183484Y303436D02*
X197974D01*
G01X183286Y387903D02*
Y412903D01*
G01X190531Y387903D02*
X176041D01*
G01X190729Y538476D02*
Y513476D01*
G01X183484Y538476D02*
X197974D01*
G01X183286Y622943D02*
Y647943D01*
G01X190531Y622943D02*
X176041D01*
G01X280659Y-437195D02*
Y-431289D01*
X277928Y-435522D01*
X281619D01*
G01X280659Y923435D02*
Y929341D01*
X277928Y925108D01*
X281619D01*
G01X385827Y741397D02*
X377982D01*
X379551Y740221D01*
G01X385827D02*
Y742574D01*
G01X377982Y749241D02*
X378243Y748457D01*
X378897Y747869D01*
X379682Y747477D01*
X380728Y747182D01*
X381905Y747084D01*
X383081Y747182D01*
X384127Y747477D01*
X384912Y747869D01*
X385566Y748457D01*
X385827Y749241D01*
X385566Y750026D01*
X384912Y750614D01*
X384127Y751006D01*
X383081Y751301D01*
X381905Y751399D01*
X380728Y751301D01*
X379682Y751006D01*
X378897Y750614D01*
X378243Y750026D01*
X377982Y749241D01*
G01X379289Y755222D02*
X378505Y755811D01*
X378113Y756497D01*
X377982Y757282D01*
X378243Y758262D01*
X378897Y758949D01*
X379682Y759145D01*
X380466Y759047D01*
X381120Y758654D01*
X382428Y756693D01*
X383343Y755811D01*
X384651Y755222D01*
X385827Y755026D01*
Y759145D01*
G01X386088Y764929D02*
X385958Y764733D01*
X385696D01*
X385566Y764929D01*
X385696Y765126D01*
X385958D01*
X386088Y764929D01*
G01X385827Y772773D02*
X377982D01*
X379551Y771597D01*
G01X385827D02*
Y773950D01*
G01X384651Y778460D02*
X385304Y779049D01*
X385696Y779735D01*
X385827Y780617D01*
X385566Y781500D01*
X385043Y782186D01*
X384127Y782677D01*
X383081Y782775D01*
X382035Y782579D01*
X381381Y782088D01*
X380859Y781402D01*
X380728Y780716D01*
X380859Y780029D01*
X381381Y779147D01*
X377982Y779441D01*
Y782088D01*
G01X377953Y741410D02*
X370108D01*
X371677Y740234D01*
G01X377953D02*
Y742587D01*
G01X370108Y749254D02*
X370369Y748470D01*
X371023Y747882D01*
X371808Y747490D01*
X372854Y747195D01*
X374031Y747097D01*
X375207Y747195D01*
X376253Y747490D01*
X377038Y747882D01*
X377692Y748470D01*
X377953Y749254D01*
X377692Y750039D01*
X377038Y750627D01*
X376253Y751019D01*
X375207Y751314D01*
X374031Y751412D01*
X372854Y751314D01*
X371808Y751019D01*
X371023Y750627D01*
X370369Y750039D01*
X370108Y749254D01*
G01Y757098D02*
X370369Y756314D01*
X371023Y755726D01*
X371808Y755334D01*
X372854Y755039D01*
X374031Y754941D01*
X375207Y755039D01*
X376253Y755334D01*
X377038Y755726D01*
X377692Y756314D01*
X377953Y757098D01*
X377692Y757883D01*
X377038Y758471D01*
X376253Y758863D01*
X375207Y759158D01*
X374031Y759256D01*
X372854Y759158D01*
X371808Y758863D01*
X371023Y758471D01*
X370369Y757883D01*
X370108Y757098D01*
G01X378214Y764942D02*
X378084Y764746D01*
X377822D01*
X377692Y764942D01*
X377822Y765139D01*
X378084D01*
X378214Y764942D01*
G01X377953Y772786D02*
X370108D01*
X371677Y771610D01*
G01X377953D02*
Y773963D01*
G01X376777Y778473D02*
X377430Y779062D01*
X377822Y779748D01*
X377953Y780630D01*
X377692Y781513D01*
X377169Y782199D01*
X376253Y782690D01*
X375207Y782788D01*
X374161Y782592D01*
X373507Y782101D01*
X372985Y781415D01*
X372854Y780729D01*
X372985Y780042D01*
X373507Y779160D01*
X370108Y779454D01*
Y782101D01*
G01X451378Y-436309D02*
X451820Y-436801D01*
X452337Y-437097D01*
X453001Y-437195D01*
X453666Y-436998D01*
X454183Y-436605D01*
X454552Y-435915D01*
X454625Y-435128D01*
X454478Y-434341D01*
X454109Y-433848D01*
X453592Y-433455D01*
X453075Y-433356D01*
X452559Y-433455D01*
X451894Y-433848D01*
X452116Y-431289D01*
X454109D01*
G01X451378Y924321D02*
X451820Y923829D01*
X452337Y923533D01*
X453001Y923435D01*
X453666Y923632D01*
X454183Y924025D01*
X454552Y924715D01*
X454625Y925502D01*
X454478Y926289D01*
X454109Y926782D01*
X453592Y927175D01*
X453075Y927274D01*
X452559Y927175D01*
X451894Y926782D01*
X452116Y929341D01*
X454109D01*
G01X572619Y68396D02*
Y43396D01*
G01X565374Y68396D02*
X579864D01*
G01X565176Y152864D02*
Y177864D01*
G01X572421Y152864D02*
X557931D01*
G01X572619Y303436D02*
Y278436D01*
G01X565374Y303436D02*
X579864D01*
G01X565176Y387903D02*
Y412903D01*
G01X572421Y387903D02*
X557931D01*
G01X572619Y538476D02*
Y513476D01*
G01X565374Y538476D02*
X579864D01*
G01X565176Y622943D02*
Y647943D01*
G01X572421Y622943D02*
X557931D01*
G01X624827Y-434734D02*
X625344Y-434045D01*
X625787Y-433651D01*
X626377Y-433455D01*
X626894Y-433651D01*
X627263Y-434045D01*
X627558Y-434636D01*
X627632Y-435325D01*
X627558Y-435915D01*
X627263Y-436506D01*
X626820Y-436998D01*
X626303Y-437195D01*
X625713Y-436998D01*
X625196Y-436408D01*
X624901Y-435522D01*
X624827Y-434537D01*
X624975Y-433258D01*
X625196Y-432569D01*
X625565Y-431880D01*
X626082Y-431387D01*
X626599Y-431289D01*
X627115Y-431486D01*
X627484Y-431978D01*
G01X624827Y925896D02*
X625344Y926585D01*
X625787Y926979D01*
X626377Y927175D01*
X626894Y926979D01*
X627263Y926585D01*
X627558Y925994D01*
X627632Y925305D01*
X627558Y924715D01*
X627263Y924124D01*
X626820Y923632D01*
X626303Y923435D01*
X625713Y923632D01*
X625196Y924222D01*
X624901Y925108D01*
X624827Y926093D01*
X624975Y927372D01*
X625196Y928061D01*
X625565Y928750D01*
X626082Y929243D01*
X626599Y929341D01*
X627115Y929144D01*
X627484Y928652D01*
G01X772990Y729025D02*
X772206Y729614D01*
X771814Y730300D01*
X771683Y731085D01*
X771944Y732065D01*
X772598Y732752D01*
X773383Y732948D01*
X774167Y732850D01*
X774821Y732457D01*
X776129Y730496D01*
X777044Y729614D01*
X778352Y729025D01*
X779528Y728829D01*
Y732948D01*
G01X771683Y738732D02*
X771944Y737948D01*
X772598Y737360D01*
X773383Y736968D01*
X774429Y736673D01*
X775606Y736575D01*
X776782Y736673D01*
X777828Y736968D01*
X778613Y737360D01*
X779267Y737948D01*
X779528Y738732D01*
X779267Y739517D01*
X778613Y740105D01*
X777828Y740497D01*
X776782Y740792D01*
X775606Y740890D01*
X774429Y740792D01*
X773383Y740497D01*
X772598Y740105D01*
X771944Y739517D01*
X771683Y738732D01*
G01X772990Y744713D02*
X772206Y745302D01*
X771814Y745988D01*
X771683Y746773D01*
X771944Y747753D01*
X772598Y748440D01*
X773383Y748636D01*
X774167Y748538D01*
X774821Y748145D01*
X776129Y746184D01*
X777044Y745302D01*
X778352Y744713D01*
X779528Y744517D01*
Y748636D01*
G01X779789Y754420D02*
X779659Y754224D01*
X779397D01*
X779267Y754420D01*
X779397Y754617D01*
X779659D01*
X779789Y754420D01*
G01X779528Y762264D02*
X771683D01*
X773252Y761088D01*
G01X779528D02*
Y763441D01*
G01X778352Y767951D02*
X779005Y768540D01*
X779397Y769226D01*
X779528Y770108D01*
X779267Y770991D01*
X778744Y771677D01*
X777828Y772168D01*
X776782Y772266D01*
X775736Y772070D01*
X775082Y771579D01*
X774560Y770893D01*
X774429Y770207D01*
X774560Y769520D01*
X775082Y768638D01*
X771683Y768932D01*
Y771579D01*
G01X759843Y731291D02*
X751998D01*
X753567Y730115D01*
G01X759843D02*
Y732468D01*
G01X758928Y737469D02*
X759582Y738155D01*
X759843Y738939D01*
X759582Y739724D01*
X758797Y740410D01*
X757620Y740900D01*
X756444Y741097D01*
X755005D01*
X753829Y740900D01*
X752783Y740410D01*
X752259Y739822D01*
X751998Y739135D01*
X752259Y738351D01*
X752783Y737763D01*
X753567Y737371D01*
X754613Y737174D01*
X755528Y737371D01*
X756444Y737861D01*
X756967Y738449D01*
X757097Y739135D01*
X756836Y739920D01*
X756182Y740508D01*
X755005Y741097D01*
G01X759843Y746783D02*
X758143Y746979D01*
X756705Y747274D01*
X755397Y747666D01*
X753959Y748156D01*
X751998Y748941D01*
Y745018D01*
G01X760104Y754823D02*
X759974Y754627D01*
X759712D01*
X759582Y754823D01*
X759712Y755020D01*
X759974D01*
X760104Y754823D01*
G01X759843Y762667D02*
X751998D01*
X753567Y761491D01*
G01X759843D02*
Y763844D01*
G01X758667Y768354D02*
X759320Y768943D01*
X759712Y769629D01*
X759843Y770511D01*
X759582Y771394D01*
X759059Y772080D01*
X758143Y772571D01*
X757097Y772669D01*
X756051Y772473D01*
X755397Y771982D01*
X754875Y771296D01*
X754744Y770610D01*
X754875Y769923D01*
X755397Y769041D01*
X751998Y769335D01*
Y771982D01*
G01X799311Y-437195D02*
X799458Y-435915D01*
X799680Y-434833D01*
X799975Y-433848D01*
X800344Y-432766D01*
X800935Y-431289D01*
X797982D01*
G01X834831Y-322812D02*
X833331Y-321812D01*
X831581Y-321145D01*
X829581D01*
X827331Y-322145D01*
X825581Y-323812D01*
X824331Y-325812D01*
X823331Y-329145D01*
X823081Y-332145D01*
X823581Y-335145D01*
X824331Y-337145D01*
X825831Y-339145D01*
X827581Y-340478D01*
X829331Y-341145D01*
X831081D01*
X832831Y-340478D01*
X834331Y-339479D01*
X835581Y-338146D01*
G01X845831Y-341145D02*
Y-327812D01*
G01Y-330478D02*
X847081Y-329145D01*
X848331Y-328145D01*
X850081Y-327812D01*
X851331Y-328145D01*
X852831Y-329145D01*
G01X865581Y-332145D02*
X873581D01*
X872831Y-329812D01*
X871581Y-328479D01*
X869831Y-327812D01*
X868081Y-328145D01*
X866581Y-329145D01*
X865581Y-331479D01*
X865081Y-333479D01*
Y-335478D01*
X865581Y-337479D01*
X866831Y-339479D01*
X868331Y-340812D01*
X870081Y-341145D01*
X871831Y-340478D01*
X873581Y-338479D01*
G01X893831Y-341145D02*
Y-327812D01*
G01Y-330145D02*
X892831Y-328812D01*
X891331Y-328145D01*
X889581Y-327812D01*
X887831Y-328479D01*
X886331Y-329812D01*
X885331Y-331812D01*
X884831Y-334479D01*
X885331Y-337145D01*
X886331Y-339145D01*
X887831Y-340478D01*
X889581Y-341145D01*
X891331Y-340812D01*
X892831Y-339812D01*
X893831Y-338479D01*
G01X909331Y-321145D02*
Y-341145D01*
G01X905831Y-327812D02*
X912831D01*
G01X925581Y-332145D02*
X933581D01*
X932831Y-329812D01*
X931581Y-328479D01*
X929831Y-327812D01*
X928081Y-328145D01*
X926581Y-329145D01*
X925581Y-331479D01*
X925081Y-333479D01*
Y-335478D01*
X925581Y-337479D01*
X926831Y-339479D01*
X928331Y-340812D01*
X930081Y-341145D01*
X931831Y-340478D01*
X933581Y-338479D01*
G01X953831Y-321145D02*
Y-341145D01*
G01Y-338146D02*
X952831Y-339812D01*
X951331Y-340812D01*
X949581Y-341145D01*
X947581Y-340478D01*
X946081Y-338812D01*
X945081Y-336812D01*
X944831Y-334479D01*
X945081Y-332145D01*
X946081Y-330145D01*
X947581Y-328479D01*
X949581Y-327812D01*
X951331Y-328145D01*
X952581Y-328812D01*
X953831Y-330145D01*
G01X820380Y-272237D02*
X826630Y-292237D01*
X832880Y-272237D01*
G01X842880Y-283237D02*
X850880D01*
X850130Y-280904D01*
X848880Y-279571D01*
X847130Y-278904D01*
X845380Y-279237D01*
X843880Y-280237D01*
X842880Y-282571D01*
X842380Y-284571D01*
Y-286570D01*
X842880Y-288571D01*
X844130Y-290571D01*
X845630Y-291904D01*
X847380Y-292237D01*
X849130Y-291570D01*
X850880Y-289571D01*
G01X863130Y-292237D02*
Y-278904D01*
G01Y-281570D02*
X864380Y-280237D01*
X865630Y-279237D01*
X867380Y-278904D01*
X868630Y-279237D01*
X870130Y-280237D01*
G01X882880Y-289904D02*
X884130Y-291237D01*
X885880Y-292237D01*
X887380D01*
X888880Y-291570D01*
X889880Y-290571D01*
X890380Y-289238D01*
X890130Y-287237D01*
X889130Y-286237D01*
X884630Y-284237D01*
X883630Y-281903D01*
X884130Y-280237D01*
X885130Y-279237D01*
X886630Y-278904D01*
X888130Y-279237D01*
X889630Y-280237D01*
G01X906630Y-278904D02*
Y-292237D01*
G01Y-273571D02*
X906130Y-273237D01*
Y-272570D01*
X906630Y-272237D01*
X907130Y-272570D01*
Y-273237D01*
X906630Y-273571D01*
G01X926630Y-292237D02*
X925130Y-291904D01*
X923630Y-290571D01*
X922630Y-288237D01*
X922130Y-285571D01*
X922630Y-282904D01*
X923630Y-280570D01*
X925130Y-279237D01*
X926630Y-278904D01*
X928130Y-279237D01*
X929630Y-280570D01*
X930630Y-282904D01*
X930880Y-285571D01*
X930630Y-288237D01*
X929630Y-290571D01*
X928130Y-291904D01*
X926630Y-292237D01*
G01X942380D02*
Y-278904D01*
G01Y-282237D02*
X943380Y-280570D01*
X944880Y-279237D01*
X946880Y-278904D01*
X948630Y-279237D01*
X950130Y-280570D01*
X950880Y-282904D01*
Y-292237D01*
G01X832777Y-204011D02*
Y-179011D01*
X840967Y-199844D01*
X849157Y-179011D01*
Y-204011D01*
G01X866167D02*
X864277Y-203594D01*
X862387Y-201928D01*
X861127Y-199011D01*
X860497Y-195678D01*
X861127Y-192345D01*
X862387Y-189428D01*
X864277Y-187761D01*
X866167Y-187345D01*
X868057Y-187761D01*
X869947Y-189428D01*
X871207Y-192345D01*
X871522Y-195678D01*
X871207Y-199011D01*
X869947Y-201928D01*
X868057Y-203594D01*
X866167Y-204011D01*
G01X897037Y-179011D02*
Y-204011D01*
G01Y-200262D02*
X895777Y-202345D01*
X893887Y-203594D01*
X891682Y-204011D01*
X889162Y-203178D01*
X887272Y-201095D01*
X886012Y-198595D01*
X885697Y-195678D01*
X886012Y-192761D01*
X887272Y-190261D01*
X889162Y-188178D01*
X891682Y-187345D01*
X893887Y-187761D01*
X895462Y-188595D01*
X897037Y-190261D01*
G01X911842Y-192761D02*
X921922D01*
X920977Y-189844D01*
X919402Y-188178D01*
X917197Y-187345D01*
X914992Y-187761D01*
X913102Y-189011D01*
X911842Y-191928D01*
X911212Y-194428D01*
Y-196928D01*
X911842Y-199428D01*
X913417Y-201928D01*
X915307Y-203594D01*
X917512Y-204011D01*
X919717Y-203178D01*
X921922Y-200678D01*
G01X941767Y-204011D02*
Y-179011D01*
G01X824331Y-248224D02*
Y-228224D01*
X830331D01*
X832331Y-229224D01*
X833831Y-231557D01*
X834331Y-234224D01*
X833831Y-236891D01*
X832581Y-238891D01*
X830331Y-239891D01*
X824331D01*
G01X854831Y-229891D02*
X853331Y-228891D01*
X851581Y-228224D01*
X849581D01*
X847331Y-229224D01*
X845581Y-230891D01*
X844331Y-232891D01*
X843331Y-236224D01*
X843081Y-239224D01*
X843581Y-242224D01*
X844331Y-244224D01*
X845831Y-246224D01*
X847581Y-247557D01*
X849331Y-248224D01*
X851081D01*
X852831Y-247557D01*
X854331Y-246558D01*
X855581Y-245225D01*
G01X871331Y-237557D02*
X872331Y-236557D01*
X873081Y-234891D01*
X873581Y-232557D01*
X873081Y-230557D01*
X872081Y-229224D01*
X870331Y-228224D01*
X863581D01*
Y-248224D01*
X871831D01*
X873581Y-246891D01*
X874581Y-244891D01*
X875081Y-242557D01*
X874581Y-240224D01*
X873081Y-238224D01*
X871331Y-237557D01*
X863581D01*
G01X903581Y-248224D02*
Y-228224D01*
X915081Y-248224D01*
Y-228224D01*
G01X929331Y-248224D02*
X927831Y-247891D01*
X926331Y-246558D01*
X925331Y-244224D01*
X924831Y-241558D01*
X925331Y-238891D01*
X926331Y-236557D01*
X927831Y-235224D01*
X929331Y-234891D01*
X930831Y-235224D01*
X932331Y-236557D01*
X933331Y-238891D01*
X933581Y-241558D01*
X933331Y-244224D01*
X932331Y-246558D01*
X930831Y-247891D01*
X929331Y-248224D01*
G01X949331Y-248891D02*
X948831Y-248557D01*
Y-247891D01*
X949331Y-247557D01*
X949831Y-247891D01*
Y-248557D01*
X949331Y-248891D01*
G01X785904Y634833D02*
X786689Y634179D01*
X787571Y633787D01*
X788356D01*
X789140Y634179D01*
X789728Y634833D01*
X790023Y635748D01*
X789827Y636663D01*
X789336Y637448D01*
X788454Y637971D01*
X787277Y638233D01*
X786591Y638755D01*
X786297Y639671D01*
X786493Y640586D01*
X786983Y641240D01*
X787669Y641632D01*
X788356D01*
X789042Y641371D01*
X789630Y640717D01*
G01X794337Y637317D02*
X797474D01*
X797180Y638233D01*
X796690Y638755D01*
X796004Y639017D01*
X795317Y638886D01*
X794729Y638494D01*
X794337Y637579D01*
X794141Y636794D01*
Y636010D01*
X794337Y635225D01*
X794827Y634441D01*
X795415Y633918D01*
X796102Y633787D01*
X796788Y634048D01*
X797474Y634833D01*
G01X802279Y633787D02*
Y639017D01*
G01Y637971D02*
X802769Y638494D01*
X803259Y638886D01*
X803946Y639017D01*
X804436Y638886D01*
X805024Y638494D01*
G01X811495Y639017D02*
Y633787D01*
G01Y641109D02*
X811299Y641240D01*
Y641501D01*
X811495Y641632D01*
X811692Y641501D01*
Y641240D01*
X811495Y641109D01*
G01X817869Y637317D02*
X821006D01*
X820712Y638233D01*
X820222Y638755D01*
X819536Y639017D01*
X818849Y638886D01*
X818261Y638494D01*
X817869Y637579D01*
X817673Y636794D01*
Y636010D01*
X817869Y635225D01*
X818359Y634441D01*
X818947Y633918D01*
X819634Y633787D01*
X820320Y634048D01*
X821006Y634833D01*
G01X825713Y634702D02*
X826203Y634179D01*
X826889Y633787D01*
X827478D01*
X828066Y634048D01*
X828458Y634441D01*
X828654Y634963D01*
X828556Y635748D01*
X828164Y636140D01*
X826399Y636925D01*
X826007Y637840D01*
X826203Y638494D01*
X826595Y638886D01*
X827183Y639017D01*
X827772Y638886D01*
X828360Y638494D01*
G01X841205Y633787D02*
Y639017D01*
G01Y637709D02*
X841597Y638363D01*
X842185Y638886D01*
X842970Y639017D01*
X843656Y638886D01*
X844244Y638363D01*
X844538Y637448D01*
Y633787D01*
G01X849049Y639017D02*
Y635356D01*
X849441Y634441D01*
X850029Y633918D01*
X850715Y633787D01*
X851402Y633918D01*
X851990Y634441D01*
X852382Y635356D01*
G01Y633787D02*
Y639017D01*
G01X855618Y633787D02*
Y639017D01*
G01Y637579D02*
X855912Y638233D01*
X856402Y638755D01*
X857089Y639017D01*
X857775Y638755D01*
X858265Y638233D01*
X858559Y637579D01*
Y633787D01*
G01Y637579D02*
X858854Y638233D01*
X859344Y638755D01*
X860030Y639017D01*
X860717Y638755D01*
X861207Y638233D01*
X861501Y637448D01*
Y633787D01*
G01X864639D02*
Y641632D01*
G01Y637709D02*
X865129Y638494D01*
X865717Y638886D01*
X866305Y639017D01*
X867188Y638755D01*
X867776Y638233D01*
X868168Y637317D01*
Y636271D01*
X867972Y635225D01*
X867580Y634441D01*
X866894Y633918D01*
X866305Y633787D01*
X865717Y633918D01*
X865129Y634310D01*
X864639Y634963D01*
G01X872777Y637317D02*
X875914D01*
X875620Y638233D01*
X875130Y638755D01*
X874444Y639017D01*
X873757Y638886D01*
X873169Y638494D01*
X872777Y637579D01*
X872581Y636794D01*
Y636010D01*
X872777Y635225D01*
X873267Y634441D01*
X873855Y633918D01*
X874542Y633787D01*
X875228Y634048D01*
X875914Y634833D01*
G01X880719Y633787D02*
Y639017D01*
G01Y637971D02*
X881209Y638494D01*
X881699Y638886D01*
X882386Y639017D01*
X882876Y638886D01*
X883464Y638494D01*
G01X899544Y633787D02*
Y639017D01*
G01Y638102D02*
X899152Y638625D01*
X898564Y638886D01*
X897878Y639017D01*
X897191Y638755D01*
X896603Y638233D01*
X896211Y637448D01*
X896015Y636402D01*
X896211Y635356D01*
X896603Y634571D01*
X897191Y634048D01*
X897878Y633787D01*
X898564Y633918D01*
X899152Y634310D01*
X899544Y634833D01*
G01X903957Y633787D02*
Y639017D01*
G01Y637709D02*
X904349Y638363D01*
X904937Y638886D01*
X905722Y639017D01*
X906408Y638886D01*
X906996Y638363D01*
X907290Y637448D01*
Y633787D01*
G01X915232Y641632D02*
Y633787D01*
G01Y634963D02*
X914840Y634310D01*
X914252Y633918D01*
X913566Y633787D01*
X912781Y634048D01*
X912193Y634702D01*
X911801Y635487D01*
X911703Y636402D01*
X911801Y637317D01*
X912193Y638102D01*
X912781Y638755D01*
X913566Y639017D01*
X914252Y638886D01*
X914742Y638625D01*
X915232Y638102D01*
G01X927783Y633787D02*
Y639017D01*
G01Y637971D02*
X928273Y638494D01*
X928763Y638886D01*
X929450Y639017D01*
X929940Y638886D01*
X930528Y638494D01*
G01X935529Y637317D02*
X938666D01*
X938372Y638233D01*
X937882Y638755D01*
X937196Y639017D01*
X936509Y638886D01*
X935921Y638494D01*
X935529Y637579D01*
X935333Y636794D01*
Y636010D01*
X935529Y635225D01*
X936019Y634441D01*
X936607Y633918D01*
X937294Y633787D01*
X937980Y634048D01*
X938666Y634833D01*
G01X944255Y633787D02*
Y640455D01*
X944451Y641109D01*
X944843Y641501D01*
X945432Y641632D01*
X946020Y641371D01*
X946314Y640717D01*
G01X945138Y638494D02*
X943177D01*
G01X951217Y637317D02*
X954354D01*
X954060Y638233D01*
X953570Y638755D01*
X952884Y639017D01*
X952197Y638886D01*
X951609Y638494D01*
X951217Y637579D01*
X951021Y636794D01*
Y636010D01*
X951217Y635225D01*
X951707Y634441D01*
X952295Y633918D01*
X952982Y633787D01*
X953668Y634048D01*
X954354Y634833D01*
G01X959159Y633787D02*
Y639017D01*
G01Y637971D02*
X959649Y638494D01*
X960139Y638886D01*
X960826Y639017D01*
X961316Y638886D01*
X961904Y638494D01*
G01X966905Y637317D02*
X970042D01*
X969748Y638233D01*
X969258Y638755D01*
X968572Y639017D01*
X967885Y638886D01*
X967297Y638494D01*
X966905Y637579D01*
X966709Y636794D01*
Y636010D01*
X966905Y635225D01*
X967395Y634441D01*
X967983Y633918D01*
X968670Y633787D01*
X969356Y634048D01*
X970042Y634833D01*
G01X974553Y633787D02*
Y639017D01*
G01Y637709D02*
X974945Y638363D01*
X975533Y638886D01*
X976318Y639017D01*
X977004Y638886D01*
X977592Y638363D01*
X977886Y637448D01*
Y633787D01*
G01X985632Y638363D02*
X984946Y638886D01*
X984358Y639017D01*
X983573Y638755D01*
X982985Y638233D01*
X982593Y637317D01*
X982495Y636402D01*
X982593Y635487D01*
X982985Y634702D01*
X983573Y634048D01*
X984358Y633787D01*
X985044Y634048D01*
X985632Y634571D01*
G01X990437Y637317D02*
X993574D01*
X993280Y638233D01*
X992790Y638755D01*
X992104Y639017D01*
X991417Y638886D01*
X990829Y638494D01*
X990437Y637579D01*
X990241Y636794D01*
Y636010D01*
X990437Y635225D01*
X990927Y634441D01*
X991515Y633918D01*
X992202Y633787D01*
X992888Y634048D01*
X993574Y634833D01*
G01X1007595Y633787D02*
X1007007Y633918D01*
X1006419Y634441D01*
X1006027Y635356D01*
X1005831Y636402D01*
X1006027Y637448D01*
X1006419Y638363D01*
X1007007Y638886D01*
X1007595Y639017D01*
X1008184Y638886D01*
X1008772Y638363D01*
X1009164Y637448D01*
X1009262Y636402D01*
X1009164Y635356D01*
X1008772Y634441D01*
X1008184Y633918D01*
X1007595Y633787D01*
G01X1013773D02*
Y639017D01*
G01Y637709D02*
X1014165Y638363D01*
X1014753Y638886D01*
X1015538Y639017D01*
X1016224Y638886D01*
X1016812Y638363D01*
X1017106Y637448D01*
Y633787D01*
G01X1023283D02*
Y641632D01*
G01X1029068Y631434D02*
X1029657Y631172D01*
X1030441Y631434D01*
X1030931Y631956D01*
X1031324Y632610D01*
X1031912Y634702D01*
X1033187Y639017D01*
G01X1030049D02*
X1031912Y634702D01*
G01X1038971Y633526D02*
X1038775Y633656D01*
Y633918D01*
X1038971Y634048D01*
X1039168Y633918D01*
Y633656D01*
X1038971Y633526D01*
G01X799311Y923435D02*
X799458Y924715D01*
X799680Y925797D01*
X799975Y926782D01*
X800344Y927864D01*
X800935Y929341D01*
X797982D01*
G01X888654Y-374649D02*
X893064Y-399649D01*
X898104Y-374649D01*
X903144Y-399649D01*
X907554Y-374649D01*
G01X923304Y-382983D02*
Y-399649D01*
G01Y-376316D02*
X922674Y-375899D01*
Y-375066D01*
X923304Y-374649D01*
X923934Y-375066D01*
Y-375899D01*
X923304Y-376316D01*
G01X943779Y-396733D02*
X945354Y-398399D01*
X947559Y-399649D01*
X949449D01*
X951339Y-398816D01*
X952599Y-397566D01*
X953229Y-395900D01*
X952914Y-393399D01*
X951654Y-392149D01*
X945984Y-389650D01*
X944724Y-386732D01*
X945354Y-384649D01*
X946614Y-383399D01*
X948504Y-382983D01*
X950394Y-383399D01*
X952284Y-384649D01*
G01X973704Y-374649D02*
Y-399649D01*
G01X969294Y-382983D02*
X978114D01*
G01X994494Y-399649D02*
Y-382983D01*
G01Y-386315D02*
X996069Y-384649D01*
X997644Y-383399D01*
X999849Y-382983D01*
X1001424Y-383399D01*
X1003314Y-384649D01*
G01X1024104Y-399649D02*
X1022214Y-399232D01*
X1020324Y-397566D01*
X1019064Y-394649D01*
X1018434Y-391316D01*
X1019064Y-387983D01*
X1020324Y-385066D01*
X1022214Y-383399D01*
X1024104Y-382983D01*
X1025994Y-383399D01*
X1027884Y-385066D01*
X1029144Y-387983D01*
X1029459Y-391316D01*
X1029144Y-394649D01*
X1027884Y-397566D01*
X1025994Y-399232D01*
X1024104Y-399649D01*
G01X1043949D02*
Y-382983D01*
G01Y-387149D02*
X1045209Y-385066D01*
X1047099Y-383399D01*
X1049619Y-382983D01*
X1051824Y-383399D01*
X1053714Y-385066D01*
X1054659Y-387983D01*
Y-399649D01*
G01X1106634Y-376733D02*
X1104744Y-375482D01*
X1102539Y-374649D01*
X1100019D01*
X1097184Y-375899D01*
X1094979Y-377982D01*
X1093404Y-380483D01*
X1092144Y-384649D01*
X1091829Y-388399D01*
X1092459Y-392149D01*
X1093404Y-394649D01*
X1095294Y-397150D01*
X1097499Y-398816D01*
X1099704Y-399649D01*
X1101909D01*
X1104114Y-398816D01*
X1106004Y-397566D01*
X1107579Y-395900D01*
G01X1124904Y-399649D02*
X1123014Y-399232D01*
X1121124Y-397566D01*
X1119864Y-394649D01*
X1119234Y-391316D01*
X1119864Y-387983D01*
X1121124Y-385066D01*
X1123014Y-383399D01*
X1124904Y-382983D01*
X1126794Y-383399D01*
X1128684Y-385066D01*
X1129944Y-387983D01*
X1130259Y-391316D01*
X1129944Y-394649D01*
X1128684Y-397566D01*
X1126794Y-399232D01*
X1124904Y-399649D01*
G01X1145694D02*
Y-382983D01*
G01Y-386315D02*
X1147269Y-384649D01*
X1148844Y-383399D01*
X1151049Y-382983D01*
X1152624Y-383399D01*
X1154514Y-384649D01*
G01X1169634Y-407982D02*
Y-382983D01*
G01Y-386732D02*
X1171209Y-384649D01*
X1172784Y-383399D01*
X1175304Y-382983D01*
X1177509Y-383399D01*
X1179714Y-385482D01*
X1180659Y-388399D01*
X1180974Y-391316D01*
X1180659Y-394233D01*
X1179714Y-397150D01*
X1177824Y-398816D01*
X1175304Y-399649D01*
X1173099Y-399232D01*
X1170894Y-397983D01*
X1169634Y-396316D01*
G01X1200504Y-399649D02*
X1198614Y-399232D01*
X1196724Y-397566D01*
X1195464Y-394649D01*
X1194834Y-391316D01*
X1195464Y-387983D01*
X1196724Y-385066D01*
X1198614Y-383399D01*
X1200504Y-382983D01*
X1202394Y-383399D01*
X1204284Y-385066D01*
X1205544Y-387983D01*
X1205859Y-391316D01*
X1205544Y-394649D01*
X1204284Y-397566D01*
X1202394Y-399232D01*
X1200504Y-399649D01*
G01X1221294D02*
Y-382983D01*
G01Y-386315D02*
X1222869Y-384649D01*
X1224444Y-383399D01*
X1226649Y-382983D01*
X1228224Y-383399D01*
X1230114Y-384649D01*
G01X1256574Y-399649D02*
Y-382983D01*
G01Y-385899D02*
X1255314Y-384233D01*
X1253424Y-383399D01*
X1251219Y-382983D01*
X1249014Y-383816D01*
X1247124Y-385482D01*
X1245864Y-387983D01*
X1245234Y-391316D01*
X1245864Y-394649D01*
X1247124Y-397150D01*
X1249014Y-398816D01*
X1251219Y-399649D01*
X1253424Y-399232D01*
X1255314Y-397983D01*
X1256574Y-396316D01*
G01X1276104Y-374649D02*
Y-399649D01*
G01X1271694Y-382983D02*
X1280514D01*
G01X1301304D02*
Y-399649D01*
G01Y-376316D02*
X1300674Y-375899D01*
Y-375066D01*
X1301304Y-374649D01*
X1301934Y-375066D01*
Y-375899D01*
X1301304Y-376316D01*
G01X1326504Y-399649D02*
X1324614Y-399232D01*
X1322724Y-397566D01*
X1321464Y-394649D01*
X1320834Y-391316D01*
X1321464Y-387983D01*
X1322724Y-385066D01*
X1324614Y-383399D01*
X1326504Y-382983D01*
X1328394Y-383399D01*
X1330284Y-385066D01*
X1331544Y-387983D01*
X1331859Y-391316D01*
X1331544Y-394649D01*
X1330284Y-397566D01*
X1328394Y-399232D01*
X1326504Y-399649D01*
G01X1346349D02*
Y-382983D01*
G01Y-387149D02*
X1347609Y-385066D01*
X1349499Y-383399D01*
X1352019Y-382983D01*
X1354224Y-383399D01*
X1356114Y-385066D01*
X1357059Y-387983D01*
Y-399649D01*
G01X965143Y246189D02*
X964623Y246016D01*
X964233Y245583D01*
X963974Y245063D01*
X963779Y244370D01*
X963714Y243590D01*
X963779Y242811D01*
X963974Y242118D01*
X964233Y241598D01*
X964623Y241165D01*
X965143Y240992D01*
X965663Y241165D01*
X966053Y241598D01*
X966312Y242118D01*
X966507Y242811D01*
X966572Y243590D01*
X966507Y244370D01*
X966312Y245063D01*
X966053Y245583D01*
X965663Y246016D01*
X965143Y246189D01*
G01X956112Y249653D02*
X957672D01*
G01X956827Y250779D02*
Y248527D01*
G01X962024Y253118D02*
X961504Y252945D01*
X961114Y252512D01*
X960855Y251992D01*
X960660Y251299D01*
X960595Y250519D01*
X960660Y249740D01*
X960855Y249047D01*
X961114Y248527D01*
X961504Y248094D01*
X962024Y247921D01*
X962544Y248094D01*
X962934Y248527D01*
X963193Y249047D01*
X963388Y249740D01*
X963453Y250519D01*
X963388Y251299D01*
X963193Y251992D01*
X962934Y252512D01*
X962544Y252945D01*
X962024Y253118D01*
G01X967221Y247748D02*
X967091Y247834D01*
Y248008D01*
X967221Y248094D01*
X967351Y248008D01*
Y247834D01*
X967221Y247748D01*
G01X972418Y253118D02*
X971898Y252945D01*
X971508Y252512D01*
X971249Y251992D01*
X971054Y251299D01*
X970989Y250519D01*
X971054Y249740D01*
X971249Y249047D01*
X971508Y248527D01*
X971898Y248094D01*
X972418Y247921D01*
X972938Y248094D01*
X973328Y248527D01*
X973587Y249047D01*
X973782Y249740D01*
X973847Y250519D01*
X973782Y251299D01*
X973587Y251992D01*
X973328Y252512D01*
X972938Y252945D01*
X972418Y253118D01*
G01X976186Y248700D02*
X976575Y248267D01*
X977030Y248008D01*
X977615Y247921D01*
X978200Y248094D01*
X978654Y248441D01*
X978979Y249047D01*
X979044Y249740D01*
X978914Y250433D01*
X978589Y250866D01*
X978135Y251212D01*
X977680Y251299D01*
X977225Y251212D01*
X976641Y250866D01*
X976835Y253118D01*
X978589D01*
G01X929546Y242724D02*
Y251385D01*
X928247Y249653D01*
G01Y242724D02*
X930845D01*
G01X938207Y242435D02*
X937990Y242580D01*
Y242868D01*
X938207Y243013D01*
X938424Y242868D01*
Y242580D01*
X938207Y242435D01*
G01X944811Y246333D02*
X945569Y247343D01*
X946218Y247921D01*
X947085Y248209D01*
X947842Y247921D01*
X948384Y247343D01*
X948817Y246477D01*
X948925Y245467D01*
X948817Y244600D01*
X948384Y243734D01*
X947734Y243013D01*
X946976Y242724D01*
X946110Y243013D01*
X945352Y243879D01*
X944919Y245178D01*
X944811Y246621D01*
X945027Y248498D01*
X945352Y249509D01*
X945894Y250519D01*
X946651Y251241D01*
X947409Y251385D01*
X948167Y251096D01*
X948709Y250375D01*
G01X955529Y251385D02*
X954663Y251096D01*
X954013Y250375D01*
X953580Y249509D01*
X953255Y248354D01*
X953147Y247054D01*
X953255Y245755D01*
X953580Y244600D01*
X954013Y243734D01*
X954663Y243013D01*
X955529Y242724D01*
X956395Y243013D01*
X957045Y243734D01*
X957478Y244600D01*
X957803Y245755D01*
X957911Y247054D01*
X957803Y248354D01*
X957478Y249509D01*
X957045Y250375D01*
X956395Y251096D01*
X955529Y251385D01*
G01X972686Y-437195D02*
X973203Y-437097D01*
X973794Y-436801D01*
X974163Y-436309D01*
X974310Y-435620D01*
X974163Y-434931D01*
X973720Y-434341D01*
X973056Y-434045D01*
X972317D01*
X971874Y-433848D01*
X971505Y-433356D01*
X971358Y-432667D01*
X971579Y-431978D01*
X972096Y-431486D01*
X972686Y-431289D01*
X973277Y-431486D01*
X973794Y-431978D01*
X974015Y-432667D01*
X973868Y-433356D01*
X973499Y-433848D01*
X973056Y-434045D01*
X972317D01*
X971653Y-434341D01*
X971210Y-434931D01*
X971063Y-435620D01*
X971210Y-436309D01*
X971579Y-436801D01*
X972170Y-437097D01*
X972686Y-437195D01*
G01X1020387Y-200304D02*
Y-177804D01*
G01X1032077D02*
Y-200304D01*
G01Y-189054D02*
X1020387D01*
G01X1048532Y-200304D02*
X1046862Y-199929D01*
X1045192Y-198429D01*
X1044078Y-195804D01*
X1043522Y-192804D01*
X1044078Y-189804D01*
X1045192Y-187179D01*
X1046862Y-185679D01*
X1048532Y-185304D01*
X1050202Y-185679D01*
X1051872Y-187179D01*
X1052985Y-189804D01*
X1053264Y-192804D01*
X1052985Y-195804D01*
X1051872Y-198429D01*
X1050202Y-199929D01*
X1048532Y-200304D01*
G01X1066100D02*
Y-185304D01*
G01Y-189054D02*
X1067214Y-187179D01*
X1068884Y-185679D01*
X1071111Y-185304D01*
X1073058Y-185679D01*
X1074729Y-187179D01*
X1075564Y-189804D01*
Y-200304D01*
G01X1088957Y-190179D02*
X1097864D01*
X1097029Y-187554D01*
X1095637Y-186054D01*
X1093689Y-185304D01*
X1091740Y-185679D01*
X1090070Y-186804D01*
X1088957Y-189429D01*
X1088400Y-191679D01*
Y-193929D01*
X1088957Y-196179D01*
X1090348Y-198429D01*
X1092019Y-199929D01*
X1093967Y-200304D01*
X1095916Y-199554D01*
X1097864Y-197305D01*
G01X1109587Y-207054D02*
X1111257Y-207804D01*
X1113484Y-207054D01*
X1114875Y-205554D01*
X1115989Y-203679D01*
X1117658Y-197680D01*
X1121277Y-185304D01*
G01X1112370D02*
X1117658Y-197680D01*
G01X1162258Y-188304D02*
X1163372Y-187179D01*
X1164207Y-185304D01*
X1164764Y-182679D01*
X1164207Y-180429D01*
X1163094Y-178929D01*
X1161145Y-177804D01*
X1153630D01*
Y-200304D01*
X1162816D01*
X1164764Y-198804D01*
X1165877Y-196554D01*
X1166434Y-193929D01*
X1165877Y-191305D01*
X1164207Y-189054D01*
X1162258Y-188304D01*
X1153630D01*
G01X1187342Y-200304D02*
Y-185304D01*
G01Y-187929D02*
X1186229Y-186429D01*
X1184558Y-185679D01*
X1182611Y-185304D01*
X1180662Y-186054D01*
X1178992Y-187554D01*
X1177878Y-189804D01*
X1177322Y-192804D01*
X1177878Y-195804D01*
X1178992Y-198054D01*
X1180662Y-199554D01*
X1182611Y-200304D01*
X1184558Y-199929D01*
X1186229Y-198804D01*
X1187342Y-197305D01*
G01X1209642Y-177804D02*
Y-200304D01*
G01Y-196930D02*
X1208529Y-198804D01*
X1206858Y-199929D01*
X1204911Y-200304D01*
X1202684Y-199554D01*
X1201014Y-197680D01*
X1199900Y-195429D01*
X1199622Y-192804D01*
X1199900Y-190179D01*
X1201014Y-187929D01*
X1202684Y-186054D01*
X1204911Y-185304D01*
X1206858Y-185679D01*
X1208250Y-186429D01*
X1209642Y-187929D01*
G01X1223035Y-205929D02*
X1224984Y-207429D01*
X1227211Y-207804D01*
X1229158Y-207429D01*
X1230829Y-205554D01*
X1231942Y-202929D01*
Y-185304D01*
G01Y-188304D02*
X1230829Y-186804D01*
X1229158Y-185679D01*
X1227211Y-185304D01*
X1224984Y-186054D01*
X1223592Y-187554D01*
X1222478Y-190179D01*
X1221922Y-192804D01*
X1222200Y-195054D01*
X1223314Y-197680D01*
X1224984Y-199554D01*
X1227211Y-200304D01*
X1228880Y-199929D01*
X1230829Y-198429D01*
X1231942Y-196930D01*
G01X1245057Y-190179D02*
X1253964D01*
X1253129Y-187554D01*
X1251737Y-186054D01*
X1249789Y-185304D01*
X1247840Y-185679D01*
X1246170Y-186804D01*
X1245057Y-189429D01*
X1244500Y-191679D01*
Y-193929D01*
X1245057Y-196179D01*
X1246448Y-198429D01*
X1248119Y-199929D01*
X1250067Y-200304D01*
X1252016Y-199554D01*
X1253964Y-197305D01*
G01X1267635Y-200304D02*
Y-185304D01*
G01Y-188304D02*
X1269027Y-186804D01*
X1270419Y-185679D01*
X1272367Y-185304D01*
X1273758Y-185679D01*
X1275429Y-186804D01*
G01X1310565Y-200304D02*
Y-177804D01*
X1317524D01*
X1319750Y-178929D01*
X1321142Y-180429D01*
X1321699Y-183429D01*
X1321142Y-186429D01*
X1319472Y-188304D01*
X1317524Y-189429D01*
X1310565D01*
G01X1317524D02*
X1321699Y-200304D01*
G01X1338432Y-185304D02*
Y-200304D01*
G01Y-179304D02*
X1337875Y-178929D01*
Y-178179D01*
X1338432Y-177804D01*
X1338989Y-178179D01*
Y-178929D01*
X1338432Y-179304D01*
G01X1356557Y-197680D02*
X1357948Y-199179D01*
X1359897Y-200304D01*
X1361567D01*
X1363237Y-199554D01*
X1364350Y-198429D01*
X1364907Y-196930D01*
X1364629Y-194679D01*
X1363516Y-193554D01*
X1358505Y-191305D01*
X1357392Y-188679D01*
X1357948Y-186804D01*
X1359062Y-185679D01*
X1360732Y-185304D01*
X1362402Y-185679D01*
X1364072Y-186804D01*
G01X1378857Y-190179D02*
X1387764D01*
X1386929Y-187554D01*
X1385537Y-186054D01*
X1383589Y-185304D01*
X1381640Y-185679D01*
X1379970Y-186804D01*
X1378857Y-189429D01*
X1378300Y-191679D01*
Y-193929D01*
X1378857Y-196179D01*
X1380248Y-198429D01*
X1381919Y-199929D01*
X1383867Y-200304D01*
X1385816Y-199554D01*
X1387764Y-197305D01*
G01X1401435Y-200304D02*
Y-185304D01*
G01Y-188304D02*
X1402827Y-186804D01*
X1404219Y-185679D01*
X1406167Y-185304D01*
X1407558Y-185679D01*
X1409229Y-186804D01*
G01X1456055Y-179679D02*
X1454385Y-178554D01*
X1452437Y-177804D01*
X1450211D01*
X1447705Y-178929D01*
X1445757Y-180804D01*
X1444365Y-183054D01*
X1443252Y-186804D01*
X1442973Y-190179D01*
X1443530Y-193554D01*
X1444365Y-195804D01*
X1446035Y-198054D01*
X1447984Y-199554D01*
X1449932Y-200304D01*
X1451880D01*
X1453829Y-199554D01*
X1455499Y-198429D01*
X1456891Y-196930D01*
G01X1477242Y-200304D02*
Y-185304D01*
G01Y-187929D02*
X1476129Y-186429D01*
X1474458Y-185679D01*
X1472511Y-185304D01*
X1470562Y-186054D01*
X1468892Y-187554D01*
X1467778Y-189804D01*
X1467222Y-192804D01*
X1467778Y-195804D01*
X1468892Y-198054D01*
X1470562Y-199554D01*
X1472511Y-200304D01*
X1474458Y-199929D01*
X1476129Y-198804D01*
X1477242Y-197305D01*
G01X1490635Y-200304D02*
Y-185304D01*
G01Y-188304D02*
X1492027Y-186804D01*
X1493419Y-185679D01*
X1495367Y-185304D01*
X1496758Y-185679D01*
X1498429Y-186804D01*
G01X1521842Y-177804D02*
Y-200304D01*
G01Y-196930D02*
X1520729Y-198804D01*
X1519058Y-199929D01*
X1517111Y-200304D01*
X1514884Y-199554D01*
X1513214Y-197680D01*
X1512100Y-195429D01*
X1511822Y-192804D01*
X1512100Y-190179D01*
X1513214Y-187929D01*
X1514884Y-186054D01*
X1517111Y-185304D01*
X1519058Y-185679D01*
X1520450Y-186429D01*
X1521842Y-187929D01*
G01X1006748Y238393D02*
X996512Y240362D01*
Y236425D01*
X1006748Y238393D01*
G01X1013048D02*
X1023284Y236425D01*
Y240362D01*
X1013048Y238393D01*
G01X1010217Y340340D02*
X1010867Y341205D01*
X1011624Y341639D01*
X1012491Y341783D01*
X1013573Y341494D01*
X1014331Y340773D01*
X1014548Y339907D01*
X1014439Y339040D01*
X1014006Y338319D01*
X1011841Y336875D01*
X1010867Y335865D01*
X1010217Y334421D01*
X1010000Y333122D01*
X1014548D01*
G01X1020935Y341783D02*
X1020069Y341494D01*
X1019419Y340773D01*
X1018986Y339907D01*
X1018661Y338752D01*
X1018553Y337452D01*
X1018661Y336153D01*
X1018986Y334998D01*
X1019419Y334132D01*
X1020069Y333411D01*
X1020935Y333122D01*
X1021801Y333411D01*
X1022451Y334132D01*
X1022884Y334998D01*
X1023209Y336153D01*
X1023317Y337452D01*
X1023209Y338752D01*
X1022884Y339907D01*
X1022451Y340773D01*
X1021801Y341494D01*
X1020935Y341783D01*
G01X1029596D02*
X1028730Y341494D01*
X1028080Y340773D01*
X1027647Y339907D01*
X1027322Y338752D01*
X1027214Y337452D01*
X1027322Y336153D01*
X1027647Y334998D01*
X1028080Y334132D01*
X1028730Y333411D01*
X1029596Y333122D01*
X1030462Y333411D01*
X1031112Y334132D01*
X1031545Y334998D01*
X1031870Y336153D01*
X1031978Y337452D01*
X1031870Y338752D01*
X1031545Y339907D01*
X1031112Y340773D01*
X1030462Y341494D01*
X1029596Y341783D01*
G01X1038257Y332833D02*
X1038040Y332978D01*
Y333266D01*
X1038257Y333411D01*
X1038474Y333266D01*
Y332978D01*
X1038257Y332833D01*
G01X1046918Y341783D02*
X1046052Y341494D01*
X1045402Y340773D01*
X1044969Y339907D01*
X1044644Y338752D01*
X1044536Y337452D01*
X1044644Y336153D01*
X1044969Y334998D01*
X1045402Y334132D01*
X1046052Y333411D01*
X1046918Y333122D01*
X1047784Y333411D01*
X1048434Y334132D01*
X1048867Y334998D01*
X1049192Y336153D01*
X1049300Y337452D01*
X1049192Y338752D01*
X1048867Y339907D01*
X1048434Y340773D01*
X1047784Y341494D01*
X1046918Y341783D01*
G01X1017091Y353049D02*
X1006748Y351746D01*
X1016836Y349120D01*
X1017091Y353049D01*
G01X972686Y923435D02*
X973203Y923533D01*
X973794Y923829D01*
X974163Y924321D01*
X974310Y925010D01*
X974163Y925699D01*
X973720Y926289D01*
X973056Y926585D01*
X972317D01*
X971874Y926782D01*
X971505Y927274D01*
X971358Y927963D01*
X971579Y928652D01*
X972096Y929144D01*
X972686Y929341D01*
X973277Y929144D01*
X973794Y928652D01*
X974015Y927963D01*
X973868Y927274D01*
X973499Y926782D01*
X973056Y926585D01*
X972317D01*
X971653Y926289D01*
X971210Y925699D01*
X971063Y925010D01*
X971210Y924321D01*
X971579Y923829D01*
X972170Y923533D01*
X972686Y923435D01*
G01X1037285Y-320837D02*
X1035785Y-319837D01*
X1034035Y-319170D01*
X1032035D01*
X1029785Y-320170D01*
X1028035Y-321837D01*
X1026785Y-323837D01*
X1025785Y-327170D01*
X1025535Y-330170D01*
X1026035Y-333170D01*
X1026785Y-335170D01*
X1028285Y-337170D01*
X1030035Y-338503D01*
X1031785Y-339170D01*
X1033535D01*
X1035285Y-338503D01*
X1036785Y-337504D01*
X1038035Y-336171D01*
G01X1051785Y-339170D02*
X1050285Y-338837D01*
X1048785Y-337504D01*
X1047785Y-335170D01*
X1047285Y-332504D01*
X1047785Y-329837D01*
X1048785Y-327503D01*
X1050285Y-326170D01*
X1051785Y-325837D01*
X1053285Y-326170D01*
X1054785Y-327503D01*
X1055785Y-329837D01*
X1056035Y-332504D01*
X1055785Y-335170D01*
X1054785Y-337504D01*
X1053285Y-338837D01*
X1051785Y-339170D01*
G01X1071785D02*
X1070285Y-338837D01*
X1068785Y-337504D01*
X1067785Y-335170D01*
X1067285Y-332504D01*
X1067785Y-329837D01*
X1068785Y-327503D01*
X1070285Y-326170D01*
X1071785Y-325837D01*
X1073285Y-326170D01*
X1074785Y-327503D01*
X1075785Y-329837D01*
X1076035Y-332504D01*
X1075785Y-335170D01*
X1074785Y-337504D01*
X1073285Y-338837D01*
X1071785Y-339170D01*
G01X1091785D02*
Y-319170D01*
G01X1116285Y-339170D02*
Y-325837D01*
G01Y-328170D02*
X1115285Y-326837D01*
X1113785Y-326170D01*
X1112035Y-325837D01*
X1110285Y-326504D01*
X1108785Y-327837D01*
X1107785Y-329837D01*
X1107285Y-332504D01*
X1107785Y-335170D01*
X1108785Y-337170D01*
X1110285Y-338503D01*
X1112035Y-339170D01*
X1113785Y-338837D01*
X1115285Y-337837D01*
X1116285Y-336504D01*
G01X1046313Y-294465D02*
X1048313Y-296131D01*
X1050563Y-297131D01*
X1052563D01*
X1054563Y-296131D01*
X1056063Y-294465D01*
X1056813Y-292131D01*
X1056313Y-289798D01*
X1055063Y-287798D01*
X1052813Y-286464D01*
X1049813Y-285798D01*
X1048063Y-284465D01*
X1047313Y-282131D01*
X1047813Y-279798D01*
X1049063Y-278131D01*
X1050813Y-277131D01*
X1052563D01*
X1054313Y-277798D01*
X1055813Y-279464D01*
G01X1065313Y-297131D02*
X1071563Y-277131D01*
X1077813Y-297131D01*
G01X1075563Y-290131D02*
X1067563D01*
G01X1037533Y-246249D02*
Y-226249D01*
X1034533Y-230249D01*
G01Y-246249D02*
X1040533D01*
G01X1052033Y-242249D02*
X1053533Y-244583D01*
X1055533Y-245916D01*
X1057783Y-246249D01*
X1059783Y-245916D01*
X1061783Y-244249D01*
X1063033Y-242249D01*
X1063283Y-240249D01*
X1062783Y-237916D01*
X1061033Y-236249D01*
X1059283Y-235582D01*
X1057033D01*
G01X1059283D02*
X1060783Y-234582D01*
X1062033Y-232916D01*
X1062533Y-230916D01*
X1062033Y-228916D01*
X1060783Y-227249D01*
X1058533Y-226249D01*
X1056283Y-226582D01*
X1054033Y-227916D01*
G01X1073283Y-243916D02*
X1075033Y-245582D01*
X1077033Y-246249D01*
X1079033Y-245582D01*
X1080783Y-243583D01*
X1082033Y-240582D01*
X1082533Y-237582D01*
Y-233916D01*
X1082033Y-230916D01*
X1080783Y-228249D01*
X1079283Y-226916D01*
X1077533Y-226249D01*
X1075533Y-226916D01*
X1074033Y-228249D01*
X1073033Y-230249D01*
X1072533Y-232916D01*
X1073033Y-235249D01*
X1074283Y-237582D01*
X1075783Y-238916D01*
X1077533Y-239249D01*
X1079533Y-238583D01*
X1081033Y-236916D01*
X1082533Y-233916D01*
G01X1097533Y-246249D02*
Y-226249D01*
X1094533Y-230249D01*
G01Y-246249D02*
X1100533D01*
G01X1113283Y-243916D02*
X1115033Y-245582D01*
X1117033Y-246249D01*
X1119033Y-245582D01*
X1120783Y-243583D01*
X1122033Y-240582D01*
X1122533Y-237582D01*
Y-233916D01*
X1122033Y-230916D01*
X1120783Y-228249D01*
X1119283Y-226916D01*
X1117533Y-226249D01*
X1115533Y-226916D01*
X1114033Y-228249D01*
X1113033Y-230249D01*
X1112533Y-232916D01*
X1113033Y-235249D01*
X1114283Y-237582D01*
X1115783Y-238916D01*
X1117533Y-239249D01*
X1119533Y-238583D01*
X1121033Y-236916D01*
X1122533Y-233916D01*
G01X1042397Y204155D02*
X1033816Y198237D01*
X1043980Y200550D01*
X1042397Y204155D01*
G01X1069904Y258629D02*
X1063752Y264726D01*
X1064068Y262584D01*
G01X1068990Y257706D02*
X1070819Y259552D01*
G01X1076206Y264578D02*
X1075951Y264526D01*
X1075746Y264729D01*
X1075796Y264984D01*
X1076051Y265036D01*
X1076256Y264833D01*
X1076206Y264578D01*
G01X1075946Y277030D02*
X1075542Y276211D01*
X1075597Y275242D01*
X1075907Y274325D01*
X1076499Y273281D01*
X1077346Y272289D01*
X1078345Y271452D01*
X1079394Y270870D01*
X1080314Y270568D01*
X1081284Y270521D01*
X1082098Y270933D01*
X1082503Y271751D01*
X1082448Y272721D01*
X1082137Y273638D01*
X1081546Y274682D01*
X1080699Y275673D01*
X1079700Y276511D01*
X1078651Y277093D01*
X1077731Y277395D01*
X1076761Y277442D01*
X1075946Y277030D01*
G01X1082043Y283182D02*
X1081639Y282363D01*
X1081694Y281394D01*
X1082004Y280477D01*
X1082596Y279433D01*
X1083443Y278441D01*
X1084442Y277604D01*
X1085491Y277022D01*
X1086411Y276720D01*
X1087381Y276673D01*
X1088195Y277085D01*
X1088600Y277903D01*
X1088545Y278873D01*
X1088234Y279790D01*
X1087643Y280834D01*
X1086796Y281825D01*
X1085797Y282663D01*
X1084748Y283245D01*
X1083828Y283547D01*
X1082858Y283594D01*
X1082043Y283182D01*
G01X1064720Y253399D02*
X1058568Y259496D01*
X1060474Y261418D01*
X1061391Y261728D01*
X1062182Y261707D01*
X1063155Y261047D01*
X1063823Y260081D01*
X1063878Y259111D01*
X1063652Y258268D01*
X1061747Y256346D01*
G01X1063652Y258268D02*
X1067769Y256475D01*
G01X1044403Y267094D02*
X1042434Y256857D01*
X1046371D01*
X1044403Y267094D01*
G01Y272606D02*
X1046371Y282842D01*
X1042434D01*
X1044403Y272606D01*
G01X1065613Y334421D02*
X1066263Y333699D01*
X1067021Y333266D01*
X1067995Y333122D01*
X1068969Y333411D01*
X1069727Y333988D01*
X1070269Y334998D01*
X1070377Y336153D01*
X1070160Y337308D01*
X1069619Y338030D01*
X1068861Y338607D01*
X1068103Y338752D01*
X1067345Y338607D01*
X1066371Y338030D01*
X1066696Y341783D01*
X1069619D01*
G01X1076656Y332833D02*
X1076439Y332978D01*
Y333266D01*
X1076656Y333411D01*
X1076873Y333266D01*
Y332978D01*
X1076656Y332833D01*
G01X1085317Y341783D02*
X1084451Y341494D01*
X1083801Y340773D01*
X1083368Y339907D01*
X1083043Y338752D01*
X1082935Y337452D01*
X1083043Y336153D01*
X1083368Y334998D01*
X1083801Y334132D01*
X1084451Y333411D01*
X1085317Y333122D01*
X1086183Y333411D01*
X1086833Y334132D01*
X1087266Y334998D01*
X1087591Y336153D01*
X1087699Y337452D01*
X1087591Y338752D01*
X1087266Y339907D01*
X1086833Y340773D01*
X1086183Y341494D01*
X1085317Y341783D01*
G01X1059911Y338896D02*
X1058828Y340700D01*
Y341783D01*
X1059640D01*
Y340700D01*
X1058828D01*
G01X1048723Y336009D02*
X1049806Y338896D01*
X1050888D01*
X1053054Y333122D01*
X1054136D01*
X1055219Y336009D01*
G01X1033576Y336724D02*
X1033865Y335858D01*
X1034586Y335208D01*
X1035452Y334775D01*
X1036607Y334450D01*
X1037907Y334342D01*
X1039206Y334450D01*
X1040361Y334775D01*
X1041227Y335208D01*
X1041948Y335858D01*
X1042237Y336724D01*
X1041948Y337590D01*
X1041227Y338240D01*
X1040361Y338673D01*
X1039206Y338998D01*
X1037907Y339106D01*
X1036607Y338998D01*
X1035452Y338673D01*
X1034586Y338240D01*
X1033865Y337590D01*
X1033576Y336724D01*
G01X1042526Y345385D02*
X1042381Y345168D01*
X1042093D01*
X1041948Y345385D01*
X1042093Y345602D01*
X1042381D01*
X1042526Y345385D01*
G01X1042237Y354046D02*
X1033576D01*
X1035308Y352747D01*
G01X1042237D02*
Y355345D01*
G01X1040505Y360325D02*
X1041515Y360975D01*
X1042093Y361841D01*
X1042237Y362815D01*
X1042093Y363681D01*
X1041371Y364548D01*
X1040505Y365089D01*
X1039639Y365197D01*
X1038628Y364981D01*
X1037907Y364223D01*
X1037618Y363465D01*
Y362490D01*
G01Y363465D02*
X1037185Y364114D01*
X1036463Y364656D01*
X1035597Y364872D01*
X1034731Y364656D01*
X1034009Y364114D01*
X1033576Y363140D01*
X1033720Y362166D01*
X1034298Y361191D01*
G01X1036463Y326618D02*
X1034659Y325535D01*
X1033576D01*
Y326347D01*
X1034659D01*
Y325535D01*
G01X1042237Y295437D02*
X1033576D01*
X1035308Y294138D01*
G01X1042237D02*
Y296736D01*
G01X1042526Y304098D02*
X1042381Y303881D01*
X1042093D01*
X1041948Y304098D01*
X1042093Y304315D01*
X1042381D01*
X1042526Y304098D01*
G01X1042237Y314058D02*
X1033576D01*
X1039783Y310052D01*
Y315466D01*
G01X1033576Y321420D02*
X1033865Y320554D01*
X1034586Y319904D01*
X1035452Y319471D01*
X1036607Y319146D01*
X1037907Y319038D01*
X1039206Y319146D01*
X1040361Y319471D01*
X1041227Y319904D01*
X1041948Y320554D01*
X1042237Y321420D01*
X1041948Y322286D01*
X1041227Y322936D01*
X1040361Y323369D01*
X1039206Y323694D01*
X1037907Y323802D01*
X1036607Y323694D01*
X1035452Y323369D01*
X1034586Y322936D01*
X1033865Y322286D01*
X1033576Y321420D01*
G01X1068855Y386512D02*
X1074642Y392956D01*
X1072519Y392535D01*
G01X1067889Y387380D02*
X1069822Y385644D01*
G01X1075107Y380510D02*
X1075042Y380762D01*
X1075235Y380977D01*
X1075492Y380940D01*
X1075557Y380687D01*
X1075364Y380473D01*
X1075107Y380510D01*
G01X1087530Y381382D02*
X1086693Y381746D01*
X1085728Y381643D01*
X1084827Y381288D01*
X1083813Y380645D01*
X1082865Y379751D01*
X1082077Y378712D01*
X1081547Y377636D01*
X1081291Y376702D01*
X1081292Y375731D01*
X1081743Y374938D01*
X1082581Y374574D01*
X1083546Y374677D01*
X1084447Y375032D01*
X1085461Y375674D01*
X1086409Y376568D01*
X1087197Y377607D01*
X1087727Y378683D01*
X1087983Y379617D01*
X1087982Y380588D01*
X1087530Y381382D01*
G01X1093974Y375595D02*
X1093137Y375959D01*
X1092172Y375856D01*
X1091271Y375501D01*
X1090257Y374858D01*
X1089309Y373964D01*
X1088521Y372925D01*
X1087991Y371849D01*
X1087735Y370915D01*
X1087736Y369944D01*
X1088187Y369151D01*
X1089025Y368787D01*
X1089990Y368890D01*
X1090891Y369245D01*
X1091905Y369887D01*
X1092853Y370781D01*
X1093641Y371820D01*
X1094171Y372896D01*
X1094427Y373830D01*
X1094426Y374801D01*
X1093974Y375595D01*
G01X1063377Y391432D02*
X1069165Y397875D01*
X1071178Y396067D01*
X1071533Y395166D01*
X1071550Y394375D01*
X1070940Y393371D01*
X1070007Y392656D01*
X1069042Y392553D01*
X1068188Y392738D01*
X1066174Y394546D01*
G01X1068188Y392738D02*
X1066600Y388538D01*
G01X1074970Y535430D02*
X1075259Y534564D01*
X1075980Y533914D01*
X1076846Y533481D01*
X1078001Y533156D01*
X1079301Y533048D01*
X1080600Y533156D01*
X1081755Y533481D01*
X1082621Y533914D01*
X1083342Y534564D01*
X1083631Y535430D01*
X1083342Y536296D01*
X1082621Y536946D01*
X1081755Y537379D01*
X1080600Y537704D01*
X1079301Y537812D01*
X1078001Y537704D01*
X1076846Y537379D01*
X1075980Y536946D01*
X1075259Y536296D01*
X1074970Y535430D01*
G01X1083920Y544091D02*
X1083775Y543874D01*
X1083487D01*
X1083342Y544091D01*
X1083487Y544308D01*
X1083775D01*
X1083920Y544091D01*
G01X1074970Y552752D02*
X1075259Y551886D01*
X1075980Y551236D01*
X1076846Y550803D01*
X1078001Y550478D01*
X1079301Y550370D01*
X1080600Y550478D01*
X1081755Y550803D01*
X1082621Y551236D01*
X1083342Y551886D01*
X1083631Y552752D01*
X1083342Y553618D01*
X1082621Y554268D01*
X1081755Y554701D01*
X1080600Y555026D01*
X1079301Y555134D01*
X1078001Y555026D01*
X1076846Y554701D01*
X1075980Y554268D01*
X1075259Y553618D01*
X1074970Y552752D01*
G01Y561413D02*
X1075259Y560547D01*
X1075980Y559897D01*
X1076846Y559464D01*
X1078001Y559139D01*
X1079301Y559031D01*
X1080600Y559139D01*
X1081755Y559464D01*
X1082621Y559897D01*
X1083342Y560547D01*
X1083631Y561413D01*
X1083342Y562279D01*
X1082621Y562929D01*
X1081755Y563362D01*
X1080600Y563687D01*
X1079301Y563795D01*
X1078001Y563687D01*
X1076846Y563362D01*
X1075980Y562929D01*
X1075259Y562279D01*
X1074970Y561413D01*
G01X1036881Y595173D02*
X1036015Y594884D01*
X1035365Y594163D01*
X1034932Y593297D01*
X1034607Y592142D01*
X1034499Y590842D01*
X1034607Y589543D01*
X1034932Y588388D01*
X1035365Y587522D01*
X1036015Y586801D01*
X1036881Y586512D01*
X1037747Y586801D01*
X1038397Y587522D01*
X1038830Y588388D01*
X1039155Y589543D01*
X1039263Y590842D01*
X1039155Y592142D01*
X1038830Y593297D01*
X1038397Y594163D01*
X1037747Y594884D01*
X1036881Y595173D01*
G01X1045542Y586223D02*
X1045325Y586368D01*
Y586656D01*
X1045542Y586801D01*
X1045759Y586656D01*
Y586368D01*
X1045542Y586223D01*
G01X1054203Y595173D02*
X1053337Y594884D01*
X1052687Y594163D01*
X1052254Y593297D01*
X1051929Y592142D01*
X1051821Y590842D01*
X1051929Y589543D01*
X1052254Y588388D01*
X1052687Y587522D01*
X1053337Y586801D01*
X1054203Y586512D01*
X1055069Y586801D01*
X1055719Y587522D01*
X1056152Y588388D01*
X1056477Y589543D01*
X1056585Y590842D01*
X1056477Y592142D01*
X1056152Y593297D01*
X1055719Y594163D01*
X1055069Y594884D01*
X1054203Y595173D01*
G01X1062864D02*
X1061998Y594884D01*
X1061348Y594163D01*
X1060915Y593297D01*
X1060590Y592142D01*
X1060482Y590842D01*
X1060590Y589543D01*
X1060915Y588388D01*
X1061348Y587522D01*
X1061998Y586801D01*
X1062864Y586512D01*
X1063730Y586801D01*
X1064380Y587522D01*
X1064813Y588388D01*
X1065138Y589543D01*
X1065246Y590842D01*
X1065138Y592142D01*
X1064813Y593297D01*
X1064380Y594163D01*
X1063730Y594884D01*
X1062864Y595173D01*
G01X1036881Y620370D02*
X1037639Y620514D01*
X1038505Y620947D01*
X1039046Y621669D01*
X1039263Y622680D01*
X1039046Y623690D01*
X1038397Y624556D01*
X1037422Y624989D01*
X1036340D01*
X1035690Y625278D01*
X1035149Y626000D01*
X1034932Y627010D01*
X1035257Y628021D01*
X1036015Y628742D01*
X1036881Y629031D01*
X1037747Y628742D01*
X1038505Y628021D01*
X1038830Y627010D01*
X1038613Y626000D01*
X1038072Y625278D01*
X1037422Y624989D01*
X1036340D01*
X1035365Y624556D01*
X1034716Y623690D01*
X1034499Y622680D01*
X1034716Y621669D01*
X1035257Y620947D01*
X1036123Y620514D01*
X1036881Y620370D01*
G01X1045542Y620081D02*
X1045325Y620226D01*
Y620514D01*
X1045542Y620659D01*
X1045759Y620514D01*
Y620226D01*
X1045542Y620081D01*
G01X1052146Y623979D02*
X1052904Y624989D01*
X1053553Y625567D01*
X1054420Y625855D01*
X1055177Y625567D01*
X1055719Y624989D01*
X1056152Y624123D01*
X1056260Y623113D01*
X1056152Y622246D01*
X1055719Y621380D01*
X1055069Y620659D01*
X1054311Y620370D01*
X1053445Y620659D01*
X1052687Y621525D01*
X1052254Y622824D01*
X1052146Y624267D01*
X1052362Y626144D01*
X1052687Y627155D01*
X1053229Y628165D01*
X1053986Y628887D01*
X1054744Y629031D01*
X1055502Y628742D01*
X1056044Y628021D01*
G01X1062864Y629031D02*
X1061998Y628742D01*
X1061348Y628021D01*
X1060915Y627155D01*
X1060590Y626000D01*
X1060482Y624700D01*
X1060590Y623401D01*
X1060915Y622246D01*
X1061348Y621380D01*
X1061998Y620659D01*
X1062864Y620370D01*
X1063730Y620659D01*
X1064380Y621380D01*
X1064813Y622246D01*
X1065138Y623401D01*
X1065246Y624700D01*
X1065138Y626000D01*
X1064813Y627155D01*
X1064380Y628021D01*
X1063730Y628742D01*
X1062864Y629031D01*
G01X1026163Y700423D02*
X1026813Y701288D01*
X1027570Y701722D01*
X1028437Y701866D01*
X1029519Y701577D01*
X1030277Y700856D01*
X1030494Y699990D01*
X1030385Y699123D01*
X1029952Y698402D01*
X1027787Y696958D01*
X1026813Y695948D01*
X1026163Y694504D01*
X1025946Y693205D01*
X1030494D01*
G01X1036664D02*
X1036881Y695081D01*
X1037206Y696669D01*
X1037639Y698113D01*
X1038180Y699701D01*
X1039046Y701866D01*
X1034716D01*
G01X1045542Y692916D02*
X1045325Y693061D01*
Y693349D01*
X1045542Y693494D01*
X1045759Y693349D01*
Y693061D01*
X1045542Y692916D01*
G01X1054203Y693205D02*
Y701866D01*
X1052904Y700134D01*
G01Y693205D02*
X1055502D01*
G01X1062864Y701866D02*
X1061998Y701577D01*
X1061348Y700856D01*
X1060915Y699990D01*
X1060590Y698835D01*
X1060482Y697535D01*
X1060590Y696236D01*
X1060915Y695081D01*
X1061348Y694215D01*
X1061998Y693494D01*
X1062864Y693205D01*
X1063730Y693494D01*
X1064380Y694215D01*
X1064813Y695081D01*
X1065138Y696236D01*
X1065246Y697535D01*
X1065138Y698835D01*
X1064813Y699990D01*
X1064380Y700856D01*
X1063730Y701577D01*
X1062864Y701866D01*
G01X1026163Y692549D02*
X1026813Y693414D01*
X1027570Y693848D01*
X1028437Y693992D01*
X1029519Y693703D01*
X1030277Y692982D01*
X1030494Y692116D01*
X1030385Y691249D01*
X1029952Y690528D01*
X1027787Y689084D01*
X1026813Y688074D01*
X1026163Y686630D01*
X1025946Y685331D01*
X1030494D01*
G01X1034499Y686630D02*
X1035149Y685908D01*
X1035907Y685475D01*
X1036881Y685331D01*
X1037855Y685620D01*
X1038613Y686197D01*
X1039155Y687207D01*
X1039263Y688362D01*
X1039046Y689517D01*
X1038505Y690239D01*
X1037747Y690816D01*
X1036989Y690961D01*
X1036231Y690816D01*
X1035257Y690239D01*
X1035582Y693992D01*
X1038505D01*
G01X1045542Y685042D02*
X1045325Y685187D01*
Y685475D01*
X1045542Y685620D01*
X1045759Y685475D01*
Y685187D01*
X1045542Y685042D01*
G01X1054203Y685331D02*
Y693992D01*
X1052904Y692260D01*
G01Y685331D02*
X1055502D01*
G01X1062864Y693992D02*
X1061998Y693703D01*
X1061348Y692982D01*
X1060915Y692116D01*
X1060590Y690961D01*
X1060482Y689661D01*
X1060590Y688362D01*
X1060915Y687207D01*
X1061348Y686341D01*
X1061998Y685620D01*
X1062864Y685331D01*
X1063730Y685620D01*
X1064380Y686341D01*
X1064813Y687207D01*
X1065138Y688362D01*
X1065246Y689661D01*
X1065138Y690961D01*
X1064813Y692116D01*
X1064380Y692982D01*
X1063730Y693703D01*
X1062864Y693992D01*
G01X1144661Y-436506D02*
X1145177Y-436998D01*
X1145768Y-437195D01*
X1146358Y-436998D01*
X1146875Y-436408D01*
X1147244Y-435522D01*
X1147392Y-434636D01*
Y-433553D01*
X1147244Y-432667D01*
X1146875Y-431880D01*
X1146432Y-431486D01*
X1145915Y-431289D01*
X1145325Y-431486D01*
X1144882Y-431880D01*
X1144587Y-432470D01*
X1144439Y-433258D01*
X1144587Y-433947D01*
X1144956Y-434636D01*
X1145399Y-435030D01*
X1145915Y-435128D01*
X1146506Y-434931D01*
X1146949Y-434439D01*
X1147392Y-433553D01*
G01X1118154Y283622D02*
X1126120Y290346D01*
X1123057Y292820D01*
X1118154Y283622D01*
G01X1099719Y285637D02*
X1091115Y279753D01*
X1093912Y276981D01*
X1099719Y285637D01*
G01X1087988Y336009D02*
X1089071Y338896D01*
X1090153D01*
X1092319Y333122D01*
X1093401D01*
X1094484Y336009D01*
G01X1133790Y306412D02*
X1127054Y311856D01*
X1127584Y309757D01*
G01X1132973Y305402D02*
X1134606Y307422D01*
G01X1139458Y312967D02*
X1139210Y312889D01*
X1138985Y313070D01*
X1139009Y313329D01*
X1139258Y313407D01*
X1139482Y313226D01*
X1139458Y312967D01*
G01X1137942Y325328D02*
X1137622Y324473D01*
X1137775Y323514D01*
X1138176Y322633D01*
X1138870Y321654D01*
X1139813Y320754D01*
X1140891Y320021D01*
X1141993Y319548D01*
X1142939Y319340D01*
X1143909Y319392D01*
X1144678Y319884D01*
X1144998Y320739D01*
X1144845Y321698D01*
X1144443Y322579D01*
X1143749Y323558D01*
X1142807Y324459D01*
X1141729Y325191D01*
X1140626Y325665D01*
X1139680Y325872D01*
X1138711Y325820D01*
X1137942Y325328D01*
G01X1143386Y332064D02*
X1143066Y331209D01*
X1143219Y330250D01*
X1143620Y329369D01*
X1144314Y328390D01*
X1145257Y327490D01*
X1146335Y326757D01*
X1147437Y326284D01*
X1148383Y326076D01*
X1149353Y326128D01*
X1150122Y326620D01*
X1150442Y327475D01*
X1150289Y328434D01*
X1149887Y329315D01*
X1149193Y330294D01*
X1148251Y331195D01*
X1147173Y331927D01*
X1146070Y332401D01*
X1145124Y332608D01*
X1144155Y332556D01*
X1143386Y332064D01*
G01X1127529Y298665D02*
X1120793Y304109D01*
X1122494Y306214D01*
X1123375Y306616D01*
X1124165Y306674D01*
X1125199Y306116D01*
X1125961Y305222D01*
X1126114Y304263D01*
X1125974Y303401D01*
X1124273Y301296D01*
G01X1125974Y303401D02*
X1130251Y302033D01*
G01X1099561Y356025D02*
X1093261Y364329D01*
X1090630Y361400D01*
X1099561Y356025D01*
G01X1103395Y533048D02*
X1104117Y533698D01*
X1104550Y534456D01*
X1104694Y535430D01*
X1104405Y536404D01*
X1103828Y537162D01*
X1102818Y537704D01*
X1101663Y537812D01*
X1100508Y537595D01*
X1099786Y537054D01*
X1099209Y536296D01*
X1099064Y535538D01*
X1099209Y534780D01*
X1099786Y533806D01*
X1096033Y534131D01*
Y537054D01*
G01X1104983Y544091D02*
X1104838Y543874D01*
X1104550D01*
X1104405Y544091D01*
X1104550Y544308D01*
X1104838D01*
X1104983Y544091D01*
G01X1102962Y550370D02*
X1103972Y551020D01*
X1104550Y551886D01*
X1104694Y552860D01*
X1104550Y553726D01*
X1103828Y554593D01*
X1102962Y555134D01*
X1102096Y555242D01*
X1101085Y555026D01*
X1100364Y554268D01*
X1100075Y553510D01*
Y552535D01*
G01Y553510D02*
X1099642Y554159D01*
X1098920Y554701D01*
X1098054Y554917D01*
X1097188Y554701D01*
X1096466Y554159D01*
X1096033Y553185D01*
X1096177Y552211D01*
X1096755Y551236D01*
G01X1103395Y559031D02*
X1104117Y559681D01*
X1104550Y560439D01*
X1104694Y561413D01*
X1104405Y562387D01*
X1103828Y563145D01*
X1102818Y563687D01*
X1101663Y563795D01*
X1100508Y563578D01*
X1099786Y563037D01*
X1099209Y562279D01*
X1099064Y561521D01*
X1099209Y560763D01*
X1099786Y559789D01*
X1096033Y560114D01*
Y563037D01*
G01X1144661Y924124D02*
X1145177Y923632D01*
X1145768Y923435D01*
X1146358Y923632D01*
X1146875Y924222D01*
X1147244Y925108D01*
X1147392Y925994D01*
Y927077D01*
X1147244Y927963D01*
X1146875Y928750D01*
X1146432Y929144D01*
X1145915Y929341D01*
X1145325Y929144D01*
X1144882Y928750D01*
X1144587Y928160D01*
X1144439Y927372D01*
X1144587Y926683D01*
X1144956Y925994D01*
X1145399Y925600D01*
X1145915Y925502D01*
X1146506Y925699D01*
X1146949Y926191D01*
X1147392Y927077D01*
G01X1200389Y-272437D02*
Y-292437D01*
G01X1194639Y-272437D02*
X1206139D01*
G01X1216139Y-292437D02*
Y-272437D01*
G01Y-282103D02*
X1217389Y-280437D01*
X1218639Y-279437D01*
X1220639Y-279104D01*
X1222139Y-279437D01*
X1223889Y-280770D01*
X1224639Y-282771D01*
Y-292437D01*
G01X1240389Y-279104D02*
Y-292437D01*
G01Y-273771D02*
X1239889Y-273437D01*
Y-272770D01*
X1240389Y-272437D01*
X1240889Y-272770D01*
Y-273437D01*
X1240389Y-273771D01*
G01X1264389Y-280770D02*
X1262639Y-279437D01*
X1261139Y-279104D01*
X1259139Y-279771D01*
X1257639Y-281104D01*
X1256639Y-283437D01*
X1256389Y-285771D01*
X1256639Y-288104D01*
X1257639Y-290104D01*
X1259139Y-291770D01*
X1261139Y-292437D01*
X1262889Y-291770D01*
X1264389Y-290437D01*
G01X1276139Y-292437D02*
Y-272437D01*
G01X1284139Y-279104D02*
X1276139Y-286770D01*
G01X1279389Y-283770D02*
X1284639Y-292437D01*
G01X1296139D02*
Y-279104D01*
G01Y-282437D02*
X1297139Y-280770D01*
X1298639Y-279437D01*
X1300639Y-279104D01*
X1302389Y-279437D01*
X1303889Y-280770D01*
X1304639Y-283104D01*
Y-292437D01*
G01X1316639Y-283437D02*
X1324639D01*
X1323889Y-281104D01*
X1322639Y-279771D01*
X1320889Y-279104D01*
X1319139Y-279437D01*
X1317639Y-280437D01*
X1316639Y-282771D01*
X1316139Y-284771D01*
Y-286770D01*
X1316639Y-288771D01*
X1317889Y-290771D01*
X1319389Y-292104D01*
X1321139Y-292437D01*
X1322889Y-291770D01*
X1324639Y-289771D01*
G01X1336639Y-290104D02*
X1337889Y-291437D01*
X1339639Y-292437D01*
X1341139D01*
X1342639Y-291770D01*
X1343639Y-290771D01*
X1344139Y-289438D01*
X1343889Y-287437D01*
X1342889Y-286437D01*
X1338389Y-284437D01*
X1337389Y-282103D01*
X1337889Y-280437D01*
X1338889Y-279437D01*
X1340389Y-279104D01*
X1341889Y-279437D01*
X1343389Y-280437D01*
G01X1356639Y-290104D02*
X1357889Y-291437D01*
X1359639Y-292437D01*
X1361139D01*
X1362639Y-291770D01*
X1363639Y-290771D01*
X1364139Y-289438D01*
X1363889Y-287437D01*
X1362889Y-286437D01*
X1358389Y-284437D01*
X1357389Y-282103D01*
X1357889Y-280437D01*
X1358889Y-279437D01*
X1360389Y-279104D01*
X1361889Y-279437D01*
X1363389Y-280437D01*
G01X1156549Y487688D02*
X1155899Y488121D01*
X1155141Y488410D01*
X1154275D01*
X1153301Y487977D01*
X1152543Y487255D01*
X1152002Y486389D01*
X1151568Y484946D01*
X1151460Y483646D01*
X1151677Y482347D01*
X1152002Y481481D01*
X1152651Y480615D01*
X1153409Y480038D01*
X1154167Y479749D01*
X1154925D01*
X1155683Y480038D01*
X1156332Y480471D01*
X1156874Y481048D01*
G01X1162828Y479749D02*
X1161962Y479893D01*
X1161204Y480471D01*
X1160554Y481337D01*
X1160121Y482347D01*
X1159905Y483502D01*
Y484657D01*
X1160121Y485812D01*
X1160554Y486822D01*
X1161204Y487688D01*
X1161962Y488266D01*
X1162828Y488410D01*
X1163694Y488266D01*
X1164452Y487688D01*
X1165102Y486822D01*
X1165535Y485812D01*
X1165751Y484657D01*
Y483502D01*
X1165535Y482347D01*
X1165102Y481337D01*
X1164452Y480471D01*
X1163694Y479893D01*
X1162828Y479749D01*
G01X1168674D02*
Y488410D01*
X1171489Y481192D01*
X1174304Y488410D01*
Y479749D01*
G01X1177985D02*
Y488410D01*
X1180583D01*
X1181449Y487977D01*
X1182099Y486967D01*
X1182315Y485812D01*
X1182099Y484657D01*
X1181557Y483791D01*
X1180583Y483358D01*
X1177985D01*
G01X1188811Y479749D02*
X1187945Y479893D01*
X1187187Y480471D01*
X1186537Y481337D01*
X1186104Y482347D01*
X1185888Y483502D01*
Y484657D01*
X1186104Y485812D01*
X1186537Y486822D01*
X1187187Y487688D01*
X1187945Y488266D01*
X1188811Y488410D01*
X1189677Y488266D01*
X1190435Y487688D01*
X1191085Y486822D01*
X1191518Y485812D01*
X1191734Y484657D01*
Y483502D01*
X1191518Y482347D01*
X1191085Y481337D01*
X1190435Y480471D01*
X1189677Y479893D01*
X1188811Y479749D01*
G01X1194982D02*
Y488410D01*
X1199962Y479749D01*
Y488410D01*
G01X1208298Y479749D02*
X1203968D01*
Y488410D01*
X1208298D01*
G01X1206566Y484224D02*
X1203968D01*
G01X1212304Y479749D02*
Y488410D01*
X1217284Y479749D01*
Y488410D01*
G01X1223455D02*
Y479749D01*
G01X1220965Y488410D02*
X1225945D01*
G01X1238503Y480904D02*
X1239370Y480182D01*
X1240344Y479749D01*
X1241210D01*
X1242076Y480182D01*
X1242726Y480904D01*
X1243051Y481914D01*
X1242834Y482925D01*
X1242293Y483791D01*
X1241318Y484368D01*
X1240019Y484657D01*
X1239261Y485234D01*
X1238936Y486245D01*
X1239153Y487255D01*
X1239694Y487977D01*
X1240452Y488410D01*
X1241210D01*
X1241968Y488121D01*
X1242618Y487400D01*
G01X1248139Y488410D02*
X1250737D01*
G01X1249438D02*
Y479749D01*
G01X1248139D02*
X1250737D01*
G01X1255717D02*
Y488410D01*
X1257882D01*
X1258749Y487977D01*
X1259398Y487400D01*
X1259940Y486534D01*
X1260373Y485523D01*
X1260481Y484079D01*
X1260373Y482636D01*
X1259940Y481625D01*
X1259398Y480759D01*
X1258749Y480182D01*
X1257882Y479749D01*
X1255717D01*
G01X1268925D02*
X1264595D01*
Y488410D01*
X1268925D01*
G01X1267193Y484224D02*
X1264595D01*
G01X1281808Y480904D02*
X1282675Y480182D01*
X1283649Y479749D01*
X1284515D01*
X1285381Y480182D01*
X1286031Y480904D01*
X1286356Y481914D01*
X1286139Y482925D01*
X1285598Y483791D01*
X1284623Y484368D01*
X1283324Y484657D01*
X1282566Y485234D01*
X1282241Y486245D01*
X1282458Y487255D01*
X1282999Y487977D01*
X1283757Y488410D01*
X1284515D01*
X1285273Y488121D01*
X1285923Y487400D01*
G01X1295125Y487688D02*
X1294475Y488121D01*
X1293717Y488410D01*
X1292851D01*
X1291877Y487977D01*
X1291119Y487255D01*
X1290578Y486389D01*
X1290144Y484946D01*
X1290036Y483646D01*
X1290253Y482347D01*
X1290578Y481481D01*
X1291227Y480615D01*
X1291985Y480038D01*
X1292743Y479749D01*
X1293501D01*
X1294259Y480038D01*
X1294908Y480471D01*
X1295450Y481048D01*
G01X1298697Y479749D02*
X1301404Y488410D01*
X1304111Y479749D01*
G01X1303136Y482780D02*
X1299672D01*
G01X1307900Y488410D02*
Y479749D01*
X1312230D01*
G01X1320891D02*
X1316561D01*
Y488410D01*
X1320891D01*
G01X1319159Y484224D02*
X1316561D01*
G01X1336048Y479749D02*
Y488410D01*
X1334749Y486678D01*
G01Y479749D02*
X1337347D01*
G01X1344709Y479460D02*
X1344492Y479605D01*
Y479893D01*
X1344709Y480038D01*
X1344926Y479893D01*
Y479605D01*
X1344709Y479460D01*
G01Y483358D02*
X1344492Y483502D01*
Y483791D01*
X1344709Y483935D01*
X1344926Y483791D01*
Y483502D01*
X1344709Y483358D01*
G01X1353370Y479749D02*
Y488410D01*
X1352071Y486678D01*
G01Y479749D02*
X1354669D01*
G01X1237463Y-341145D02*
Y-321145D01*
X1242463D01*
X1244463Y-322145D01*
X1245963Y-323478D01*
X1247213Y-325478D01*
X1248213Y-327812D01*
X1248463Y-331145D01*
X1248213Y-334479D01*
X1247213Y-336812D01*
X1245963Y-338812D01*
X1244463Y-340145D01*
X1242463Y-341145D01*
X1237463D01*
G01X1267463D02*
Y-327812D01*
G01Y-330145D02*
X1266463Y-328812D01*
X1264963Y-328145D01*
X1263213Y-327812D01*
X1261463Y-328479D01*
X1259963Y-329812D01*
X1258963Y-331812D01*
X1258463Y-334479D01*
X1258963Y-337145D01*
X1259963Y-339145D01*
X1261463Y-340478D01*
X1263213Y-341145D01*
X1264963Y-340812D01*
X1266463Y-339812D01*
X1267463Y-338479D01*
G01X1282963Y-321145D02*
Y-341145D01*
G01X1279463Y-327812D02*
X1286463D01*
G01X1299213Y-332145D02*
X1307213D01*
X1306463Y-329812D01*
X1305213Y-328479D01*
X1303463Y-327812D01*
X1301713Y-328145D01*
X1300213Y-329145D01*
X1299213Y-331479D01*
X1298713Y-333479D01*
Y-335478D01*
X1299213Y-337479D01*
X1300463Y-339479D01*
X1301963Y-340812D01*
X1303713Y-341145D01*
X1305463Y-340478D01*
X1307213Y-338479D01*
G01X1213243Y171911D02*
X1214110Y171189D01*
X1215084Y170756D01*
X1215950D01*
X1216816Y171189D01*
X1217466Y171911D01*
X1217791Y172921D01*
X1217574Y173932D01*
X1217033Y174798D01*
X1216058Y175375D01*
X1214759Y175664D01*
X1214001Y176241D01*
X1213676Y177252D01*
X1213893Y178262D01*
X1214434Y178984D01*
X1215192Y179417D01*
X1215950D01*
X1216708Y179128D01*
X1217358Y178407D01*
G01X1224178Y170756D02*
X1223312Y170900D01*
X1222554Y171478D01*
X1221904Y172344D01*
X1221471Y173354D01*
X1221255Y174509D01*
Y175664D01*
X1221471Y176819D01*
X1221904Y177829D01*
X1222554Y178695D01*
X1223312Y179273D01*
X1224178Y179417D01*
X1225044Y179273D01*
X1225802Y178695D01*
X1226452Y177829D01*
X1226885Y176819D01*
X1227101Y175664D01*
Y174509D01*
X1226885Y173354D01*
X1226452Y172344D01*
X1225802Y171478D01*
X1225044Y170900D01*
X1224178Y170756D01*
G01X1230674Y179417D02*
Y170756D01*
X1235004D01*
G01X1239118D02*
Y179417D01*
X1241283D01*
X1242150Y178984D01*
X1242799Y178407D01*
X1243341Y177541D01*
X1243774Y176530D01*
X1243882Y175086D01*
X1243774Y173643D01*
X1243341Y172632D01*
X1242799Y171766D01*
X1242150Y171189D01*
X1241283Y170756D01*
X1239118D01*
G01X1252326D02*
X1247996D01*
Y179417D01*
X1252326D01*
G01X1250594Y175231D02*
X1247996D01*
G01X1256657Y170756D02*
Y179417D01*
X1259363D01*
X1260229Y178984D01*
X1260771Y178407D01*
X1260987Y177252D01*
X1260771Y176097D01*
X1260121Y175375D01*
X1259363Y174942D01*
X1256657D01*
G01X1259363D02*
X1260987Y170756D01*
G01X1273870Y171911D02*
X1274737Y171189D01*
X1275711Y170756D01*
X1276577D01*
X1277443Y171189D01*
X1278093Y171911D01*
X1278418Y172921D01*
X1278201Y173932D01*
X1277660Y174798D01*
X1276685Y175375D01*
X1275386Y175664D01*
X1274628Y176241D01*
X1274303Y177252D01*
X1274520Y178262D01*
X1275061Y178984D01*
X1275819Y179417D01*
X1276577D01*
X1277335Y179128D01*
X1277985Y178407D01*
G01X1283506Y179417D02*
X1286104D01*
G01X1284805D02*
Y170756D01*
G01X1283506D02*
X1286104D01*
G01X1291084D02*
Y179417D01*
X1293249D01*
X1294116Y178984D01*
X1294765Y178407D01*
X1295307Y177541D01*
X1295740Y176530D01*
X1295848Y175086D01*
X1295740Y173643D01*
X1295307Y172632D01*
X1294765Y171766D01*
X1294116Y171189D01*
X1293249Y170756D01*
X1291084D01*
G01X1304292D02*
X1299962D01*
Y179417D01*
X1304292D01*
G01X1302560Y175231D02*
X1299962D01*
G01X1317175Y171911D02*
X1318042Y171189D01*
X1319016Y170756D01*
X1319882D01*
X1320748Y171189D01*
X1321398Y171911D01*
X1321723Y172921D01*
X1321506Y173932D01*
X1320965Y174798D01*
X1319990Y175375D01*
X1318691Y175664D01*
X1317933Y176241D01*
X1317608Y177252D01*
X1317825Y178262D01*
X1318366Y178984D01*
X1319124Y179417D01*
X1319882D01*
X1320640Y179128D01*
X1321290Y178407D01*
G01X1330492Y178695D02*
X1329842Y179128D01*
X1329084Y179417D01*
X1328218D01*
X1327244Y178984D01*
X1326486Y178262D01*
X1325945Y177396D01*
X1325511Y175953D01*
X1325403Y174653D01*
X1325620Y173354D01*
X1325945Y172488D01*
X1326594Y171622D01*
X1327352Y171045D01*
X1328110Y170756D01*
X1328868D01*
X1329626Y171045D01*
X1330275Y171478D01*
X1330817Y172055D01*
G01X1334064Y170756D02*
X1336771Y179417D01*
X1339478Y170756D01*
G01X1338503Y173787D02*
X1335039D01*
G01X1343267Y179417D02*
Y170756D01*
X1347597D01*
G01X1356258D02*
X1351928D01*
Y179417D01*
X1356258D01*
G01X1354526Y175231D02*
X1351928D01*
G01X1371415Y170756D02*
Y179417D01*
X1370116Y177685D01*
G01Y170756D02*
X1372714D01*
G01X1380076Y170467D02*
X1379859Y170612D01*
Y170900D01*
X1380076Y171045D01*
X1380293Y170900D01*
Y170612D01*
X1380076Y170467D01*
G01Y174365D02*
X1379859Y174509D01*
Y174798D01*
X1380076Y174942D01*
X1380293Y174798D01*
Y174509D01*
X1380076Y174365D01*
G01X1388737Y170756D02*
Y179417D01*
X1387438Y177685D01*
G01Y170756D02*
X1390036D01*
G01X1229537Y711590D02*
X1230547Y712240D01*
X1231125Y713106D01*
X1231269Y714080D01*
X1231125Y714946D01*
X1230403Y715813D01*
X1229537Y716354D01*
X1228671Y716462D01*
X1227660Y716246D01*
X1226939Y715488D01*
X1226650Y714730D01*
Y713755D01*
G01Y714730D02*
X1226217Y715379D01*
X1225495Y715921D01*
X1224629Y716137D01*
X1223763Y715921D01*
X1223041Y715379D01*
X1222608Y714405D01*
X1222752Y713431D01*
X1223330Y712456D01*
G01X1231269Y722416D02*
X1229393Y722633D01*
X1227805Y722958D01*
X1226361Y723391D01*
X1224773Y723932D01*
X1222608Y724798D01*
Y720468D01*
G01X1231558Y731294D02*
X1231413Y731077D01*
X1231125D01*
X1230980Y731294D01*
X1231125Y731511D01*
X1231413D01*
X1231558Y731294D01*
G01X1229970Y737573D02*
X1230692Y738223D01*
X1231125Y738981D01*
X1231269Y739955D01*
X1230980Y740929D01*
X1230403Y741687D01*
X1229393Y742229D01*
X1228238Y742337D01*
X1227083Y742120D01*
X1226361Y741579D01*
X1225784Y740821D01*
X1225639Y740063D01*
X1225784Y739305D01*
X1226361Y738331D01*
X1222608Y738656D01*
Y741579D01*
G01Y748616D02*
X1222897Y747750D01*
X1223618Y747100D01*
X1224484Y746667D01*
X1225639Y746342D01*
X1226939Y746234D01*
X1228238Y746342D01*
X1229393Y746667D01*
X1230259Y747100D01*
X1230980Y747750D01*
X1231269Y748616D01*
X1230980Y749482D01*
X1230259Y750132D01*
X1229393Y750565D01*
X1228238Y750890D01*
X1226939Y750998D01*
X1225639Y750890D01*
X1224484Y750565D01*
X1223618Y750132D01*
X1222897Y749482D01*
X1222608Y748616D01*
G01X1319143Y-437195D02*
Y-431289D01*
X1318258Y-432470D01*
G01Y-437195D02*
X1320029D01*
G01X1325048Y-431289D02*
X1324458Y-431486D01*
X1324015Y-431978D01*
X1323720Y-432569D01*
X1323498Y-433356D01*
X1323425Y-434242D01*
X1323498Y-435128D01*
X1323720Y-435915D01*
X1324015Y-436506D01*
X1324458Y-436998D01*
X1325048Y-437195D01*
X1325639Y-436998D01*
X1326082Y-436506D01*
X1326377Y-435915D01*
X1326599Y-435128D01*
X1326672Y-434242D01*
X1326599Y-433356D01*
X1326377Y-432569D01*
X1326082Y-431978D01*
X1325639Y-431486D01*
X1325048Y-431289D01*
G01X1316546Y290402D02*
X1314578Y280166D01*
X1318515D01*
X1316546Y290402D01*
G01X1313082Y317530D02*
X1313804Y318180D01*
X1314237Y318938D01*
X1314381Y319912D01*
X1314092Y320886D01*
X1313515Y321644D01*
X1312505Y322186D01*
X1311350Y322294D01*
X1310195Y322077D01*
X1309473Y321536D01*
X1308896Y320778D01*
X1308751Y320020D01*
X1308896Y319262D01*
X1309473Y318288D01*
X1305720Y318613D01*
Y321536D01*
G01X1314670Y328573D02*
X1314525Y328356D01*
X1314237D01*
X1314092Y328573D01*
X1314237Y328790D01*
X1314525D01*
X1314670Y328573D01*
G01X1305720Y337234D02*
X1306009Y336368D01*
X1306730Y335718D01*
X1307596Y335285D01*
X1308751Y334960D01*
X1310051Y334852D01*
X1311350Y334960D01*
X1312505Y335285D01*
X1313371Y335718D01*
X1314092Y336368D01*
X1314381Y337234D01*
X1314092Y338100D01*
X1313371Y338750D01*
X1312505Y339183D01*
X1311350Y339508D01*
X1310051Y339616D01*
X1308751Y339508D01*
X1307596Y339183D01*
X1306730Y338750D01*
X1306009Y338100D01*
X1305720Y337234D01*
G01Y345895D02*
X1306009Y345029D01*
X1306730Y344379D01*
X1307596Y343946D01*
X1308751Y343621D01*
X1310051Y343513D01*
X1311350Y343621D01*
X1312505Y343946D01*
X1313371Y344379D01*
X1314092Y345029D01*
X1314381Y345895D01*
X1314092Y346761D01*
X1313371Y347411D01*
X1312505Y347844D01*
X1311350Y348169D01*
X1310051Y348277D01*
X1308751Y348169D01*
X1307596Y347844D01*
X1306730Y347411D01*
X1306009Y346761D01*
X1305720Y345895D01*
G01X1316546Y310087D02*
X1318515Y320324D01*
X1314578D01*
X1316546Y310087D01*
G01X1303948Y367580D02*
X1304598Y366858D01*
X1305356Y366425D01*
X1306330Y366281D01*
X1307304Y366570D01*
X1308062Y367147D01*
X1308604Y368157D01*
X1308712Y369312D01*
X1308495Y370467D01*
X1307954Y371189D01*
X1307196Y371766D01*
X1306438Y371911D01*
X1305680Y371766D01*
X1304706Y371189D01*
X1305031Y374942D01*
X1307954D01*
G01X1314991Y365992D02*
X1314774Y366137D01*
Y366425D01*
X1314991Y366570D01*
X1315208Y366425D01*
Y366137D01*
X1314991Y365992D01*
G01X1323652Y374942D02*
X1322786Y374653D01*
X1322136Y373932D01*
X1321703Y373066D01*
X1321378Y371911D01*
X1321270Y370611D01*
X1321378Y369312D01*
X1321703Y368157D01*
X1322136Y367291D01*
X1322786Y366570D01*
X1323652Y366281D01*
X1324518Y366570D01*
X1325168Y367291D01*
X1325601Y368157D01*
X1325926Y369312D01*
X1326034Y370611D01*
X1325926Y371911D01*
X1325601Y373066D01*
X1325168Y373932D01*
X1324518Y374653D01*
X1323652Y374942D01*
G01X1332313D02*
X1331447Y374653D01*
X1330797Y373932D01*
X1330364Y373066D01*
X1330039Y371911D01*
X1329931Y370611D01*
X1330039Y369312D01*
X1330364Y368157D01*
X1330797Y367291D01*
X1331447Y366570D01*
X1332313Y366281D01*
X1333179Y366570D01*
X1333829Y367291D01*
X1334262Y368157D01*
X1334587Y369312D01*
X1334695Y370611D01*
X1334587Y371911D01*
X1334262Y373066D01*
X1333829Y373932D01*
X1333179Y374653D01*
X1332313Y374942D01*
G01X1308710Y711590D02*
X1309432Y712240D01*
X1309865Y712998D01*
X1310009Y713972D01*
X1309720Y714946D01*
X1309143Y715704D01*
X1308133Y716246D01*
X1306978Y716354D01*
X1305823Y716137D01*
X1305101Y715596D01*
X1304524Y714838D01*
X1304379Y714080D01*
X1304524Y713322D01*
X1305101Y712348D01*
X1301348Y712673D01*
Y715596D01*
G01X1310009Y722416D02*
X1308133Y722633D01*
X1306545Y722958D01*
X1305101Y723391D01*
X1303513Y723932D01*
X1301348Y724798D01*
Y720468D01*
G01X1310298Y731294D02*
X1310153Y731077D01*
X1309865D01*
X1309720Y731294D01*
X1309865Y731511D01*
X1310153D01*
X1310298Y731294D01*
G01X1308710Y737573D02*
X1309432Y738223D01*
X1309865Y738981D01*
X1310009Y739955D01*
X1309720Y740929D01*
X1309143Y741687D01*
X1308133Y742229D01*
X1306978Y742337D01*
X1305823Y742120D01*
X1305101Y741579D01*
X1304524Y740821D01*
X1304379Y740063D01*
X1304524Y739305D01*
X1305101Y738331D01*
X1301348Y738656D01*
Y741579D01*
G01Y748616D02*
X1301637Y747750D01*
X1302358Y747100D01*
X1303224Y746667D01*
X1304379Y746342D01*
X1305679Y746234D01*
X1306978Y746342D01*
X1308133Y746667D01*
X1308999Y747100D01*
X1309720Y747750D01*
X1310009Y748616D01*
X1309720Y749482D01*
X1308999Y750132D01*
X1308133Y750565D01*
X1306978Y750890D01*
X1305679Y750998D01*
X1304379Y750890D01*
X1303224Y750565D01*
X1302358Y750132D01*
X1301637Y749482D01*
X1301348Y748616D01*
G01X1319143Y923435D02*
Y929341D01*
X1318258Y928160D01*
G01Y923435D02*
X1320029D01*
G01X1325048Y929341D02*
X1324458Y929144D01*
X1324015Y928652D01*
X1323720Y928061D01*
X1323498Y927274D01*
X1323425Y926388D01*
X1323498Y925502D01*
X1323720Y924715D01*
X1324015Y924124D01*
X1324458Y923632D01*
X1325048Y923435D01*
X1325639Y923632D01*
X1326082Y924124D01*
X1326377Y924715D01*
X1326599Y925502D01*
X1326672Y926388D01*
X1326599Y927274D01*
X1326377Y928061D01*
X1326082Y928652D01*
X1325639Y929144D01*
X1325048Y929341D01*
G01X1395645Y337908D02*
X1389287Y343789D01*
X1389676Y341659D01*
G01X1394763Y336955D02*
X1396527Y338862D01*
G01X1401738Y344070D02*
X1401485Y344010D01*
X1401273Y344205D01*
X1401314Y344462D01*
X1401567Y344523D01*
X1401779Y344328D01*
X1401738Y344070D01*
G01X1401049Y356505D02*
X1400673Y355673D01*
X1400762Y354706D01*
X1401103Y353800D01*
X1401731Y352778D01*
X1402611Y351816D01*
X1403638Y351014D01*
X1404707Y350468D01*
X1405637Y350198D01*
X1406607Y350185D01*
X1407407Y350624D01*
X1407784Y351456D01*
X1407695Y352423D01*
X1407353Y353329D01*
X1406726Y354352D01*
X1405846Y355313D01*
X1404818Y356116D01*
X1403750Y356662D01*
X1402820Y356932D01*
X1401849Y356945D01*
X1401049Y356505D01*
G01X1406930Y362863D02*
X1406554Y362031D01*
X1406643Y361064D01*
X1406984Y360158D01*
X1407612Y359136D01*
X1408492Y358174D01*
X1409519Y357372D01*
X1410588Y356826D01*
X1411518Y356556D01*
X1412488Y356543D01*
X1413288Y356982D01*
X1413665Y357814D01*
X1413576Y358781D01*
X1413234Y359687D01*
X1412607Y360710D01*
X1411727Y361671D01*
X1410699Y362474D01*
X1409631Y363020D01*
X1408701Y363290D01*
X1407730Y363303D01*
X1406930Y362863D01*
G01X1388881Y330596D02*
X1382523Y336477D01*
X1384360Y338464D01*
X1385267Y338805D01*
X1386058Y338811D01*
X1387053Y338186D01*
X1387754Y337243D01*
X1387842Y336276D01*
X1387646Y335425D01*
X1385808Y333438D01*
G01X1387646Y335425D02*
X1391822Y333775D01*
G01X1371896Y309041D02*
X1380291Y315219D01*
X1377401Y317892D01*
X1371896Y309041D01*
G01X1353475Y364115D02*
X1343239Y366084D01*
Y362147D01*
X1353475Y364115D01*
G01X1373160D02*
X1383396Y362147D01*
Y366084D01*
X1373160Y364115D01*
G01X1388750Y526552D02*
X1386874Y526769D01*
X1385286Y527094D01*
X1383842Y527527D01*
X1382254Y528068D01*
X1380089Y528934D01*
Y524604D01*
G01X1388750Y535213D02*
X1386874Y535430D01*
X1385286Y535755D01*
X1383842Y536188D01*
X1382254Y536729D01*
X1380089Y537595D01*
Y533265D01*
G01X1389039Y544091D02*
X1388894Y543874D01*
X1388606D01*
X1388461Y544091D01*
X1388606Y544308D01*
X1388894D01*
X1389039Y544091D01*
G01X1387451Y550370D02*
X1388173Y551020D01*
X1388606Y551778D01*
X1388750Y552752D01*
X1388461Y553726D01*
X1387884Y554484D01*
X1386874Y555026D01*
X1385719Y555134D01*
X1384564Y554917D01*
X1383842Y554376D01*
X1383265Y553618D01*
X1383120Y552860D01*
X1383265Y552102D01*
X1383842Y551128D01*
X1380089Y551453D01*
Y554376D01*
G01Y561413D02*
X1380378Y560547D01*
X1381099Y559897D01*
X1381965Y559464D01*
X1383120Y559139D01*
X1384420Y559031D01*
X1385719Y559139D01*
X1386874Y559464D01*
X1387740Y559897D01*
X1388461Y560547D01*
X1388750Y561413D01*
X1388461Y562279D01*
X1387740Y562929D01*
X1386874Y563362D01*
X1385719Y563687D01*
X1384420Y563795D01*
X1383120Y563687D01*
X1381965Y563362D01*
X1381099Y562929D01*
X1380378Y562279D01*
X1380089Y561413D01*
G01X1344786Y711915D02*
X1343776Y712673D01*
X1343198Y713322D01*
X1342910Y714189D01*
X1343198Y714946D01*
X1343776Y715488D01*
X1344642Y715921D01*
X1345652Y716029D01*
X1346519Y715921D01*
X1347385Y715488D01*
X1348106Y714838D01*
X1348395Y714080D01*
X1348106Y713214D01*
X1347240Y712456D01*
X1345941Y712023D01*
X1344498Y711915D01*
X1342621Y712131D01*
X1341610Y712456D01*
X1340600Y712998D01*
X1339878Y713755D01*
X1339734Y714513D01*
X1340023Y715271D01*
X1340744Y715813D01*
G01X1348395Y722416D02*
X1346519Y722633D01*
X1344931Y722958D01*
X1343487Y723391D01*
X1341899Y723932D01*
X1339734Y724798D01*
Y720468D01*
G01X1348684Y731294D02*
X1348539Y731077D01*
X1348251D01*
X1348106Y731294D01*
X1348251Y731511D01*
X1348539D01*
X1348684Y731294D01*
G01X1341177Y737898D02*
X1340312Y738548D01*
X1339878Y739305D01*
X1339734Y740172D01*
X1340023Y741254D01*
X1340744Y742012D01*
X1341610Y742229D01*
X1342477Y742120D01*
X1343198Y741687D01*
X1344642Y739522D01*
X1345652Y738548D01*
X1347096Y737898D01*
X1348395Y737681D01*
Y742229D01*
G01X1347096Y746234D02*
X1347818Y746884D01*
X1348251Y747642D01*
X1348395Y748616D01*
X1348106Y749590D01*
X1347529Y750348D01*
X1346519Y750890D01*
X1345364Y750998D01*
X1344209Y750781D01*
X1343487Y750240D01*
X1342910Y749482D01*
X1342765Y748724D01*
X1342910Y747966D01*
X1343487Y746992D01*
X1339734Y747317D01*
Y750240D01*
G01X1374380Y713755D02*
X1372504Y713972D01*
X1370916Y714297D01*
X1369472Y714730D01*
X1367884Y715271D01*
X1365719Y716137D01*
Y711807D01*
G01X1372648Y720251D02*
X1373658Y720901D01*
X1374236Y721767D01*
X1374380Y722741D01*
X1374236Y723607D01*
X1373514Y724474D01*
X1372648Y725015D01*
X1371782Y725123D01*
X1370771Y724907D01*
X1370050Y724149D01*
X1369761Y723391D01*
Y722416D01*
G01Y723391D02*
X1369328Y724040D01*
X1368606Y724582D01*
X1367740Y724798D01*
X1366874Y724582D01*
X1366152Y724040D01*
X1365719Y723066D01*
X1365863Y722092D01*
X1366441Y721117D01*
G01X1374669Y731294D02*
X1374524Y731077D01*
X1374236D01*
X1374091Y731294D01*
X1374236Y731511D01*
X1374524D01*
X1374669Y731294D01*
G01X1374380Y739955D02*
X1374236Y740713D01*
X1373803Y741579D01*
X1373081Y742120D01*
X1372070Y742337D01*
X1371060Y742120D01*
X1370194Y741471D01*
X1369761Y740496D01*
Y739414D01*
X1369472Y738764D01*
X1368750Y738223D01*
X1367740Y738006D01*
X1366729Y738331D01*
X1366008Y739089D01*
X1365719Y739955D01*
X1366008Y740821D01*
X1366729Y741579D01*
X1367740Y741904D01*
X1368750Y741687D01*
X1369472Y741146D01*
X1369761Y740496D01*
Y739414D01*
X1370194Y738439D01*
X1371060Y737790D01*
X1372070Y737573D01*
X1373081Y737790D01*
X1373803Y738331D01*
X1374236Y739197D01*
X1374380Y739955D01*
G01X1373081Y746234D02*
X1373803Y746884D01*
X1374236Y747642D01*
X1374380Y748616D01*
X1374091Y749590D01*
X1373514Y750348D01*
X1372504Y750890D01*
X1371349Y750998D01*
X1370194Y750781D01*
X1369472Y750240D01*
X1368895Y749482D01*
X1368750Y748724D01*
X1368895Y747966D01*
X1369472Y746992D01*
X1365719Y747317D01*
Y750240D01*
G01X1401694Y-322503D02*
X1403194Y-320504D01*
X1404944Y-319503D01*
X1406944Y-319170D01*
X1409444Y-319837D01*
X1411194Y-321503D01*
X1411694Y-323503D01*
X1411444Y-325504D01*
X1410444Y-327170D01*
X1405444Y-330503D01*
X1403194Y-332837D01*
X1401694Y-336171D01*
X1401194Y-339170D01*
X1411694D01*
G01X1426444Y-319170D02*
X1424444Y-319837D01*
X1422944Y-321503D01*
X1421944Y-323503D01*
X1421194Y-326170D01*
X1420944Y-329170D01*
X1421194Y-332170D01*
X1421944Y-334837D01*
X1422944Y-336837D01*
X1424444Y-338503D01*
X1426444Y-339170D01*
X1428444Y-338503D01*
X1429944Y-336837D01*
X1430944Y-334837D01*
X1431694Y-332170D01*
X1431944Y-329170D01*
X1431694Y-326170D01*
X1430944Y-323503D01*
X1429944Y-321503D01*
X1428444Y-319837D01*
X1426444Y-319170D01*
G01X1446444Y-339170D02*
Y-319170D01*
X1443444Y-323170D01*
G01Y-339170D02*
X1449444D01*
G01X1460944Y-335170D02*
X1462444Y-337504D01*
X1464444Y-338837D01*
X1466694Y-339170D01*
X1468694Y-338837D01*
X1470694Y-337170D01*
X1471944Y-335170D01*
X1472194Y-333170D01*
X1471694Y-330837D01*
X1469944Y-329170D01*
X1468194Y-328503D01*
X1465944D01*
G01X1468194D02*
X1469694Y-327503D01*
X1470944Y-325837D01*
X1471444Y-323837D01*
X1470944Y-321837D01*
X1469694Y-320170D01*
X1467444Y-319170D01*
X1465194Y-319503D01*
X1462944Y-320837D01*
G01X1481944Y-339837D02*
X1490944Y-319170D01*
G01X1506444Y-339170D02*
Y-319170D01*
X1503444Y-323170D01*
G01Y-339170D02*
X1509444D01*
G01X1526444D02*
Y-319170D01*
X1523444Y-323170D01*
G01Y-339170D02*
X1529444D01*
G01X1541944Y-339837D02*
X1550944Y-319170D01*
G01X1561694Y-322503D02*
X1563194Y-320504D01*
X1564944Y-319503D01*
X1566944Y-319170D01*
X1569444Y-319837D01*
X1571194Y-321503D01*
X1571694Y-323503D01*
X1571444Y-325504D01*
X1570444Y-327170D01*
X1565444Y-330503D01*
X1563194Y-332837D01*
X1561694Y-336171D01*
X1561194Y-339170D01*
X1571694D01*
G01X1586444Y-319170D02*
X1584444Y-319837D01*
X1582944Y-321503D01*
X1581944Y-323503D01*
X1581194Y-326170D01*
X1580944Y-329170D01*
X1581194Y-332170D01*
X1581944Y-334837D01*
X1582944Y-336837D01*
X1584444Y-338503D01*
X1586444Y-339170D01*
X1588444Y-338503D01*
X1589944Y-336837D01*
X1590944Y-334837D01*
X1591694Y-332170D01*
X1591944Y-329170D01*
X1591694Y-326170D01*
X1590944Y-323503D01*
X1589944Y-321503D01*
X1588444Y-319837D01*
X1586444Y-319170D01*
G01X1414338Y-290463D02*
Y-270463D01*
X1411338Y-274463D01*
G01Y-290463D02*
X1417338D01*
G01X1434338Y-291130D02*
X1433838Y-290796D01*
Y-290130D01*
X1434338Y-289796D01*
X1434838Y-290130D01*
Y-290796D01*
X1434338Y-291130D01*
G01X1449588Y-282130D02*
X1451338Y-279796D01*
X1452838Y-278463D01*
X1454838Y-277797D01*
X1456588Y-278463D01*
X1457838Y-279796D01*
X1458838Y-281796D01*
X1459088Y-284130D01*
X1458838Y-286130D01*
X1457838Y-288130D01*
X1456338Y-289796D01*
X1454588Y-290463D01*
X1452588Y-289796D01*
X1450838Y-287797D01*
X1449838Y-284796D01*
X1449588Y-281463D01*
X1450088Y-277130D01*
X1450838Y-274796D01*
X1452088Y-272463D01*
X1453838Y-270796D01*
X1455588Y-270463D01*
X1457338Y-271130D01*
X1458588Y-272796D01*
G01X1466838Y-290463D02*
Y-277130D01*
G01Y-280797D02*
X1467588Y-279130D01*
X1468838Y-277797D01*
X1470588Y-277130D01*
X1472338Y-277797D01*
X1473588Y-279130D01*
X1474338Y-280797D01*
Y-290463D01*
G01Y-280797D02*
X1475088Y-279130D01*
X1476338Y-277797D01*
X1478088Y-277130D01*
X1479838Y-277797D01*
X1481088Y-279130D01*
X1481838Y-281130D01*
Y-290463D01*
G01X1486838D02*
Y-277130D01*
G01Y-280797D02*
X1487588Y-279130D01*
X1488838Y-277797D01*
X1490588Y-277130D01*
X1492338Y-277797D01*
X1493588Y-279130D01*
X1494338Y-280797D01*
Y-290463D01*
G01Y-280797D02*
X1495088Y-279130D01*
X1496338Y-277797D01*
X1498088Y-277130D01*
X1499838Y-277797D01*
X1501088Y-279130D01*
X1501838Y-281130D01*
Y-290463D01*
G01X1436584Y526769D02*
X1436440Y527527D01*
X1436007Y528393D01*
X1435285Y528934D01*
X1434274Y529151D01*
X1433264Y528934D01*
X1432398Y528285D01*
X1431965Y527310D01*
Y526228D01*
X1431676Y525578D01*
X1430954Y525037D01*
X1429944Y524820D01*
X1428933Y525145D01*
X1428212Y525903D01*
X1427923Y526769D01*
X1428212Y527635D01*
X1428933Y528393D01*
X1429944Y528718D01*
X1430954Y528501D01*
X1431676Y527960D01*
X1431965Y527310D01*
Y526228D01*
X1432398Y525253D01*
X1433264Y524604D01*
X1434274Y524387D01*
X1435285Y524604D01*
X1436007Y525145D01*
X1436440Y526011D01*
X1436584Y526769D01*
G01X1435574Y533589D02*
X1436295Y534347D01*
X1436584Y535213D01*
X1436295Y536080D01*
X1435429Y536837D01*
X1434130Y537379D01*
X1432831Y537595D01*
X1431243D01*
X1429944Y537379D01*
X1428789Y536837D01*
X1428212Y536188D01*
X1427923Y535430D01*
X1428212Y534564D01*
X1428789Y533914D01*
X1429655Y533481D01*
X1430810Y533265D01*
X1431820Y533481D01*
X1432831Y534023D01*
X1433408Y534672D01*
X1433553Y535430D01*
X1433264Y536296D01*
X1432542Y536946D01*
X1431243Y537595D01*
G01X1436873Y544091D02*
X1436728Y543874D01*
X1436440D01*
X1436295Y544091D01*
X1436440Y544308D01*
X1436728D01*
X1436873Y544091D01*
G01X1432975Y550695D02*
X1431965Y551453D01*
X1431387Y552102D01*
X1431099Y552969D01*
X1431387Y553726D01*
X1431965Y554268D01*
X1432831Y554701D01*
X1433841Y554809D01*
X1434708Y554701D01*
X1435574Y554268D01*
X1436295Y553618D01*
X1436584Y552860D01*
X1436295Y551994D01*
X1435429Y551236D01*
X1434130Y550803D01*
X1432687Y550695D01*
X1430810Y550911D01*
X1429799Y551236D01*
X1428789Y551778D01*
X1428067Y552535D01*
X1427923Y553293D01*
X1428212Y554051D01*
X1428933Y554593D01*
G01X1435285Y559031D02*
X1436007Y559681D01*
X1436440Y560439D01*
X1436584Y561413D01*
X1436295Y562387D01*
X1435718Y563145D01*
X1434708Y563687D01*
X1433553Y563795D01*
X1432398Y563578D01*
X1431676Y563037D01*
X1431099Y562279D01*
X1430954Y561521D01*
X1431099Y560763D01*
X1431676Y559789D01*
X1427923Y560114D01*
Y563037D01*
G01X1456637Y524928D02*
X1457358Y525686D01*
X1457647Y526552D01*
X1457358Y527419D01*
X1456492Y528176D01*
X1455193Y528718D01*
X1453894Y528934D01*
X1452306D01*
X1451007Y528718D01*
X1449852Y528176D01*
X1449275Y527527D01*
X1448986Y526769D01*
X1449275Y525903D01*
X1449852Y525253D01*
X1450718Y524820D01*
X1451873Y524604D01*
X1452883Y524820D01*
X1453894Y525362D01*
X1454471Y526011D01*
X1454616Y526769D01*
X1454327Y527635D01*
X1453605Y528285D01*
X1452306Y528934D01*
G01X1456348Y533048D02*
X1457070Y533698D01*
X1457503Y534456D01*
X1457647Y535430D01*
X1457358Y536404D01*
X1456781Y537162D01*
X1455771Y537704D01*
X1454616Y537812D01*
X1453461Y537595D01*
X1452739Y537054D01*
X1452162Y536296D01*
X1452017Y535538D01*
X1452162Y534780D01*
X1452739Y533806D01*
X1448986Y534131D01*
Y537054D01*
G01X1457936Y544091D02*
X1457791Y543874D01*
X1457503D01*
X1457358Y544091D01*
X1457503Y544308D01*
X1457791D01*
X1457936Y544091D01*
G01X1448986Y552752D02*
X1449275Y551886D01*
X1449996Y551236D01*
X1450862Y550803D01*
X1452017Y550478D01*
X1453317Y550370D01*
X1454616Y550478D01*
X1455771Y550803D01*
X1456637Y551236D01*
X1457358Y551886D01*
X1457647Y552752D01*
X1457358Y553618D01*
X1456637Y554268D01*
X1455771Y554701D01*
X1454616Y555026D01*
X1453317Y555134D01*
X1452017Y555026D01*
X1450862Y554701D01*
X1449996Y554268D01*
X1449275Y553618D01*
X1448986Y552752D01*
G01Y561413D02*
X1449275Y560547D01*
X1449996Y559897D01*
X1450862Y559464D01*
X1452017Y559139D01*
X1453317Y559031D01*
X1454616Y559139D01*
X1455771Y559464D01*
X1456637Y559897D01*
X1457358Y560547D01*
X1457647Y561413D01*
X1457358Y562279D01*
X1456637Y562929D01*
X1455771Y563362D01*
X1454616Y563687D01*
X1453317Y563795D01*
X1452017Y563687D01*
X1450862Y563362D01*
X1449996Y562929D01*
X1449275Y562279D01*
X1448986Y561413D01*
G01X1400364Y713972D02*
X1400220Y714730D01*
X1399787Y715596D01*
X1399065Y716137D01*
X1398054Y716354D01*
X1397044Y716137D01*
X1396178Y715488D01*
X1395745Y714513D01*
Y713431D01*
X1395456Y712781D01*
X1394734Y712240D01*
X1393724Y712023D01*
X1392713Y712348D01*
X1391992Y713106D01*
X1391703Y713972D01*
X1391992Y714838D01*
X1392713Y715596D01*
X1393724Y715921D01*
X1394734Y715704D01*
X1395456Y715163D01*
X1395745Y714513D01*
Y713431D01*
X1396178Y712456D01*
X1397044Y711807D01*
X1398054Y711590D01*
X1399065Y711807D01*
X1399787Y712348D01*
X1400220Y713214D01*
X1400364Y713972D01*
G01X1391703Y722633D02*
X1391992Y721767D01*
X1392713Y721117D01*
X1393579Y720684D01*
X1394734Y720359D01*
X1396034Y720251D01*
X1397333Y720359D01*
X1398488Y720684D01*
X1399354Y721117D01*
X1400075Y721767D01*
X1400364Y722633D01*
X1400075Y723499D01*
X1399354Y724149D01*
X1398488Y724582D01*
X1397333Y724907D01*
X1396034Y725015D01*
X1394734Y724907D01*
X1393579Y724582D01*
X1392713Y724149D01*
X1391992Y723499D01*
X1391703Y722633D01*
G01X1400653Y731294D02*
X1400508Y731077D01*
X1400220D01*
X1400075Y731294D01*
X1400220Y731511D01*
X1400508D01*
X1400653Y731294D01*
G01X1400364Y741254D02*
X1391703D01*
X1397910Y737248D01*
Y742662D01*
G01X1399065Y746234D02*
X1399787Y746884D01*
X1400220Y747642D01*
X1400364Y748616D01*
X1400075Y749590D01*
X1399498Y750348D01*
X1398488Y750890D01*
X1397333Y750998D01*
X1396178Y750781D01*
X1395456Y750240D01*
X1394879Y749482D01*
X1394734Y748724D01*
X1394879Y747966D01*
X1395456Y746992D01*
X1391703Y747317D01*
Y750240D01*
G01X1492371Y-437195D02*
Y-431289D01*
X1491486Y-432470D01*
G01Y-437195D02*
X1493257D01*
G01X1498276D02*
Y-431289D01*
X1497391Y-432470D01*
G01Y-437195D02*
X1499162D01*
G01X1482746Y636118D02*
Y644779D01*
X1481447Y643047D01*
G01Y636118D02*
X1484045D01*
G01X1489350Y643336D02*
X1490000Y644201D01*
X1490757Y644635D01*
X1491624Y644779D01*
X1492706Y644490D01*
X1493464Y643769D01*
X1493681Y642903D01*
X1493572Y642036D01*
X1493139Y641315D01*
X1490974Y639871D01*
X1490000Y638861D01*
X1489350Y637417D01*
X1489133Y636118D01*
X1493681D01*
G01X1500068Y635829D02*
X1499851Y635974D01*
Y636262D01*
X1500068Y636407D01*
X1500285Y636262D01*
Y635974D01*
X1500068Y635829D01*
G01X1506672Y639727D02*
X1507430Y640737D01*
X1508079Y641315D01*
X1508946Y641603D01*
X1509703Y641315D01*
X1510245Y640737D01*
X1510678Y639871D01*
X1510786Y638861D01*
X1510678Y637994D01*
X1510245Y637128D01*
X1509595Y636407D01*
X1508837Y636118D01*
X1507971Y636407D01*
X1507213Y637273D01*
X1506780Y638572D01*
X1506672Y640015D01*
X1506888Y641892D01*
X1507213Y642903D01*
X1507755Y643913D01*
X1508512Y644635D01*
X1509270Y644779D01*
X1510028Y644490D01*
X1510570Y643769D01*
G01X1517390Y644779D02*
X1516524Y644490D01*
X1515874Y643769D01*
X1515441Y642903D01*
X1515116Y641748D01*
X1515008Y640448D01*
X1515116Y639149D01*
X1515441Y637994D01*
X1515874Y637128D01*
X1516524Y636407D01*
X1517390Y636118D01*
X1518256Y636407D01*
X1518906Y637128D01*
X1519339Y637994D01*
X1519664Y639149D01*
X1519772Y640448D01*
X1519664Y641748D01*
X1519339Y642903D01*
X1518906Y643769D01*
X1518256Y644490D01*
X1517390Y644779D01*
G01X1492371Y923435D02*
Y929341D01*
X1491486Y928160D01*
G01Y923435D02*
X1493257D01*
G01X1498276D02*
Y929341D01*
X1497391Y928160D01*
G01Y923435D02*
X1499162D01*
G01X1621914Y-367117D02*
Y-361211D01*
X1624719D01*
G01X1623686Y-364065D02*
X1621914D01*
G01X1624793Y-130896D02*
X1621840D01*
Y-124990D01*
X1624793D01*
G01X1623612Y-127844D02*
X1621840D01*
G01X1621693Y105324D02*
Y111230D01*
X1623169D01*
X1623759Y110935D01*
X1624202Y110541D01*
X1624571Y109950D01*
X1624867Y109261D01*
X1624940Y108277D01*
X1624867Y107293D01*
X1624571Y106604D01*
X1624202Y106013D01*
X1623759Y105619D01*
X1623169Y105324D01*
X1621693D01*
G01X1624940Y346959D02*
X1624498Y347254D01*
X1623981Y347451D01*
X1623390D01*
X1622726Y347156D01*
X1622209Y346664D01*
X1621840Y346073D01*
X1621545Y345089D01*
X1621471Y344203D01*
X1621619Y343317D01*
X1621840Y342726D01*
X1622283Y342135D01*
X1622800Y341742D01*
X1623316Y341545D01*
X1623833D01*
X1624350Y341742D01*
X1624793Y342037D01*
X1625162Y342431D01*
G01X1623907Y580915D02*
X1624202Y581210D01*
X1624424Y581702D01*
X1624571Y582391D01*
X1624424Y582982D01*
X1624129Y583376D01*
X1623612Y583671D01*
X1621619D01*
Y577765D01*
X1624055D01*
X1624571Y578159D01*
X1624867Y578749D01*
X1625014Y579438D01*
X1624867Y580127D01*
X1624424Y580718D01*
X1623907Y580915D01*
X1621619D01*
G01X1621471Y813986D02*
X1623316Y819892D01*
X1625162Y813986D01*
G01X1624498Y816053D02*
X1622135D01*
G01X-333740Y-443449D02*
X1634763D01*
G01X-333740Y934504D02*
Y-443449D01*
G01Y-246599D02*
X-316418D01*
G01X-333740Y-10378D02*
X-316418D01*
G01X-333740Y225842D02*
X-316418D01*
G01X-333740Y462063D02*
X-316418D01*
G01X-333740Y698283D02*
X-316418D01*
G01X-333740Y934504D02*
X1634763D01*
G01X-316418Y-426126D02*
X1617441D01*
G01X-316418Y917181D02*
Y-426126D01*
G01Y917181D02*
X1617441D01*
G01X-160512Y-426126D02*
Y-443449D01*
G01Y934504D02*
Y917181D01*
G01X-15113Y0D02*
X-62954D01*
G01X-20271Y15000D02*
Y676339D01*
G01X-18519Y-4649D02*
X-54719D01*
G01X-3304Y10566D02*
X-18519Y-4649D01*
G01X-20271Y15000D02*
G03X-5271Y0I15000J0D01*
G01X-3937Y106693D02*
X-54039D01*
G01X-3937Y114567D02*
X-53619D01*
G01X15157Y221260D02*
X-55424D01*
G01X15157Y235040D02*
X-54290D01*
G01X-3937Y341733D02*
X-55006D01*
G01X-3937Y349607D02*
X-55207D01*
G01X15157Y456300D02*
X-52419D01*
G01X15157Y470079D02*
X-52842D01*
G01X-3937Y576772D02*
X-50741D01*
G01X-3937Y584646D02*
X-50680D01*
G01X-15113Y691339D02*
X-49631D01*
G01X-20271Y684213D02*
Y731176D01*
G01X-5271Y691339D02*
G03X-20271Y676339I0J-15000D01*
G01X12716Y-426126D02*
Y-443449D01*
G01X10771Y38708D02*
G03Y42708I0J2000D01*
G01D02*
G03Y38708I0J-2000D01*
G01X17071Y36808D02*
X4471D01*
G01X17071Y44608D02*
Y36808D01*
G01X4471D02*
Y44608D01*
G01X18171Y35708D02*
X3371D01*
G01X18171Y45708D02*
Y35708D01*
G01X3371D02*
Y45708D01*
G01X3395Y13517D02*
G03I-4000J0D01*
G01X1395D02*
G03I-2000J0D01*
G01X-10374Y7031D02*
X-3304Y10566D01*
G01D02*
X-6839Y3496D01*
G01D02*
X-10374Y7031D01*
G01X0Y37795D02*
G03X-7874I-3937J0D01*
G01X3937Y25984D02*
X13189D01*
G01X-7874Y37795D02*
G03X3937Y25984I11811J0D01*
G01X0Y37795D02*
G03X3937Y33858I3937J0D01*
G01X21063Y29921D02*
G03X17126Y33858I-3937J0D01*
G01X23009Y19700D02*
X23173Y19742D01*
G01X23502Y19113D02*
X23337Y19071D01*
G01X23009Y18862D02*
X23173Y18904D01*
G01X23502Y18234D02*
X23337Y18192D01*
G01X21328Y19951D02*
X21082Y19909D01*
G01X21164Y19700D02*
X21369Y19742D01*
G01X22968Y19909D02*
X23173Y19951D01*
G01X23583Y18024D02*
X23378Y17983D01*
G01X3937Y33858D02*
X17126D01*
G01X45866Y22047D02*
X48622D01*
G01X41929D02*
X44685D01*
G01X37992D02*
X40748D01*
G01X34055D02*
X36811D01*
G01X30118D02*
X32874D01*
G01X26181D02*
X28937D01*
G01X22244D02*
X25000D01*
G01X23173Y19951D02*
X23337D01*
G01X21492D02*
X21328D01*
G01X25306D02*
X24978D01*
G01X23173Y19742D02*
X23337D01*
G01X21369D02*
X21533D01*
G01X21943Y19490D02*
X22148D01*
G01X23337Y19071D02*
X23173D01*
G01Y18904D02*
X23337D01*
G01X24773Y18653D02*
X25511D01*
G01X24732Y18485D02*
X25552D01*
G01X21861Y18192D02*
X20713D01*
G01X23337D02*
X23173D01*
G01X25716Y17983D02*
X25962D01*
G01X24322D02*
X24568D01*
G01X20713D02*
X22189D01*
G01X23378D02*
X23132D01*
G01X21063Y5512D02*
X301378D01*
G01X25000D02*
X22244D01*
G01X28937D02*
X26181D01*
G01X32874D02*
X30118D01*
G01X36811D02*
X34055D01*
G01X40748D02*
X37992D01*
G01X44685D02*
X41929D01*
G01X48622D02*
X45866D01*
G01X23665Y18318D02*
X23502Y18234D01*
G01X23748Y19030D02*
X23665Y18988D01*
G01X22845Y18778D02*
X23009Y18862D01*
G01X22763Y18946D02*
X22845Y18988D01*
G01X21082Y19909D02*
X20918Y19825D01*
G01X21779Y19909D02*
X21492Y19951D01*
G01X299409Y0D02*
X23031D01*
G01X23789Y18150D02*
X23583Y18024D01*
G01X22763Y19783D02*
X22968Y19909D01*
G01X23337Y19742D02*
X23502Y19700D01*
G01X23173Y19071D02*
X23009Y19113D01*
G01X23337Y18904D02*
X23502Y18862D01*
G01X23173Y18192D02*
X23009Y18234D01*
G01X23337Y19951D02*
X23543Y19909D01*
G01X21533Y19742D02*
X21738Y19700D01*
G01X23132Y17983D02*
X22927Y18024D01*
G01X21041Y19616D02*
X21164Y19700D01*
G01X23665Y19239D02*
X23502Y19113D01*
G01X22599Y18820D02*
X22763Y18946D01*
G01X22845Y19574D02*
X23009Y19700D01*
G01X23911Y18276D02*
X23789Y18150D01*
G01X23870Y19155D02*
X23748Y19030D01*
G01X22640Y19658D02*
X22763Y19783D01*
G01X20918Y19825D02*
X20754Y19658D01*
G01X23543Y19909D02*
X23748Y19783D01*
G01X23665Y18988D02*
X23748Y18946D01*
G01X21943Y19825D02*
X21779Y19909D01*
G01X23502Y18862D02*
X23665Y18778D01*
G01X22845Y18988D02*
X22763Y19030D01*
G01X23009Y18234D02*
X22845Y18318D01*
G01X23789Y18485D02*
X23665Y18318D01*
G01X22722Y18611D02*
X22845Y18778D01*
G01X23502Y19700D02*
X23665Y19574D01*
G01X23748Y18946D02*
X23911Y18820D01*
G01X23009Y19113D02*
X22845Y19239D01*
G01X21738Y19700D02*
X21861Y19616D01*
G01X22927Y18024D02*
X22722Y18150D01*
G01X23748Y19365D02*
X23665Y19239D01*
G01X22763Y19448D02*
X22845Y19574D01*
G01X20959Y19490D02*
X21041Y19616D01*
G01X23748Y19783D02*
X23870Y19658D01*
G01X22189Y18192D02*
X21041Y19239D01*
G01X20836Y19113D02*
X21861Y18192D01*
G01X23952Y19323D02*
X23870Y19155D01*
G01X23994Y18485D02*
X23911Y18276D01*
G01X22517Y18611D02*
X22599Y18820D01*
G01X22558Y19448D02*
X22640Y19658D01*
G01X23665Y18778D02*
X23789Y18611D01*
G01X22845Y18318D02*
X22722Y18485D01*
G01X22763Y19030D02*
X22640Y19155D01*
G01X22107Y19658D02*
X21943Y19825D01*
G01X22722Y18150D02*
X22599Y18276D01*
G01X21063Y1969D02*
X23031Y0D01*
G01X24978Y19951D02*
X24322Y17983D01*
G01X24568D02*
X24732Y18485D01*
G01X25142Y19783D02*
X24773Y18653D01*
G01X20754Y19658D02*
X20713Y19490D01*
G01X45866Y5512D02*
Y22047D01*
G01X44685D02*
Y5512D01*
G01X41929D02*
Y22047D01*
G01X40748D02*
Y5512D01*
G01X37992D02*
Y22047D01*
G01X36811D02*
Y5512D01*
G01X34055D02*
Y22047D01*
G01X25511Y18653D02*
X25142Y19783D01*
G01X25552Y18485D02*
X25716Y17983D01*
G01X25962D02*
X25306Y19951D01*
G01X23870Y19658D02*
X23952Y19448D01*
G01X23911Y18820D02*
X23994Y18611D01*
G01X22599Y18276D02*
X22517Y18485D01*
G01X22640Y19155D02*
X22558Y19323D01*
G01X21041Y19239D02*
X20959Y19407D01*
G01X23665Y19574D02*
X23748Y19448D01*
G01X22845Y19239D02*
X22763Y19365D01*
G01X21861Y19616D02*
X21943Y19490D01*
G01X20754Y19239D02*
X20836Y19113D01*
G01X32874Y22047D02*
Y5512D01*
G01X30118D02*
Y22047D01*
G01X28937D02*
Y5512D01*
G01X26181D02*
Y22047D01*
G01X25000D02*
Y5512D01*
G01X23994Y18611D02*
Y18485D01*
G01X23952Y19448D02*
Y19323D01*
G01X23789Y18611D02*
Y18485D01*
G01X23748Y19448D02*
Y19365D01*
G01X22763D02*
Y19448D01*
G01X22722Y18485D02*
Y18611D01*
G01X22558Y19323D02*
Y19448D01*
G01X22517Y18485D02*
Y18611D01*
G01X22244Y5512D02*
Y22047D01*
G01X22189Y17983D02*
Y18192D01*
G01X21063Y1969D02*
Y29921D01*
G01X20959Y19407D02*
Y19490D01*
G01X20713Y18192D02*
Y17983D01*
G01Y19490D02*
Y19407D01*
G01X22148Y19490D02*
X22107Y19658D01*
G01X20713Y19407D02*
X20754Y19239D01*
G01X0Y102756D02*
Y37795D01*
G01X13189Y0D02*
X-5271D01*
G01X13189Y25984D02*
Y0D01*
G01X4471Y44608D02*
X17071D01*
G01X3371Y45708D02*
X18171D01*
G01X-7874Y68504D02*
G03X0I3937J0D01*
G01X19488Y81890D02*
X17913Y83465D01*
G01Y73228D02*
X19488Y74803D01*
G01Y78346D02*
G03I-2953J0D01*
G01X3937Y106693D02*
G03X0Y102756I0J-3937D01*
G01X20276Y80107D02*
G03Y76586I-3740J-1760D01*
G01X12795Y75974D02*
G03X20276I3740J2372D01*
G01Y80719D02*
G03X12795I-3740J-2372D01*
G01X28268Y98425D02*
X11811D01*
G01X49173D02*
X33268D01*
G01X19685Y92835D02*
X11811D01*
G01X362205Y92815D02*
X11811D01*
G01X24178Y91634D02*
X23067D01*
G01X32052D02*
X30941D01*
G01X39926D02*
X38815D01*
G01X47800D02*
X46689D01*
G01X19685Y91142D02*
X354331D01*
G01X24178Y90650D02*
X23067D01*
G01X32052D02*
X30941D01*
G01X39926D02*
X38815D01*
G01X47800D02*
X46689D01*
G01X46670Y90201D02*
X47819D01*
G01X38796D02*
X39944D01*
G01X30922D02*
X32070D01*
G01X23048D02*
X24196D01*
G01X24187Y89933D02*
X23057D01*
G01X32061D02*
X30931D01*
G01X39935D02*
X38806D01*
G01X47809D02*
X46680D01*
G01X20157Y89665D02*
X15354D01*
G01X11811Y88878D02*
X19685D01*
G01X24201Y88414D02*
X23043D01*
G01X32075D02*
X30917D01*
G01X39949D02*
X38791D01*
G01X47823D02*
X46665D01*
G01X46674Y88146D02*
X47814D01*
G01X38800D02*
X39940D01*
G01X30926D02*
X32066D01*
G01X23052D02*
X24192D01*
G01X19291Y87697D02*
X15354D01*
G01X24211D02*
X23034D01*
G01X28148D02*
X26971D01*
G01X32085D02*
X30908D01*
G01X36022D02*
X34845D01*
G01X39959D02*
X38782D01*
G01X43896D02*
X42719D01*
G01X47833D02*
X46656D01*
G01X24211Y86713D02*
X23034D01*
G01X28148D02*
X26971D01*
G01X32085D02*
X30908D01*
G01X36022D02*
X34845D01*
G01X39959D02*
X38782D01*
G01X43896D02*
X42719D01*
G01X47833D02*
X46656D01*
G01X28129Y86264D02*
X26989D01*
G01X36003D02*
X34863D01*
G01X43877D02*
X42737D01*
G01X42728Y85996D02*
X43886D01*
G01X34854D02*
X36012D01*
G01X26980D02*
X28138D01*
G01X20157Y85335D02*
X15354D01*
G01X42743Y84477D02*
X43872D01*
G01X34869D02*
X35998D01*
G01X26994D02*
X28124D01*
G01X28133Y84209D02*
X26985D01*
G01X36007D02*
X34859D01*
G01X43881D02*
X42733D01*
G01X28115Y83760D02*
X27004D01*
G01X35989D02*
X34878D01*
G01X43863D02*
X42752D01*
G01X302172Y83465D02*
X17913D01*
G01X28115Y82776D02*
X27004D01*
G01X35989D02*
X34878D01*
G01X43863D02*
X42752D01*
G01X19488Y81890D02*
X354528D01*
G01X24247Y81299D02*
X22997D01*
G01X28184D02*
X26934D01*
G01X32121D02*
X30871D01*
G01X36058D02*
X34808D01*
G01X39995D02*
X38745D01*
G01X43932D02*
X42682D01*
G01X47869D02*
X46619D01*
G01X46638Y81229D02*
X47850D01*
G01X42701D02*
X43913D01*
G01X38764D02*
X39976D01*
G01X34827D02*
X36039D01*
G01X30890D02*
X32102D01*
G01X26953D02*
X28165D01*
G01X23016D02*
X24228D01*
G01X24237Y81004D02*
X23007D01*
G01X28174D02*
X26944D01*
G01X32111D02*
X30881D01*
G01X36048D02*
X34818D01*
G01X39985D02*
X38755D01*
G01X43922D02*
X42692D01*
G01X47859D02*
X46629D01*
G01X46617Y80389D02*
X47872D01*
G01X42680D02*
X43935D01*
G01X38743D02*
X39998D01*
G01X34806D02*
X36061D01*
G01X30869D02*
X32124D01*
G01X26931D02*
X28187D01*
G01X22994D02*
X24250D01*
G01X24226Y80301D02*
X23019D01*
G01X28163D02*
X26956D01*
G01X32100D02*
X30893D01*
G01X36037D02*
X34830D01*
G01X39974D02*
X38767D01*
G01X43911D02*
X42704D01*
G01X47848D02*
X46641D01*
G01X24237Y80019D02*
X23007D01*
G01X28174D02*
X26944D01*
G01X32111D02*
X30881D01*
G01X36048D02*
X34818D01*
G01X39985D02*
X38755D01*
G01X43922D02*
X42692D01*
G01X47859D02*
X46629D01*
G01X46630Y76674D02*
X47859D01*
G01X42693D02*
X43922D01*
G01X38756D02*
X39985D01*
G01X34819D02*
X36048D01*
G01X30881D02*
X32111D01*
G01X26944D02*
X28174D01*
G01X23007D02*
X24237D01*
G01X46641Y76392D02*
X47848D01*
G01X42704D02*
X43911D01*
G01X38767D02*
X39974D01*
G01X34830D02*
X36037D01*
G01X30893D02*
X32100D01*
G01X26956D02*
X28163D01*
G01X23019D02*
X24226D01*
G01X24250Y76304D02*
X22994D01*
G01X28187D02*
X26931D01*
G01X32124D02*
X30869D01*
G01X36061D02*
X34806D01*
G01X39998D02*
X38743D01*
G01X43935D02*
X42680D01*
G01X47872D02*
X46617D01*
G01X46630Y75690D02*
X47859D01*
G01X42693D02*
X43922D01*
G01X38756D02*
X39985D01*
G01X34819D02*
X36048D01*
G01X30881D02*
X32111D01*
G01X26944D02*
X28174D01*
G01X23007D02*
X24237D01*
G01X24228Y75464D02*
X23016D01*
G01X28165D02*
X26953D01*
G01X32102D02*
X30890D01*
G01X36039D02*
X34827D01*
G01X39976D02*
X38764D01*
G01X43913D02*
X42701D01*
G01X47850D02*
X46638D01*
G01X46619Y75394D02*
X47869D01*
G01X42682D02*
X43932D01*
G01X38745D02*
X39995D01*
G01X34808D02*
X36058D01*
G01X30871D02*
X32121D01*
G01X26934D02*
X28184D01*
G01X22997D02*
X24247D01*
G01X19488Y74803D02*
X354528D01*
G01X42752Y73917D02*
X43863D01*
G01X34878D02*
X35989D01*
G01X27004D02*
X28115D01*
G01X17913Y73228D02*
X302172D01*
G01X42752Y72933D02*
X43863D01*
G01X34878D02*
X35989D01*
G01X27004D02*
X28115D01*
G01X42733Y72484D02*
X43881D01*
G01X34859D02*
X36007D01*
G01X26985D02*
X28133D01*
G01X28124Y72217D02*
X26994D01*
G01X35998D02*
X34869D01*
G01X43872D02*
X42743D01*
G01X15354Y71358D02*
X20157D01*
G01X28138Y70697D02*
X26980D01*
G01X36012D02*
X34854D01*
G01X43886D02*
X42728D01*
G01X42737Y70430D02*
X43877D01*
G01X34863D02*
X36003D01*
G01X26989D02*
X28129D01*
G01X46656Y69980D02*
X47833D01*
G01X42719D02*
X43896D01*
G01X38782D02*
X39959D01*
G01X34845D02*
X36022D01*
G01X30908D02*
X32085D01*
G01X26971D02*
X28148D01*
G01X23034D02*
X24211D01*
G01X19291Y68996D02*
X15354D01*
G01X24211D02*
X23034D01*
G01X28148D02*
X26971D01*
G01X32085D02*
X30908D01*
G01X36022D02*
X34845D01*
G01X39959D02*
X38782D01*
G01X43896D02*
X42719D01*
G01X47833D02*
X46656D01*
G01X24192Y68547D02*
X23052D01*
G01X32066D02*
X30926D01*
G01X39940D02*
X38800D01*
G01X47814D02*
X46674D01*
G01X46665Y68280D02*
X47823D01*
G01X38791D02*
X39949D01*
G01X30917D02*
X32075D01*
G01X23043D02*
X24201D01*
G01X19685Y67815D02*
X11811D01*
G01X20157Y67028D02*
X15354D01*
G01X46680Y66760D02*
X47809D01*
G01X38806D02*
X39935D01*
G01X30931D02*
X32061D01*
G01X23057D02*
X24187D01*
G01X24196Y66493D02*
X23048D01*
G01X32070D02*
X30922D01*
G01X39944D02*
X38796D01*
G01X47819D02*
X46670D01*
G01X46689Y66043D02*
X47800D01*
G01X38815D02*
X39926D01*
G01X30941D02*
X32052D01*
G01X23067D02*
X24178D01*
G01X354331Y65551D02*
X19685D01*
G01X46689Y65059D02*
X47800D01*
G01X38815D02*
X39926D01*
G01X30941D02*
X32052D01*
G01X23067D02*
X24178D01*
G01X11811Y63878D02*
X362205D01*
G01X46641Y80301D02*
X46671Y81890D01*
G01X46609Y74803D02*
X46619Y75394D01*
G01X46617Y76304D02*
X46592Y74803D01*
G01X46680Y89933D02*
X46674Y88146D01*
G01X46665Y88414D02*
X46670Y90201D01*
G01X46811Y66043D02*
Y65059D01*
G01Y90650D02*
Y91634D01*
G01X46656Y69980D02*
Y68996D01*
G01Y87697D02*
Y86713D01*
G01X46674Y68547D02*
X46680Y66760D01*
G01X46670Y66493D02*
X46665Y68280D01*
G01X46619Y81299D02*
X46609Y81890D01*
G01X46591D02*
X46617Y80389D01*
G01X46671Y74803D02*
X46641Y76392D01*
G01X46638Y75464D02*
X46651Y74803D01*
G01Y81890D02*
X46638Y81229D01*
G01X43900Y74803D02*
X43913Y75464D01*
G01X43911Y76392D02*
X43880Y74803D01*
G01X42704Y80301D02*
X42734Y81890D01*
G01X42714D02*
X42701Y81229D01*
G01X39963Y74803D02*
X39976Y75464D01*
G01X39974Y76392D02*
X39943Y74803D01*
G01X38767Y80301D02*
X38797Y81890D01*
G01X38777D02*
X38764Y81229D01*
G01X36026Y74803D02*
X36039Y75464D01*
G01X36037Y76392D02*
X36006Y74803D01*
G01X34830Y80301D02*
X34860Y81890D01*
G01X34840D02*
X34827Y81229D01*
G01X43935Y80389D02*
X43960Y81890D01*
G01X43942D02*
X43932Y81299D01*
G01X42672Y74803D02*
X42682Y75394D01*
G01X42680Y76304D02*
X42655Y74803D01*
G01X39998Y80389D02*
X40023Y81890D01*
G01X40005D02*
X39995Y81299D01*
G01X38735Y74803D02*
X38745Y75394D01*
G01X38743Y76304D02*
X38718Y74803D01*
G01X36061Y80389D02*
X36086Y81890D01*
G01X36068D02*
X36058Y81299D01*
G01X34798Y74803D02*
X34808Y75394D01*
G01X34806Y76304D02*
X34781Y74803D01*
G01X43886Y85996D02*
X43881Y84209D01*
G01X43872Y84477D02*
X43877Y86264D01*
G01X42743Y72217D02*
X42737Y70430D01*
G01X42728Y70697D02*
X42733Y72484D01*
G01X39949Y68280D02*
X39944Y66493D01*
G01X39935Y66760D02*
X39940Y68547D01*
G01X38806Y89933D02*
X38800Y88146D01*
G01X38791Y88414D02*
X38796Y90201D01*
G01X36012Y85996D02*
X36007Y84209D01*
G01X35998Y84477D02*
X36003Y86264D01*
G01X34869Y72217D02*
X34863Y70430D01*
G01X34854Y70697D02*
X34859Y72484D01*
G01X43896Y69980D02*
Y68996D01*
G01Y87697D02*
Y86713D01*
G01X43740Y73917D02*
Y72933D01*
G01Y83760D02*
Y82776D01*
G01X42874Y73917D02*
Y72933D01*
G01Y82776D02*
Y83760D01*
G01X42719Y68996D02*
Y69980D01*
G01Y86713D02*
Y87697D01*
G01X39959Y68996D02*
Y69980D01*
G01Y86713D02*
Y87697D01*
G01X39803Y66043D02*
Y65059D01*
G01Y91634D02*
Y90650D01*
G01X38937Y66043D02*
Y65059D01*
G01Y90650D02*
Y91634D01*
G01X38782Y69980D02*
Y68996D01*
G01Y87697D02*
Y86713D01*
G01X36022Y69980D02*
Y68996D01*
G01Y87697D02*
Y86713D01*
G01X35866Y73917D02*
Y72933D01*
G01Y83760D02*
Y82776D01*
G01X35000Y73917D02*
Y72933D01*
G01Y82776D02*
Y83760D01*
G01X34845Y68996D02*
Y69980D01*
G01Y86713D02*
Y87697D01*
G01X33268Y98425D02*
Y92815D01*
G01X43881Y72484D02*
X43886Y70697D01*
G01X43877Y70430D02*
X43872Y72217D01*
G01X42737Y86264D02*
X42743Y84477D01*
G01X42733Y84209D02*
X42728Y85996D01*
G01X39944Y90201D02*
X39949Y88414D01*
G01X39940Y88146D02*
X39935Y89933D01*
G01X38800Y68547D02*
X38806Y66760D01*
G01X38796Y66493D02*
X38791Y68280D01*
G01X36007Y72484D02*
X36012Y70697D01*
G01X36003Y70430D02*
X35998Y72217D01*
G01X34863Y86264D02*
X34869Y84477D01*
G01X34859Y84209D02*
X34854Y85996D01*
G01X43960Y74803D02*
X43935Y76304D01*
G01X43932Y75394D02*
X43942Y74803D01*
G01X42682Y81299D02*
X42672Y81890D01*
G01X42654D02*
X42680Y80389D01*
G01X40023Y74803D02*
X39998Y76304D01*
G01X39995Y75394D02*
X40005Y74803D01*
G01X38745Y81299D02*
X38735Y81890D01*
G01X38717D02*
X38743Y80389D01*
G01X36086Y74803D02*
X36061Y76304D01*
G01X36058Y75394D02*
X36068Y74803D01*
G01X34808Y81299D02*
X34798Y81890D01*
G01X34780D02*
X34806Y80389D01*
G01X43913Y81229D02*
X43900Y81890D01*
G01X43880D02*
X43911Y80301D01*
G01X42734Y74803D02*
X42704Y76392D01*
G01X42701Y75464D02*
X42714Y74803D01*
G01X39976Y81229D02*
X39963Y81890D01*
G01X39943D02*
X39974Y80301D01*
G01X38797Y74803D02*
X38767Y76392D01*
G01X38764Y75464D02*
X38777Y74803D01*
G01X36039Y81229D02*
X36026Y81890D01*
G01X36006D02*
X36037Y80301D01*
G01X34860Y74803D02*
X34830Y76392D01*
G01X34827Y75464D02*
X34840Y74803D01*
G01X32089D02*
X32102Y75464D01*
G01X32100Y76392D02*
X32069Y74803D01*
G01X30893Y80301D02*
X30923Y81890D01*
G01X30903D02*
X30890Y81229D01*
G01X28152Y74803D02*
X28165Y75464D01*
G01X28163Y76392D02*
X28132Y74803D01*
G01X26956Y80301D02*
X26986Y81890D01*
G01X26966D02*
X26953Y81229D01*
G01X24215Y74803D02*
X24228Y75464D01*
G01X24226Y76392D02*
X24195Y74803D01*
G01X23019Y80301D02*
X23049Y81890D01*
G01X23029D02*
X23016Y81229D01*
G01X32124Y80389D02*
X32149Y81890D01*
G01X32131D02*
X32121Y81299D01*
G01X30861Y74803D02*
X30871Y75394D01*
G01X30869Y76304D02*
X30844Y74803D01*
G01X28187Y80389D02*
X28212Y81890D01*
G01X28194D02*
X28184Y81299D01*
G01X26924Y74803D02*
X26934Y75394D01*
G01X26931Y76304D02*
X26907Y74803D01*
G01X24250Y80389D02*
X24275Y81890D01*
G01X24257D02*
X24247Y81299D01*
G01X22987Y74803D02*
X22997Y75394D01*
G01X22994Y76304D02*
X22970Y74803D01*
G01X32075Y68280D02*
X32070Y66493D01*
G01X32061Y66760D02*
X32066Y68547D01*
G01X30931Y89933D02*
X30926Y88146D01*
G01X30917Y88414D02*
X30922Y90201D01*
G01X28138Y85996D02*
X28133Y84209D01*
G01X28124Y84477D02*
X28129Y86264D01*
G01X26994Y72217D02*
X26989Y70430D01*
G01X26980Y70697D02*
X26985Y72484D01*
G01X24201Y68280D02*
X24196Y66493D01*
G01X24187Y66760D02*
X24192Y68547D01*
G01X23057Y89933D02*
X23052Y88146D01*
G01X23043Y88414D02*
X23048Y90201D01*
G01X32085Y68996D02*
Y69980D01*
G01Y86713D02*
Y87697D01*
G01X31929Y66043D02*
Y65059D01*
G01Y91634D02*
Y90650D01*
G01X31063Y66043D02*
Y65059D01*
G01Y90650D02*
Y91634D01*
G01X30908Y69980D02*
Y68996D01*
G01Y87697D02*
Y86713D01*
G01X28268Y98425D02*
Y92815D01*
G01X28148Y69980D02*
Y68996D01*
G01Y87697D02*
Y86713D01*
G01X27992Y73917D02*
Y72933D01*
G01Y83760D02*
Y82776D01*
G01X27126Y73917D02*
Y72933D01*
G01Y82776D02*
Y83760D01*
G01X26971Y68996D02*
Y69980D01*
G01Y86713D02*
Y87697D01*
G01X24211Y68996D02*
Y69980D01*
G01Y86713D02*
Y87697D01*
G01X24055Y66043D02*
Y65059D01*
G01Y91634D02*
Y90650D01*
G01X23189Y66043D02*
Y65059D01*
G01Y90650D02*
Y91634D01*
G01X23034Y69980D02*
Y68996D01*
G01Y87697D02*
Y86713D01*
G01X20276Y80719D02*
Y75974D01*
G01X32070Y90201D02*
X32075Y88414D01*
G01X32066Y88146D02*
X32061Y89933D01*
G01X30926Y68547D02*
X30931Y66760D01*
G01X30922Y66493D02*
X30917Y68280D01*
G01X28133Y72484D02*
X28138Y70697D01*
G01X28129Y70430D02*
X28124Y72217D01*
G01X26989Y86264D02*
X26994Y84477D01*
G01X26985Y84209D02*
X26980Y85996D01*
G01X24196Y90201D02*
X24201Y88414D01*
G01X24192Y88146D02*
X24187Y89933D01*
G01X23052Y68547D02*
X23057Y66760D01*
G01X23048Y66493D02*
X23043Y68280D01*
G01X32149Y74803D02*
X32124Y76304D01*
G01X32121Y75394D02*
X32131Y74803D01*
G01X30871Y81299D02*
X30861Y81890D01*
G01X30843D02*
X30869Y80389D01*
G01X28212Y74803D02*
X28187Y76304D01*
G01X28184Y75394D02*
X28194Y74803D01*
G01X26934Y81299D02*
X26924Y81890D01*
G01X26906D02*
X26931Y80389D01*
G01X24275Y74803D02*
X24250Y76304D01*
G01X24247Y75394D02*
X24257Y74803D01*
G01X22997Y81299D02*
X22987Y81890D01*
G01X22969D02*
X22994Y80389D01*
G01X32102Y81229D02*
X32089Y81890D01*
G01X32069D02*
X32100Y80301D01*
G01X30923Y74803D02*
X30893Y76392D01*
G01X30890Y75464D02*
X30903Y74803D01*
G01X28165Y81229D02*
X28152Y81890D01*
G01X28132D02*
X28163Y80301D01*
G01X26986Y74803D02*
X26956Y76392D01*
G01X26953Y75464D02*
X26966Y74803D01*
G01X24228Y81229D02*
X24215Y81890D01*
G01X24195D02*
X24226Y80301D01*
G01X23049Y74803D02*
X23019Y76392D01*
G01X23016Y75464D02*
X23029Y74803D01*
G01X20157Y67028D02*
Y71358D01*
G01Y89665D02*
Y85335D01*
G01X19685Y88878D02*
Y92835D01*
G01Y67815D02*
Y63878D01*
G01X19488Y74803D02*
Y81890D01*
G01X19291Y85335D02*
Y87697D01*
G01Y71358D02*
Y68996D01*
G01X17913Y83465D02*
Y73228D01*
G01X15354Y85335D02*
Y89665D01*
G01Y71358D02*
Y67028D01*
G01X12795Y80107D02*
Y80719D01*
G01Y75974D02*
Y76586D01*
G01X11811Y63878D02*
Y98425D01*
G01X-7874Y68504D02*
Y122737D01*
G01X0Y118504D02*
G03X3937Y114567I3937J0D01*
G01Y157382D02*
G03X0Y153445I0J-3937D01*
G01X17126Y157382D02*
G03X21063Y161319I0J3937D01*
G01X0Y118504D02*
Y153445D01*
G01X21063Y219292D02*
Y161319D01*
G01D02*
Y187402D01*
G01X143701Y114567D02*
X3937D01*
G01Y157382D02*
X17126D01*
G01X-7874Y153445D02*
Y157382D01*
G01Y153445D02*
G03X0I3937J0D01*
G01Y122737D02*
G03X-7874I-3937J0D01*
G01X-10433Y161070D02*
G03X-7874Y157382I3937J0D01*
G01X-10433Y265210D02*
Y161070D01*
G01X3937Y106693D02*
X143701D01*
G01X51378Y181496D02*
G03X47441Y177559I0J-3937D01*
G01Y165748D02*
G03X51378Y161811I3937J0D01*
G01X47441Y165748D02*
Y177559D01*
G01X23031Y221260D02*
X21063Y219292D01*
G01X23031Y221260D02*
X63189D01*
G01X0Y272835D02*
G03X3937Y268898I3937J0D01*
G01X21063Y264961D02*
G03X17126Y268898I-3937J0D01*
G01X3937D02*
X17126D01*
G01X299409Y235040D02*
X23031D01*
G01X21063Y237008D02*
X23031Y235040D01*
G01X21063Y237008D02*
Y264961D01*
G01X0Y337796D02*
Y272835D01*
G01X10770Y273748D02*
G03Y277748I0J2000D01*
G01D02*
G03Y273748I0J-2000D01*
G01X17070Y271848D02*
X4470D01*
G01X17070Y279648D02*
Y271848D01*
G01X4470Y279648D02*
X17070D01*
G01X4470Y271848D02*
Y279648D01*
G01X18170Y270748D02*
X3370D01*
G01X18170Y280748D02*
Y270748D01*
G01X3370Y280748D02*
X18170D01*
G01X3370Y270748D02*
Y280748D01*
G01X0Y272835D02*
G03X-7874I-3937J0D01*
G01Y268898D02*
G03X-10433Y265210I1378J-3688D01*
G01X-7874Y268898D02*
Y272835D01*
G01X3937Y341733D02*
G03X0Y337796I0J-3937D01*
G01X3937Y341733D02*
X143701D01*
G01X-7874Y303543D02*
Y357781D01*
G01Y303544D02*
G03X0I3937J0D01*
G01X47441Y400788D02*
G03X51378Y396851I3937J0D01*
G01X47441Y400788D02*
Y412599D01*
G01X0Y353544D02*
G03X3937Y349607I3937J0D01*
G01Y392422D02*
G03X0Y388485I0J-3937D01*
G01X17126Y392422D02*
G03X21063Y396359I0J3937D01*
G01X0Y353544D02*
Y388485D01*
G01X21063Y454331D02*
Y396359D01*
G01D02*
Y422441D01*
G01X143701Y349607D02*
X3937D01*
G01Y392422D02*
X17126D01*
G01X-7874Y388480D02*
Y392422D01*
G01Y388485D02*
G03X0I3937J0D01*
G01Y357776D02*
G03X-7874I-3937J0D01*
G01X-10433Y396110D02*
G03X-7874Y392422I3937J0D01*
G01X-10433Y500250D02*
Y396110D01*
G01X51378Y416536D02*
G03X47441Y412599I0J-3937D01*
G01X23031Y456300D02*
X21063Y454331D01*
G01X23031Y456300D02*
X63189D01*
G01X0Y507874D02*
G03X3937Y503937I3937J0D01*
G01X21063Y500000D02*
G03X17126Y503937I-3937J0D01*
G01X3937D02*
X17126D01*
G01X299409Y470079D02*
X23031D01*
G01X21063Y472048D02*
X23031Y470079D01*
G01X21063Y472048D02*
Y500000D01*
G01X0Y572835D02*
Y507874D01*
G01X10770Y508787D02*
G03Y512787I0J2000D01*
G01D02*
G03Y508787I0J-2000D01*
G01X17070Y506887D02*
X4470D01*
G01X17070Y514687D02*
Y506887D01*
G01X4470Y514687D02*
X17070D01*
G01X4470Y506887D02*
Y514687D01*
G01X18170Y505787D02*
X3370D01*
G01X18170Y515787D02*
Y505787D01*
G01X3370Y515787D02*
X18170D01*
G01X3370Y505787D02*
Y515787D01*
G01X0Y507874D02*
G03X-7874I-3937J0D01*
G01Y503937D02*
Y507880D01*
G01Y503937D02*
G03X-10433Y500250I1378J-3688D01*
G01X3937Y576772D02*
G03X0Y572835I0J-3937D01*
G01X3937Y576772D02*
X143701D01*
G01X-7874Y538578D02*
Y592823D01*
G01Y538583D02*
G03X0I3937J0D01*
G01Y588583D02*
G03X3937Y584646I3937J0D01*
G01X0Y588583D02*
Y623524D01*
G01X143701Y584646D02*
X3937D01*
G01X0Y631398D02*
Y730594D01*
G01X1830Y651994D02*
G03I-4292J0D01*
G01X-7874Y623517D02*
Y623536D01*
G01X13189Y691339D02*
Y635335D01*
G01X3937D02*
X13189D01*
G01X3937D02*
G03X-7874Y623524I0J-11811D01*
G01X51378Y651576D02*
G03X47441Y647639I0J-3937D01*
G01Y635828D02*
G03X51378Y631891I3937J0D01*
G01X47441Y635828D02*
Y647639D01*
G01X3937Y627461D02*
G03X0Y623524I0J-3937D01*
G01X17126Y627461D02*
G03X21063Y631398I0J3937D01*
G01Y689371D02*
Y631398D01*
G01D02*
Y657481D01*
G01X3937Y627461D02*
X17126D01*
G01X-7874Y623524D02*
G03X0I3937J0D01*
G01Y592816D02*
G03X-7874I-3937J0D01*
G01X4498Y680644D02*
G03I-4000J0D01*
G01X2498D02*
G03I-2000J0D01*
G01X23031Y691339D02*
X21063Y689371D01*
G01X23031Y691339D02*
X63189D01*
G01X13189D02*
X-5271D01*
G01X12716Y934504D02*
Y917181D01*
G01X104921Y22047D02*
X107677D01*
G01X100984D02*
X103740D01*
G01X97047D02*
X99803D01*
G01X93110D02*
X95866D01*
G01X89173D02*
X91929D01*
G01X85236D02*
X87992D01*
G01X81299D02*
X84055D01*
G01X77362D02*
X80118D01*
G01X73425D02*
X76181D01*
G01X69488D02*
X72244D01*
G01X65551D02*
X68307D01*
G01X61614D02*
X64370D01*
G01X57677D02*
X60433D01*
G01X53740D02*
X56496D01*
G01X49803D02*
X52559D01*
G01Y5512D02*
X49803D01*
G01X56496D02*
X53740D01*
G01X60433D02*
X57677D01*
G01X64370D02*
X61614D01*
G01X68307D02*
X65551D01*
G01X72244D02*
X69488D01*
G01X76181D02*
X73425D01*
G01X80118D02*
X77362D01*
G01X84055D02*
X81299D01*
G01X87992D02*
X85236D01*
G01X91929D02*
X89173D01*
G01X95866D02*
X93110D01*
G01X99803D02*
X97047D01*
G01X103740D02*
X100984D01*
G01X107677D02*
X104921D01*
G01X107677Y22047D02*
Y5512D01*
G01X104921D02*
Y22047D01*
G01X103740D02*
Y5512D01*
G01X100984D02*
Y22047D01*
G01X99803D02*
Y5512D01*
G01X97047D02*
Y22047D01*
G01X95866D02*
Y5512D01*
G01X93110D02*
Y22047D01*
G01X91929D02*
Y5512D01*
G01X89173D02*
Y22047D01*
G01X87992D02*
Y5512D01*
G01X85236D02*
Y22047D01*
G01X84055D02*
Y5512D01*
G01X81299D02*
Y22047D01*
G01X80118D02*
Y5512D01*
G01X77362D02*
Y22047D01*
G01X76181D02*
Y5512D01*
G01X73425D02*
Y22047D01*
G01X72244D02*
Y5512D01*
G01X69488D02*
Y22047D01*
G01X68307D02*
Y5512D01*
G01X65551D02*
Y22047D01*
G01X64370D02*
Y5512D01*
G01X61614D02*
Y22047D01*
G01X60433D02*
Y5512D01*
G01X57677D02*
Y22047D01*
G01X56496D02*
Y5512D01*
G01X53740D02*
Y22047D01*
G01X52559D02*
Y5512D01*
G01X49803D02*
Y22047D01*
G01X48622D02*
Y5512D01*
G01X70079Y98425D02*
X54173D01*
G01X90984D02*
X75079D01*
G01X111890D02*
X95984D01*
G01X55674Y91634D02*
X54563D01*
G01X63548D02*
X62437D01*
G01X71422D02*
X70311D01*
G01X79296D02*
X78185D01*
G01X87170D02*
X86059D01*
G01X95044D02*
X93933D01*
G01X102918D02*
X101807D01*
G01X55674Y90650D02*
X54563D01*
G01X63548D02*
X62437D01*
G01X71422D02*
X70311D01*
G01X79296D02*
X78185D01*
G01X87170D02*
X86059D01*
G01X95044D02*
X93933D01*
G01X102918D02*
X101807D01*
G01X101788Y90201D02*
X102937D01*
G01X93914D02*
X95063D01*
G01X86040D02*
X87189D01*
G01X78166D02*
X79315D01*
G01X70292D02*
X71441D01*
G01X62418D02*
X63567D01*
G01X54544D02*
X55693D01*
G01X55683Y89933D02*
X54554D01*
G01X63557D02*
X62428D01*
G01X71431D02*
X70302D01*
G01X79305D02*
X78176D01*
G01X87179D02*
X86050D01*
G01X95053D02*
X93924D01*
G01X102927D02*
X101798D01*
G01X55697Y88414D02*
X54539D01*
G01X63571D02*
X62413D01*
G01X71445D02*
X70287D01*
G01X79319D02*
X78161D01*
G01X87193D02*
X86035D01*
G01X95067D02*
X93909D01*
G01X102941D02*
X101783D01*
G01X101793Y88146D02*
X102932D01*
G01X93919D02*
X95058D01*
G01X86044D02*
X87184D01*
G01X78170D02*
X79310D01*
G01X70296D02*
X71436D01*
G01X62422D02*
X63562D01*
G01X54548D02*
X55688D01*
G01X51770Y87697D02*
X50593D01*
G01X55707D02*
X54530D01*
G01X59644D02*
X58467D01*
G01X63581D02*
X62404D01*
G01X67518D02*
X66341D01*
G01X71455D02*
X70278D01*
G01X75392D02*
X74215D01*
G01X79329D02*
X78152D01*
G01X83266D02*
X82089D01*
G01X87203D02*
X86026D01*
G01X91140D02*
X89963D01*
G01X95077D02*
X93900D01*
G01X99014D02*
X97837D01*
G01X102951D02*
X101774D01*
G01X106888D02*
X105711D01*
G01X51770Y86713D02*
X50593D01*
G01X55707D02*
X54530D01*
G01X59644D02*
X58467D01*
G01X63581D02*
X62404D01*
G01X67518D02*
X66341D01*
G01X71455D02*
X70278D01*
G01X75392D02*
X74215D01*
G01X79329D02*
X78152D01*
G01X83266D02*
X82089D01*
G01X87203D02*
X86026D01*
G01X91140D02*
X89963D01*
G01X95077D02*
X93900D01*
G01X99014D02*
X97837D01*
G01X102951D02*
X101774D01*
G01X106888D02*
X105711D01*
G01X51751Y86264D02*
X50611D01*
G01X59625D02*
X58485D01*
G01X67499D02*
X66359D01*
G01X75373D02*
X74233D01*
G01X83247D02*
X82107D01*
G01X91121D02*
X89981D01*
G01X98995D02*
X97856D01*
G01X106869D02*
X105730D01*
G01X105720Y85996D02*
X106878D01*
G01X97846D02*
X99004D01*
G01X89972D02*
X91130D01*
G01X82098D02*
X83256D01*
G01X74224D02*
X75382D01*
G01X66350D02*
X67508D01*
G01X58476D02*
X59634D01*
G01X50602D02*
X51760D01*
G01X105735Y84477D02*
X106864D01*
G01X97861D02*
X98990D01*
G01X89987D02*
X91116D01*
G01X82113D02*
X83242D01*
G01X74239D02*
X75368D01*
G01X66365D02*
X67494D01*
G01X58491D02*
X59620D01*
G01X50617D02*
X51746D01*
G01X51756Y84209D02*
X50607D01*
G01X59630D02*
X58481D01*
G01X67504D02*
X66355D01*
G01X75378D02*
X74229D01*
G01X83252D02*
X82103D01*
G01X91126D02*
X89977D01*
G01X99000D02*
X97851D01*
G01X106874D02*
X105725D01*
G01X51737Y83760D02*
X50626D01*
G01X59611D02*
X58500D01*
G01X67485D02*
X66374D01*
G01X75359D02*
X74248D01*
G01X83233D02*
X82122D01*
G01X91107D02*
X89996D01*
G01X98981D02*
X97870D01*
G01X106855D02*
X105744D01*
G01X51737Y82776D02*
X50626D01*
G01X59611D02*
X58500D01*
G01X67485D02*
X66374D01*
G01X75359D02*
X74248D01*
G01X83233D02*
X82122D01*
G01X91107D02*
X89996D01*
G01X98981D02*
X97870D01*
G01X106855D02*
X105744D01*
G01X51806Y81299D02*
X50556D01*
G01X55743D02*
X54493D01*
G01X59680D02*
X58430D01*
G01X63617D02*
X62367D01*
G01X67554D02*
X66304D01*
G01X71491D02*
X70241D01*
G01X75428D02*
X74178D01*
G01X79365D02*
X78115D01*
G01X83302D02*
X82052D01*
G01X87239D02*
X85989D01*
G01X91176D02*
X89926D01*
G01X95113D02*
X93863D01*
G01X99050D02*
X97800D01*
G01X102987D02*
X101737D01*
G01X106924D02*
X105674D01*
G01X105693Y81229D02*
X106905D01*
G01X101756D02*
X102968D01*
G01X97819D02*
X99031D01*
G01X93882D02*
X95094D01*
G01X89945D02*
X91157D01*
G01X86008D02*
X87220D01*
G01X82071D02*
X83283D01*
G01X78134D02*
X79346D01*
G01X74197D02*
X75409D01*
G01X70260D02*
X71472D01*
G01X66323D02*
X67535D01*
G01X62386D02*
X63598D01*
G01X58449D02*
X59661D01*
G01X54512D02*
X55724D01*
G01X50575D02*
X51787D01*
G01X51796Y81004D02*
X50566D01*
G01X55733D02*
X54503D01*
G01X59670D02*
X58440D01*
G01X63607D02*
X62377D01*
G01X67544D02*
X66314D01*
G01X71481D02*
X70251D01*
G01X75418D02*
X74188D01*
G01X79355D02*
X78125D01*
G01X83292D02*
X82062D01*
G01X87229D02*
X85999D01*
G01X91166D02*
X89936D01*
G01X95103D02*
X93873D01*
G01X99040D02*
X97810D01*
G01X102977D02*
X101747D01*
G01X106914D02*
X105684D01*
G01X105672Y80389D02*
X106927D01*
G01X101735D02*
X102990D01*
G01X97798D02*
X99053D01*
G01X93861D02*
X95116D01*
G01X89924D02*
X91179D01*
G01X85987D02*
X87242D01*
G01X82050D02*
X83305D01*
G01X78113D02*
X79368D01*
G01X74176D02*
X75431D01*
G01X70239D02*
X71494D01*
G01X66302D02*
X67557D01*
G01X62365D02*
X63620D01*
G01X58428D02*
X59683D01*
G01X54491D02*
X55746D01*
G01X50554D02*
X51809D01*
G01X51785Y80301D02*
X50578D01*
G01X55722D02*
X54515D01*
G01X59659D02*
X58452D01*
G01X63596D02*
X62389D01*
G01X67533D02*
X66326D01*
G01X71470D02*
X70263D01*
G01X75407D02*
X74200D01*
G01X79344D02*
X78137D01*
G01X83281D02*
X82074D01*
G01X87218D02*
X86011D01*
G01X91155D02*
X89948D01*
G01X95092D02*
X93885D01*
G01X99029D02*
X97822D01*
G01X102966D02*
X101759D01*
G01X106903D02*
X105696D01*
G01X51796Y80019D02*
X50566D01*
G01X55733D02*
X54503D01*
G01X59670D02*
X58440D01*
G01X63607D02*
X62377D01*
G01X67544D02*
X66314D01*
G01X71481D02*
X70251D01*
G01X75418D02*
X74188D01*
G01X79355D02*
X78125D01*
G01X83292D02*
X82062D01*
G01X87229D02*
X85999D01*
G01X91166D02*
X89936D01*
G01X95103D02*
X93873D01*
G01X99040D02*
X97810D01*
G01X102977D02*
X101747D01*
G01X106914D02*
X105684D01*
G01X105685Y76674D02*
X106914D01*
G01X101748D02*
X102977D01*
G01X97811D02*
X99040D01*
G01X93874D02*
X95103D01*
G01X89937D02*
X91166D01*
G01X86000D02*
X87229D01*
G01X82063D02*
X83292D01*
G01X78126D02*
X79355D01*
G01X74189D02*
X75418D01*
G01X70252D02*
X71481D01*
G01X66315D02*
X67544D01*
G01X62378D02*
X63607D01*
G01X58441D02*
X59670D01*
G01X54504D02*
X55733D01*
G01X50567D02*
X51796D01*
G01X105696Y76392D02*
X106903D01*
G01X101759D02*
X102966D01*
G01X97822D02*
X99029D01*
G01X93885D02*
X95092D01*
G01X89948D02*
X91155D01*
G01X86011D02*
X87218D01*
G01X82074D02*
X83281D01*
G01X78137D02*
X79344D01*
G01X74200D02*
X75407D01*
G01X70263D02*
X71470D01*
G01X66326D02*
X67533D01*
G01X62389D02*
X63596D01*
G01X58452D02*
X59659D01*
G01X54515D02*
X55722D01*
G01X50578D02*
X51785D01*
G01X51809Y76304D02*
X50554D01*
G01X55746D02*
X54491D01*
G01X59683D02*
X58428D01*
G01X63620D02*
X62365D01*
G01X67557D02*
X66302D01*
G01X71494D02*
X70239D01*
G01X75431D02*
X74176D01*
G01X79368D02*
X78113D01*
G01X83305D02*
X82050D01*
G01X87242D02*
X85987D01*
G01X91179D02*
X89924D01*
G01X95116D02*
X93861D01*
G01X99053D02*
X97798D01*
G01X102990D02*
X101735D01*
G01X106927D02*
X105672D01*
G01X105685Y75690D02*
X106914D01*
G01X101748D02*
X102977D01*
G01X97811D02*
X99040D01*
G01X93874D02*
X95103D01*
G01X89937D02*
X91166D01*
G01X86000D02*
X87229D01*
G01X82063D02*
X83292D01*
G01X78126D02*
X79355D01*
G01X74189D02*
X75418D01*
G01X70252D02*
X71481D01*
G01X66315D02*
X67544D01*
G01X62378D02*
X63607D01*
G01X58441D02*
X59670D01*
G01X54504D02*
X55733D01*
G01X50567D02*
X51796D01*
G01X51787Y75464D02*
X50575D01*
G01X55724D02*
X54512D01*
G01X59661D02*
X58449D01*
G01X63598D02*
X62386D01*
G01X67535D02*
X66323D01*
G01X71472D02*
X70260D01*
G01X75409D02*
X74197D01*
G01X79346D02*
X78134D01*
G01X83283D02*
X82071D01*
G01X87220D02*
X86008D01*
G01X91157D02*
X89945D01*
G01X95094D02*
X93882D01*
G01X99031D02*
X97819D01*
G01X102968D02*
X101756D01*
G01X106905D02*
X105693D01*
G01X105674Y75394D02*
X106924D01*
G01X101737D02*
X102987D01*
G01X97800D02*
X99050D01*
G01X93863D02*
X95113D01*
G01X89926D02*
X91176D01*
G01X85989D02*
X87239D01*
G01X82052D02*
X83302D01*
G01X78115D02*
X79365D01*
G01X74178D02*
X75428D01*
G01X70241D02*
X71491D01*
G01X66304D02*
X67554D01*
G01X62367D02*
X63617D01*
G01X58430D02*
X59680D01*
G01X54493D02*
X55743D01*
G01X50556D02*
X51806D01*
G01X105744Y73917D02*
X106855D01*
G01X97870D02*
X98981D01*
G01X89996D02*
X91107D01*
G01X82122D02*
X83233D01*
G01X74248D02*
X75359D01*
G01X66374D02*
X67485D01*
G01X58500D02*
X59611D01*
G01X50626D02*
X51737D01*
G01X105744Y72933D02*
X106855D01*
G01X97870D02*
X98981D01*
G01X89996D02*
X91107D01*
G01X82122D02*
X83233D01*
G01X74248D02*
X75359D01*
G01X66374D02*
X67485D01*
G01X58500D02*
X59611D01*
G01X50626D02*
X51737D01*
G01X105725Y72484D02*
X106874D01*
G01X97851D02*
X99000D01*
G01X89977D02*
X91126D01*
G01X82103D02*
X83252D01*
G01X74229D02*
X75378D01*
G01X66355D02*
X67504D01*
G01X58481D02*
X59630D01*
G01X50607D02*
X51756D01*
G01X51746Y72217D02*
X50617D01*
G01X59620D02*
X58491D01*
G01X67494D02*
X66365D01*
G01X75368D02*
X74239D01*
G01X83242D02*
X82113D01*
G01X91116D02*
X89987D01*
G01X98990D02*
X97861D01*
G01X106864D02*
X105735D01*
G01X51760Y70697D02*
X50602D01*
G01X59634D02*
X58476D01*
G01X67508D02*
X66350D01*
G01X75382D02*
X74224D01*
G01X83256D02*
X82098D01*
G01X91130D02*
X89972D01*
G01X99004D02*
X97846D01*
G01X106878D02*
X105720D01*
G01X105730Y70430D02*
X106869D01*
G01X97856D02*
X98995D01*
G01X89981D02*
X91121D01*
G01X82107D02*
X83247D01*
G01X74233D02*
X75373D01*
G01X66359D02*
X67499D01*
G01X58485D02*
X59625D01*
G01X50611D02*
X51751D01*
G01X105711Y69980D02*
X106888D01*
G01X101774D02*
X102951D01*
G01X97837D02*
X99014D01*
G01X93900D02*
X95077D01*
G01X89963D02*
X91140D01*
G01X86026D02*
X87203D01*
G01X82089D02*
X83266D01*
G01X78152D02*
X79329D01*
G01X74215D02*
X75392D01*
G01X70278D02*
X71455D01*
G01X66341D02*
X67518D01*
G01X62404D02*
X63581D01*
G01X58467D02*
X59644D01*
G01X54530D02*
X55707D01*
G01X50593D02*
X51770D01*
G01Y68996D02*
X50593D01*
G01X55707D02*
X54530D01*
G01X59644D02*
X58467D01*
G01X63581D02*
X62404D01*
G01X67518D02*
X66341D01*
G01X71455D02*
X70278D01*
G01X75392D02*
X74215D01*
G01X79329D02*
X78152D01*
G01X83266D02*
X82089D01*
G01X87203D02*
X86026D01*
G01X91140D02*
X89963D01*
G01X95077D02*
X93900D01*
G01X99014D02*
X97837D01*
G01X102951D02*
X101774D01*
G01X106888D02*
X105711D01*
G01X55688Y68547D02*
X54548D01*
G01X63562D02*
X62422D01*
G01X71436D02*
X70296D01*
G01X79310D02*
X78170D01*
G01X87184D02*
X86044D01*
G01X95058D02*
X93919D01*
G01X102932D02*
X101793D01*
G01X101783Y68280D02*
X102941D01*
G01X93909D02*
X95067D01*
G01X86035D02*
X87193D01*
G01X78161D02*
X79319D01*
G01X70287D02*
X71445D01*
G01X62413D02*
X63571D01*
G01X54539D02*
X55697D01*
G01X101798Y66760D02*
X102927D01*
G01X93924D02*
X95053D01*
G01X86050D02*
X87179D01*
G01X78176D02*
X79305D01*
G01X70302D02*
X71431D01*
G01X62428D02*
X63557D01*
G01X54554D02*
X55683D01*
G01X55693Y66493D02*
X54544D01*
G01X63567D02*
X62418D01*
G01X71441D02*
X70292D01*
G01X79315D02*
X78166D01*
G01X87189D02*
X86040D01*
G01X95063D02*
X93914D01*
G01X102937D02*
X101788D01*
G01X101807Y66043D02*
X102918D01*
G01X93933D02*
X95044D01*
G01X86059D02*
X87170D01*
G01X78185D02*
X79296D01*
G01X70311D02*
X71422D01*
G01X62437D02*
X63548D01*
G01X54563D02*
X55674D01*
G01X101807Y65059D02*
X102918D01*
G01X93933D02*
X95044D01*
G01X86059D02*
X87170D01*
G01X78185D02*
X79296D01*
G01X70311D02*
X71422D01*
G01X62437D02*
X63548D01*
G01X54563D02*
X55674D01*
G01X106893Y74803D02*
X106905Y75464D01*
G01X106903Y76392D02*
X106872Y74803D01*
G01X105696Y80301D02*
X105726Y81890D01*
G01X105706D02*
X105693Y81229D01*
G01X102956Y74803D02*
X102968Y75464D01*
G01X102966Y76392D02*
X102935Y74803D01*
G01X101759Y80301D02*
X101789Y81890D01*
G01X101769D02*
X101756Y81229D01*
G01X99019Y74803D02*
X99031Y75464D01*
G01X99029Y76392D02*
X98998Y74803D01*
G01X106927Y80389D02*
X106952Y81890D01*
G01X106934D02*
X106924Y81299D01*
G01X105665Y74803D02*
X105674Y75394D01*
G01X105672Y76304D02*
X105647Y74803D01*
G01X102990Y80389D02*
X103015Y81890D01*
G01X102997D02*
X102987Y81299D01*
G01X101728Y74803D02*
X101737Y75394D01*
G01X101735Y76304D02*
X101710Y74803D01*
G01X99053Y80389D02*
X99078Y81890D01*
G01X99060D02*
X99050Y81299D01*
G01X106878Y85996D02*
X106874Y84209D01*
G01X106864Y84477D02*
X106869Y86264D01*
G01X105735Y72217D02*
X105730Y70430D01*
G01X105720Y70697D02*
X105725Y72484D01*
G01X102941Y68280D02*
X102937Y66493D01*
G01X102927Y66760D02*
X102932Y68547D01*
G01X101798Y89933D02*
X101793Y88146D01*
G01X101783Y88414D02*
X101788Y90201D01*
G01X99004Y85996D02*
X99000Y84209D01*
G01X98990Y84477D02*
X98995Y86264D01*
G01X106888Y69980D02*
Y68996D01*
G01Y87697D02*
Y86713D01*
G01X106732Y73917D02*
Y72933D01*
G01Y83760D02*
Y82776D01*
G01X105867Y73917D02*
Y72933D01*
G01X105866Y82776D02*
Y83760D01*
G01X105711Y68996D02*
Y69980D01*
G01Y86713D02*
Y87697D01*
G01X102951Y68996D02*
Y69980D01*
G01Y86713D02*
Y87697D01*
G01X102795Y66043D02*
Y65059D01*
G01Y91634D02*
Y90650D01*
G01X101930Y66043D02*
Y65059D01*
G01X101929Y90650D02*
Y91634D01*
G01X101774Y69980D02*
Y68996D01*
G01Y87697D02*
Y86713D01*
G01X99014Y69980D02*
Y68996D01*
G01Y87697D02*
Y86713D01*
G01X98858Y73917D02*
Y72933D01*
G01Y83760D02*
Y82776D01*
G01X106874Y72484D02*
X106878Y70697D01*
G01X106869Y70430D02*
X106864Y72217D01*
G01X105730Y86264D02*
X105735Y84477D01*
G01X105725Y84209D02*
X105720Y85996D01*
G01X102937Y90201D02*
X102941Y88414D01*
G01X102932Y88146D02*
X102927Y89933D01*
G01X101793Y68547D02*
X101798Y66760D01*
G01X101788Y66493D02*
X101783Y68280D01*
G01X99000Y72484D02*
X99004Y70697D01*
G01X98995Y70430D02*
X98990Y72217D01*
G01X106952Y74803D02*
X106927Y76304D01*
G01X106924Y75394D02*
X106934Y74803D01*
G01X105674Y81299D02*
X105664Y81890D01*
G01X105646D02*
X105672Y80389D01*
G01X103015Y74803D02*
X102990Y76304D01*
G01X102987Y75394D02*
X102997Y74803D01*
G01X101737Y81299D02*
X101727Y81890D01*
G01X101709D02*
X101735Y80389D01*
G01X99078Y74803D02*
X99053Y76304D01*
G01X99050Y75394D02*
X99060Y74803D01*
G01X97800Y81299D02*
X97790Y81890D01*
G01X97772D02*
X97798Y80389D01*
G01X106905Y81229D02*
X106893Y81890D01*
G01X106872D02*
X106903Y80301D01*
G01X105726Y74803D02*
X105696Y76392D01*
G01X105693Y75464D02*
X105706Y74803D01*
G01X102968Y81229D02*
X102956Y81890D01*
G01X102935D02*
X102966Y80301D01*
G01X101789Y74803D02*
X101759Y76392D01*
G01X101756Y75464D02*
X101769Y74803D01*
G01X99031Y81229D02*
X99019Y81890D01*
G01X98998D02*
X99029Y80301D01*
G01X97852Y74803D02*
X97822Y76392D01*
G01X97819Y75464D02*
X97832Y74803D01*
G01X97822Y80301D02*
X97852Y81890D01*
G01X97832D02*
X97819Y81229D01*
G01X95081Y74803D02*
X95094Y75464D01*
G01X95092Y76392D02*
X95061Y74803D01*
G01X93885Y80301D02*
X93915Y81890D01*
G01X93895D02*
X93882Y81229D01*
G01X91144Y74803D02*
X91157Y75464D01*
G01X91155Y76392D02*
X91124Y74803D01*
G01X89948Y80301D02*
X89978Y81890D01*
G01X89958D02*
X89945Y81229D01*
G01X87207Y74803D02*
X87220Y75464D01*
G01X87218Y76392D02*
X87187Y74803D01*
G01X86011Y80301D02*
X86041Y81890D01*
G01X86021D02*
X86008Y81229D01*
G01X97791Y74803D02*
X97800Y75394D01*
G01X97798Y76304D02*
X97773Y74803D01*
G01X95116Y80389D02*
X95141Y81890D01*
G01X95123D02*
X95113Y81299D01*
G01X93854Y74803D02*
X93863Y75394D01*
G01X93861Y76304D02*
X93836Y74803D01*
G01X91179Y80389D02*
X91204Y81890D01*
G01X91186D02*
X91176Y81299D01*
G01X89917Y74803D02*
X89926Y75394D01*
G01X89924Y76304D02*
X89899Y74803D01*
G01X87242Y80389D02*
X87267Y81890D01*
G01X87249D02*
X87239Y81299D01*
G01X85980Y74803D02*
X85989Y75394D01*
G01X85987Y76304D02*
X85962Y74803D01*
G01X97861Y72217D02*
X97856Y70430D01*
G01X97846Y70697D02*
X97851Y72484D01*
G01X95067Y68280D02*
X95063Y66493D01*
G01X95053Y66760D02*
X95058Y68547D01*
G01X93924Y89933D02*
X93919Y88146D01*
G01X93909Y88414D02*
X93914Y90201D01*
G01X91130Y85996D02*
X91126Y84209D01*
G01X91116Y84477D02*
X91121Y86264D01*
G01X89987Y72217D02*
X89981Y70430D01*
G01X89972Y70697D02*
X89977Y72484D01*
G01X87193Y68280D02*
X87189Y66493D01*
G01X87179Y66760D02*
X87184Y68547D01*
G01X86050Y89933D02*
X86044Y88146D01*
G01X86035Y88414D02*
X86040Y90201D01*
G01X97993Y73917D02*
Y72933D01*
G01X97992Y82776D02*
Y83760D01*
G01X97837Y68996D02*
Y69980D01*
G01Y86713D02*
Y87697D01*
G01X95984Y98425D02*
Y92815D01*
G01X95077Y68996D02*
Y69980D01*
G01Y86713D02*
Y87697D01*
G01X94921Y66043D02*
Y65059D01*
G01Y91634D02*
Y90650D01*
G01X94056Y66043D02*
Y65059D01*
G01X94055Y90650D02*
Y91634D01*
G01X93900Y69980D02*
Y68996D01*
G01Y87697D02*
Y86713D01*
G01X91140Y69980D02*
Y68996D01*
G01Y87697D02*
Y86713D01*
G01X90984Y73917D02*
Y72933D01*
G01Y98425D02*
Y92815D01*
G01Y83760D02*
Y82776D01*
G01X90119Y73917D02*
Y72933D01*
G01X90118Y82776D02*
Y83760D01*
G01X89963Y68996D02*
Y69980D01*
G01Y86713D02*
Y87697D01*
G01X87203Y68996D02*
Y69980D01*
G01Y86713D02*
Y87697D01*
G01X87047Y66043D02*
Y65059D01*
G01Y91634D02*
Y90650D01*
G01X86181Y66043D02*
Y65059D01*
G01Y90650D02*
Y91634D01*
G01X86026Y69980D02*
Y68996D01*
G01Y87697D02*
Y86713D01*
G01X97856Y86264D02*
X97861Y84477D01*
G01X97851Y84209D02*
X97846Y85996D01*
G01X95063Y90201D02*
X95067Y88414D01*
G01X95058Y88146D02*
X95053Y89933D01*
G01X93919Y68547D02*
X93924Y66760D01*
G01X93914Y66493D02*
X93909Y68280D01*
G01X91126Y72484D02*
X91130Y70697D01*
G01X91121Y70430D02*
X91116Y72217D01*
G01X89981Y86264D02*
X89987Y84477D01*
G01X89977Y84209D02*
X89972Y85996D01*
G01X87189Y90201D02*
X87193Y88414D01*
G01X87184Y88146D02*
X87179Y89933D01*
G01X86044Y68547D02*
X86050Y66760D01*
G01X86040Y66493D02*
X86035Y68280D01*
G01X95141Y74803D02*
X95116Y76304D01*
G01X95113Y75394D02*
X95123Y74803D01*
G01X93863Y81299D02*
X93853Y81890D01*
G01X93835D02*
X93861Y80389D01*
G01X91204Y74803D02*
X91179Y76304D01*
G01X91176Y75394D02*
X91186Y74803D01*
G01X89926Y81299D02*
X89916Y81890D01*
G01X89898D02*
X89924Y80389D01*
G01X87267Y74803D02*
X87242Y76304D01*
G01X87239Y75394D02*
X87249Y74803D01*
G01X85989Y81299D02*
X85979Y81890D01*
G01X85961D02*
X85987Y80389D01*
G01X95094Y81229D02*
X95081Y81890D01*
G01X95061D02*
X95092Y80301D01*
G01X93915Y74803D02*
X93885Y76392D01*
G01X93882Y75464D02*
X93895Y74803D01*
G01X91157Y81229D02*
X91144Y81890D01*
G01X91124D02*
X91155Y80301D01*
G01X89978Y74803D02*
X89948Y76392D01*
G01X89945Y75464D02*
X89958Y74803D01*
G01X87220Y81229D02*
X87207Y81890D01*
G01X87187D02*
X87218Y80301D01*
G01X86041Y74803D02*
X86011Y76392D01*
G01X86008Y75464D02*
X86021Y74803D01*
G01X83270D02*
X83283Y75464D01*
G01X83281Y76392D02*
X83250Y74803D01*
G01X82074Y80301D02*
X82104Y81890D01*
G01X82084D02*
X82071Y81229D01*
G01X79333Y74803D02*
X79346Y75464D01*
G01X79344Y76392D02*
X79313Y74803D01*
G01X78137Y80301D02*
X78167Y81890D01*
G01X78147D02*
X78134Y81229D01*
G01X75396Y74803D02*
X75409Y75464D01*
G01X75407Y76392D02*
X75376Y74803D01*
G01X74200Y80301D02*
X74230Y81890D01*
G01X74210D02*
X74197Y81229D01*
G01X83305Y80389D02*
X83330Y81890D01*
G01X83312D02*
X83302Y81299D01*
G01X82043Y74803D02*
X82052Y75394D01*
G01X82050Y76304D02*
X82025Y74803D01*
G01X79368Y80389D02*
X79393Y81890D01*
G01X79375D02*
X79365Y81299D01*
G01X78106Y74803D02*
X78115Y75394D01*
G01X78113Y76304D02*
X78088Y74803D01*
G01X75431Y80389D02*
X75456Y81890D01*
G01X75438D02*
X75428Y81299D01*
G01X74169Y74803D02*
X74178Y75394D01*
G01X74176Y76304D02*
X74151Y74803D01*
G01X83256Y85996D02*
X83252Y84209D01*
G01X83242Y84477D02*
X83247Y86264D01*
G01X82113Y72217D02*
X82107Y70430D01*
G01X82098Y70697D02*
X82103Y72484D01*
G01X79319Y68280D02*
X79315Y66493D01*
G01X79305Y66760D02*
X79310Y68547D01*
G01X78176Y89933D02*
X78170Y88146D01*
G01X78161Y88414D02*
X78166Y90201D01*
G01X75382Y85996D02*
X75378Y84209D01*
G01X75368Y84477D02*
X75373Y86264D01*
G01X74239Y72217D02*
X74233Y70430D01*
G01X74224Y70697D02*
X74229Y72484D01*
G01X83266Y69980D02*
Y68996D01*
G01Y87697D02*
Y86713D01*
G01X83110Y73917D02*
Y72933D01*
G01Y83760D02*
Y82776D01*
G01X82244Y73917D02*
Y72933D01*
G01Y82776D02*
Y83760D01*
G01X82089Y68996D02*
Y69980D01*
G01Y86713D02*
Y87697D01*
G01X79329Y68996D02*
Y69980D01*
G01Y86713D02*
Y87697D01*
G01X79173Y66043D02*
Y65059D01*
G01Y91634D02*
Y90650D01*
G01X78307Y66043D02*
Y65059D01*
G01Y90650D02*
Y91634D01*
G01X78152Y69980D02*
Y68996D01*
G01Y87697D02*
Y86713D01*
G01X75392Y69980D02*
Y68996D01*
G01Y86713D02*
Y87697D01*
G01X75236Y73917D02*
Y72933D01*
G01Y83760D02*
Y82776D01*
G01X75079Y98425D02*
Y92815D01*
G01X74370Y73917D02*
Y72933D01*
G01Y82776D02*
Y83760D01*
G01X74215Y68996D02*
Y69980D01*
G01Y87697D02*
Y86713D01*
G01X83252Y72484D02*
X83256Y70697D01*
G01X83247Y70430D02*
X83242Y72217D01*
G01X82107Y86264D02*
X82113Y84477D01*
G01X82103Y84209D02*
X82098Y85996D01*
G01X79315Y90201D02*
X79319Y88414D01*
G01X79310Y88146D02*
X79305Y89933D01*
G01X78170Y68547D02*
X78176Y66760D01*
G01X78166Y66493D02*
X78161Y68280D01*
G01X75378Y72484D02*
X75382Y70697D01*
G01X75373Y70430D02*
X75368Y72217D01*
G01X74233Y86264D02*
X74239Y84477D01*
G01X74229Y84209D02*
X74224Y85996D01*
G01X83330Y74803D02*
X83305Y76304D01*
G01X83302Y75394D02*
X83312Y74803D01*
G01X82052Y81299D02*
X82042Y81890D01*
G01X82024D02*
X82050Y80389D01*
G01X79393Y74803D02*
X79368Y76304D01*
G01X79365Y75394D02*
X79375Y74803D01*
G01X78115Y81299D02*
X78105Y81890D01*
G01X78087D02*
X78113Y80389D01*
G01X75456Y74803D02*
X75431Y76304D01*
G01X75428Y75394D02*
X75438Y74803D01*
G01X74178Y81299D02*
X74168Y81890D01*
G01X74150D02*
X74176Y80389D01*
G01X83283Y81229D02*
X83270Y81890D01*
G01X83250D02*
X83281Y80301D01*
G01X82104Y74803D02*
X82074Y76392D01*
G01X82071Y75464D02*
X82084Y74803D01*
G01X79346Y81229D02*
X79333Y81890D01*
G01X79313D02*
X79344Y80301D01*
G01X78167Y74803D02*
X78137Y76392D01*
G01X78134Y75464D02*
X78147Y74803D01*
G01X75409Y81229D02*
X75396Y81890D01*
G01X75376D02*
X75407Y80301D01*
G01X74230Y74803D02*
X74200Y76392D01*
G01X74197Y75464D02*
X74210Y74803D01*
G01X71459D02*
X71472Y75464D01*
G01X71470Y76392D02*
X71439Y74803D01*
G01X70263Y80301D02*
X70293Y81890D01*
G01X70273D02*
X70260Y81229D01*
G01X67522Y74803D02*
X67535Y75464D01*
G01X67533Y76392D02*
X67502Y74803D01*
G01X66326Y80301D02*
X66356Y81890D01*
G01X66336D02*
X66323Y81229D01*
G01X63585Y74803D02*
X63598Y75464D01*
G01X63596Y76392D02*
X63565Y74803D01*
G01X62389Y80301D02*
X62419Y81890D01*
G01X62399D02*
X62386Y81229D01*
G01X59648Y74803D02*
X59661Y75464D01*
G01X59659Y76392D02*
X59628Y74803D01*
G01X71494Y80389D02*
X71519Y81890D01*
G01X71501D02*
X71491Y81299D01*
G01X70231Y74803D02*
X70241Y75394D01*
G01X70239Y76304D02*
X70214Y74803D01*
G01X67557Y80389D02*
X67582Y81890D01*
G01X67564D02*
X67554Y81299D01*
G01X66294Y74803D02*
X66304Y75394D01*
G01X66302Y76304D02*
X66277Y74803D01*
G01X63620Y80389D02*
X63645Y81890D01*
G01X63627D02*
X63617Y81299D01*
G01X62357Y74803D02*
X62367Y75394D01*
G01X62365Y76304D02*
X62340Y74803D01*
G01X59683Y80389D02*
X59708Y81890D01*
G01X59690D02*
X59680Y81299D01*
G01X71445Y68280D02*
X71441Y66493D01*
G01X71431Y66760D02*
X71436Y68547D01*
G01X70302Y89933D02*
X70296Y88146D01*
G01X70287Y88414D02*
X70292Y90201D01*
G01X67508Y85996D02*
X67504Y84209D01*
G01X67494Y84477D02*
X67499Y86264D01*
G01X66365Y72217D02*
X66359Y70430D01*
G01X66350Y70697D02*
X66355Y72484D01*
G01X63571Y68280D02*
X63567Y66493D01*
G01X63557Y66760D02*
X63562Y68547D01*
G01X62428Y89933D02*
X62422Y88146D01*
G01X62413Y88414D02*
X62418Y90201D01*
G01X59634Y85996D02*
X59630Y84209D01*
G01X59620Y84477D02*
X59625Y86264D01*
G01X71455Y68996D02*
Y69980D01*
G01Y86713D02*
Y87697D01*
G01X71299Y66043D02*
Y65059D01*
G01Y91634D02*
Y90650D01*
G01X70433Y66043D02*
Y65059D01*
G01Y90650D02*
Y91634D01*
G01X70278Y69980D02*
Y68996D01*
G01Y87697D02*
Y86713D01*
G01X70079Y98425D02*
Y92815D01*
G01X67518Y69980D02*
Y68996D01*
G01Y87697D02*
Y86713D01*
G01X67362Y73917D02*
Y72933D01*
G01Y83760D02*
Y82776D01*
G01X66496Y73917D02*
Y72933D01*
G01Y82776D02*
Y83760D01*
G01X66341Y68996D02*
Y69980D01*
G01Y86713D02*
Y87697D01*
G01X63581Y68996D02*
Y69980D01*
G01Y86713D02*
Y87697D01*
G01X63425Y66043D02*
Y65059D01*
G01Y91634D02*
Y90650D01*
G01X62559Y66043D02*
Y65059D01*
G01Y90650D02*
Y91634D01*
G01X62404Y69980D02*
Y68996D01*
G01Y87697D02*
Y86713D01*
G01X59644Y69980D02*
Y68996D01*
G01Y87697D02*
Y86713D01*
G01X59488Y73917D02*
Y72933D01*
G01Y83760D02*
Y82776D01*
G01X71441Y90201D02*
X71445Y88414D01*
G01X71436Y88146D02*
X71431Y89933D01*
G01X70296Y68547D02*
X70302Y66760D01*
G01X70292Y66493D02*
X70287Y68280D01*
G01X67504Y72484D02*
X67508Y70697D01*
G01X67499Y70430D02*
X67494Y72217D01*
G01X66359Y86264D02*
X66365Y84477D01*
G01X66355Y84209D02*
X66350Y85996D01*
G01X63567Y90201D02*
X63571Y88414D01*
G01X63562Y88146D02*
X63557Y89933D01*
G01X62422Y68547D02*
X62428Y66760D01*
G01X62418Y66493D02*
X62413Y68280D01*
G01X59630Y72484D02*
X59634Y70697D01*
G01X59625Y70430D02*
X59620Y72217D01*
G01X71519Y74803D02*
X71494Y76304D01*
G01X71491Y75394D02*
X71501Y74803D01*
G01X70241Y81299D02*
X70231Y81890D01*
G01X70213D02*
X70239Y80389D01*
G01X67582Y74803D02*
X67557Y76304D01*
G01X67554Y75394D02*
X67564Y74803D01*
G01X66304Y81299D02*
X66294Y81890D01*
G01X66276D02*
X66302Y80389D01*
G01X63645Y74803D02*
X63620Y76304D01*
G01X63617Y75394D02*
X63627Y74803D01*
G01X62367Y81299D02*
X62357Y81890D01*
G01X62339D02*
X62365Y80389D01*
G01X59708Y74803D02*
X59683Y76304D01*
G01X59680Y75394D02*
X59690Y74803D01*
G01X71472Y81229D02*
X71459Y81890D01*
G01X71439D02*
X71470Y80301D01*
G01X70293Y74803D02*
X70263Y76392D01*
G01X70260Y75464D02*
X70273Y74803D01*
G01X67535Y81229D02*
X67522Y81890D01*
G01X67502D02*
X67533Y80301D01*
G01X66356Y74803D02*
X66326Y76392D01*
G01X66323Y75464D02*
X66336Y74803D01*
G01X63598Y81229D02*
X63585Y81890D01*
G01X63565D02*
X63596Y80301D01*
G01X62419Y74803D02*
X62389Y76392D01*
G01X62386Y75464D02*
X62399Y74803D01*
G01X59661Y81229D02*
X59648Y81890D01*
G01X59628D02*
X59659Y80301D01*
G01X58452D02*
X58482Y81890D01*
G01X58462D02*
X58449Y81229D01*
G01X55711Y74803D02*
X55724Y75464D01*
G01X55722Y76392D02*
X55691Y74803D01*
G01X54515Y80301D02*
X54545Y81890D01*
G01X54525D02*
X54512Y81229D01*
G01X51774Y74803D02*
X51787Y75464D01*
G01X51785Y76392D02*
X51754Y74803D01*
G01X50578Y80301D02*
X50608Y81890D01*
G01X50588D02*
X50575Y81229D01*
G01X47837Y74803D02*
X47850Y75464D01*
G01X47848Y76392D02*
X47817Y74803D01*
G01X58420D02*
X58430Y75394D01*
G01X58428Y76304D02*
X58403Y74803D01*
G01X55746Y80389D02*
X55771Y81890D01*
G01X55753D02*
X55743Y81299D01*
G01X54483Y74803D02*
X54493Y75394D01*
G01X54491Y76304D02*
X54466Y74803D01*
G01X51809Y80389D02*
X51834Y81890D01*
G01X51816D02*
X51806Y81299D01*
G01X50546Y74803D02*
X50556Y75394D01*
G01X50554Y76304D02*
X50529Y74803D01*
G01X47872Y80389D02*
X47897Y81890D01*
G01X47879D02*
X47869Y81299D01*
G01X58491Y72217D02*
X58485Y70430D01*
G01X58476Y70697D02*
X58481Y72484D01*
G01X55697Y68280D02*
X55693Y66493D01*
G01X55683Y66760D02*
X55688Y68547D01*
G01X54554Y89933D02*
X54548Y88146D01*
G01X54539Y88414D02*
X54544Y90201D01*
G01X51760Y85996D02*
X51756Y84209D01*
G01X51746Y84477D02*
X51751Y86264D01*
G01X50617Y72217D02*
X50611Y70430D01*
G01X50602Y70697D02*
X50607Y72484D01*
G01X47823Y68280D02*
X47819Y66493D01*
G01X47809Y66760D02*
X47814Y68547D01*
G01X58622Y73917D02*
Y72933D01*
G01Y82776D02*
Y83760D01*
G01X58467Y68996D02*
Y69980D01*
G01Y86713D02*
Y87697D01*
G01X55707Y68996D02*
Y69980D01*
G01Y86713D02*
Y87697D01*
G01X55551Y66043D02*
Y65059D01*
G01Y91634D02*
Y90650D01*
G01X54685Y66043D02*
Y65059D01*
G01Y90650D02*
Y91634D01*
G01X54530Y69980D02*
Y68996D01*
G01Y87697D02*
Y86713D01*
G01X54173Y98425D02*
Y92815D01*
G01X51770Y69980D02*
Y68996D01*
G01Y87697D02*
Y86713D01*
G01X51614Y73917D02*
Y72933D01*
G01Y83760D02*
Y82776D01*
G01X50748Y73917D02*
Y72933D01*
G01Y82776D02*
Y83760D01*
G01X50593Y68996D02*
Y69980D01*
G01Y86713D02*
Y87697D01*
G01X49173Y98425D02*
Y92815D01*
G01X47833Y68996D02*
Y69980D01*
G01Y86713D02*
Y87697D01*
G01X47677Y66043D02*
Y65059D01*
G01Y91634D02*
Y90650D01*
G01X58485Y86264D02*
X58491Y84477D01*
G01X58481Y84209D02*
X58476Y85996D01*
G01X55693Y90201D02*
X55697Y88414D01*
G01X55688Y88146D02*
X55683Y89933D01*
G01X54548Y68547D02*
X54554Y66760D01*
G01X54544Y66493D02*
X54539Y68280D01*
G01X51756Y72484D02*
X51760Y70697D01*
G01X51751Y70430D02*
X51746Y72217D01*
G01X50611Y86264D02*
X50617Y84477D01*
G01X50607Y84209D02*
X50602Y85996D01*
G01X47819Y90201D02*
X47823Y88414D01*
G01X47814Y88146D02*
X47809Y89933D01*
G01X58430Y81299D02*
X58420Y81890D01*
G01X58402D02*
X58428Y80389D01*
G01X55771Y74803D02*
X55746Y76304D01*
G01X55743Y75394D02*
X55753Y74803D01*
G01X54493Y81299D02*
X54483Y81890D01*
G01X54465D02*
X54491Y80389D01*
G01X51834Y74803D02*
X51809Y76304D01*
G01X51806Y75394D02*
X51816Y74803D01*
G01X50556Y81299D02*
X50546Y81890D01*
G01X50528D02*
X50554Y80389D01*
G01X47897Y74803D02*
X47872Y76304D01*
G01X47869Y75394D02*
X47879Y74803D01*
G01X58482D02*
X58452Y76392D01*
G01X58449Y75464D02*
X58462Y74803D01*
G01X55724Y81229D02*
X55711Y81890D01*
G01X55691D02*
X55722Y80301D01*
G01X54545Y74803D02*
X54515Y76392D01*
G01X54512Y75464D02*
X54525Y74803D01*
G01X51787Y81229D02*
X51774Y81890D01*
G01X51754D02*
X51785Y80301D01*
G01X50608Y74803D02*
X50578Y76392D01*
G01X50575Y75464D02*
X50588Y74803D01*
G01X47850Y81229D02*
X47837Y81890D01*
G01X47817D02*
X47848Y80301D01*
G01X63189Y161811D02*
G03X67126Y165748I0J3937D01*
G01X73425D02*
G03X77362Y161811I3937J0D01*
G01X89173D02*
G03X93110Y165748I0J3937D01*
G01X99409D02*
G03X103346Y161811I3937J0D01*
G01X63189D02*
X51378D01*
G01X89173D02*
X77362D01*
G01X115157D02*
X103346D01*
G01X89173Y114567D02*
G03Y106693I0J-3937D01*
G01X58465D02*
G03Y114567I0J3937D01*
G01X67126Y177559D02*
G03X63189Y181496I-3937J0D01*
G01X77362D02*
G03X73425Y177559I0J-3937D01*
G01X93110D02*
G03X89173Y181496I-3937J0D01*
G01X103346D02*
G03X99409Y177559I0J-3937D01*
G01X67126D02*
Y165748D01*
G01X73425D02*
Y177559D01*
G01X93110D02*
Y165748D01*
G01X99409D02*
Y177559D01*
G01X103346Y181496D02*
X115157D01*
G01X77362D02*
X89173D01*
G01X51378D02*
X63189D01*
G01X65157Y191930D02*
G03X72638I3740J0D01*
G01X65157Y219292D02*
Y191930D01*
G01X74606Y221260D02*
X72638Y219292D01*
G01D02*
Y191930D01*
G01X65157Y219292D02*
X63189Y221260D01*
G01X74606D02*
X350984D01*
G01X89173Y349607D02*
G03Y341733I0J-3937D01*
G01X58465D02*
G03Y349607I0J3937D01*
G01X63189Y396851D02*
G03X67126Y400788I0J3937D01*
G01X73425D02*
G03X77362Y396851I3937J0D01*
G01X89173D02*
G03X93110Y400788I0J3937D01*
G01X99409D02*
G03X103346Y396851I3937J0D01*
G01X67126Y412599D02*
Y400788D01*
G01X73425D02*
Y412599D01*
G01X93110D02*
Y400788D01*
G01X99409D02*
Y412599D01*
G01X63189Y396851D02*
X51378D01*
G01X89173D02*
X77362D01*
G01X115157D02*
X103346D01*
G01X67126Y412599D02*
G03X63189Y416536I-3937J0D01*
G01X77362D02*
G03X73425Y412599I0J-3937D01*
G01X93110D02*
G03X89173Y416536I-3937J0D01*
G01X103346D02*
G03X99409Y412599I0J-3937D01*
G01X103346Y416536D02*
X115157D01*
G01X77362D02*
X89173D01*
G01X51378D02*
X63189D01*
G01X65157Y426969D02*
G03X72638I3740J0D01*
G01X65157Y454331D02*
Y426969D01*
G01X74606Y456300D02*
X72638Y454331D01*
G01D02*
Y426969D01*
G01X65157Y454331D02*
X63189Y456300D01*
G01X74606D02*
X350984D01*
G01X89173Y584646D02*
G03Y576772I0J-3937D01*
G01X58465D02*
G03Y584646I0J3937D01*
G01X67126Y647639D02*
G03X63189Y651576I-3937J0D01*
G01Y631891D02*
G03X67126Y635828I0J3937D01*
G01X73425D02*
G03X77362Y631891I3937J0D01*
G01Y651576D02*
G03X73425Y647639I0J-3937D01*
G01X93110D02*
G03X89173Y651576I-3937J0D01*
G01Y631891D02*
G03X93110Y635828I0J3937D01*
G01X103346Y651576D02*
G03X99409Y647639I0J-3937D01*
G01Y635828D02*
G03X103346Y631891I3937J0D01*
G01X67126Y647639D02*
Y635828D01*
G01X73425D02*
Y647639D01*
G01X93110D02*
Y635828D01*
G01X99409D02*
Y647639D01*
G01X63189Y631891D02*
X51378D01*
G01X89173D02*
X77362D01*
G01X115157D02*
X103346D01*
G01Y651576D02*
X115157D01*
G01X77362D02*
X89173D01*
G01X51378D02*
X63189D01*
G01X65157Y662009D02*
G03X72638I3740J0D01*
G01X65157Y689371D02*
Y662009D01*
G01X74606Y691339D02*
X72638Y689371D01*
G01D02*
Y662009D01*
G01X65157Y689371D02*
X63189Y691339D01*
G01X74606D02*
X350984D01*
G01X167913Y5512D02*
Y22047D01*
G01X166732D02*
Y5512D01*
G01X163976D02*
Y22047D01*
G01X167913D02*
X170669D01*
G01X163976D02*
X166732D01*
G01X160039D02*
X162795D01*
G01X156102D02*
X158858D01*
G01X152165D02*
X154921D01*
G01X148228D02*
X150984D01*
G01X144291D02*
X147047D01*
G01X140354D02*
X143110D01*
G01X136417D02*
X139173D01*
G01X132480D02*
X135236D01*
G01X128543D02*
X131299D01*
G01X124606D02*
X127362D01*
G01X120669D02*
X123425D01*
G01X116732D02*
X119488D01*
G01X112795D02*
X115551D01*
G01X108858D02*
X111614D01*
G01X162795D02*
Y5512D01*
G01X160039D02*
Y22047D01*
G01X158858D02*
Y5512D01*
G01X156102D02*
Y22047D01*
G01X154921D02*
Y5512D01*
G01X152165D02*
Y22047D01*
G01X150984D02*
Y5512D01*
G01X111614D02*
X108858D01*
G01X115551D02*
X112795D01*
G01X119488D02*
X116732D01*
G01X123425D02*
X120669D01*
G01X127362D02*
X124606D01*
G01X131299D02*
X128543D01*
G01X135236D02*
X132480D01*
G01X139173D02*
X136417D01*
G01X143110D02*
X140354D01*
G01X147047D02*
X144291D01*
G01X150984D02*
X148228D01*
G01X154921D02*
X152165D01*
G01X158858D02*
X156102D01*
G01X162795D02*
X160039D01*
G01X166732D02*
X163976D01*
G01X170669D02*
X167913D01*
G01X148228D02*
Y22047D01*
G01X147047D02*
Y5512D01*
G01X144291D02*
Y22047D01*
G01X143110D02*
Y5512D01*
G01X140354D02*
Y22047D01*
G01X139173D02*
Y5512D01*
G01X136417D02*
Y22047D01*
G01X135236D02*
Y5512D01*
G01X132480D02*
Y22047D01*
G01X131299D02*
Y5512D01*
G01X128543D02*
Y22047D01*
G01X127362D02*
Y5512D01*
G01X124606D02*
Y22047D01*
G01X123425D02*
Y5512D01*
G01X120669D02*
Y22047D01*
G01X119488D02*
Y5512D01*
G01X116732D02*
Y22047D01*
G01X115551D02*
Y5512D01*
G01X112795D02*
Y22047D01*
G01X111614D02*
Y5512D01*
G01X108858D02*
Y22047D01*
G01X147638Y102756D02*
G03X151575Y98819I3937J0D01*
G01X147638Y102756D02*
G03X143701Y106693I-3937J0D01*
G01X151575Y98819D02*
X112205D01*
G01D02*
Y106693D01*
G01X147638Y102756D02*
G03X151575Y98819I3937J0D01*
G01X147638Y102756D02*
G03X143701Y106693I-3937J0D01*
G01X147638Y102756D02*
G03X151575Y98819I3937J0D01*
G01X147638Y102756D02*
G03X143701Y106693I-3937J0D01*
G01X151575Y98819D02*
X222441D01*
G01X132795Y98425D02*
X116890D01*
G01X153701D02*
X137795D01*
G01X174606D02*
X158701D01*
G01X110792Y91634D02*
X109681D01*
G01X118666D02*
X117555D01*
G01X126540D02*
X125429D01*
G01X134414D02*
X133303D01*
G01X142288D02*
X141177D01*
G01X150162D02*
X149051D01*
G01X158036D02*
X156925D01*
G01X165910D02*
X164799D01*
G01X110792Y90650D02*
X109681D01*
G01X118666D02*
X117555D01*
G01X126540D02*
X125429D01*
G01X134414D02*
X133303D01*
G01X142288D02*
X141177D01*
G01X150162D02*
X149051D01*
G01X158036D02*
X156925D01*
G01X165910D02*
X164799D01*
G01X164780Y90201D02*
X165929D01*
G01X156906D02*
X158055D01*
G01X149032D02*
X150181D01*
G01X141158D02*
X142307D01*
G01X133284D02*
X134433D01*
G01X125410D02*
X126559D01*
G01X117536D02*
X118685D01*
G01X109662D02*
X110811D01*
G01X110801Y89933D02*
X109672D01*
G01X118675D02*
X117546D01*
G01X126549D02*
X125420D01*
G01X134423D02*
X133294D01*
G01X142297D02*
X141168D01*
G01X150171D02*
X149042D01*
G01X158045D02*
X156916D01*
G01X165919D02*
X164790D01*
G01X110815Y88414D02*
X109657D01*
G01X118689D02*
X117531D01*
G01X126563D02*
X125405D01*
G01X134437D02*
X133279D01*
G01X142311D02*
X141153D01*
G01X150185D02*
X149027D01*
G01X158059D02*
X156901D01*
G01X165933D02*
X164775D01*
G01X164785Y88146D02*
X165924D01*
G01X156911D02*
X158050D01*
G01X149037D02*
X150176D01*
G01X141163D02*
X142302D01*
G01X133289D02*
X134428D01*
G01X125415D02*
X126554D01*
G01X117541D02*
X118680D01*
G01X109667D02*
X110806D01*
G01X110825Y87697D02*
X109648D01*
G01X114762D02*
X113585D01*
G01X118699D02*
X117522D01*
G01X122636D02*
X121459D01*
G01X126573D02*
X125396D01*
G01X130510D02*
X129333D01*
G01X134447D02*
X133270D01*
G01X138384D02*
X137207D01*
G01X142321D02*
X141144D01*
G01X146258D02*
X145081D01*
G01X150195D02*
X149018D01*
G01X154132D02*
X152955D01*
G01X158069D02*
X156892D01*
G01X162006D02*
X160829D01*
G01X165943D02*
X164766D01*
G01X169880D02*
X168703D01*
G01X110825Y86713D02*
X109648D01*
G01X114762D02*
X113585D01*
G01X118699D02*
X117522D01*
G01X122636D02*
X121459D01*
G01X126573D02*
X125396D01*
G01X130510D02*
X129333D01*
G01X134447D02*
X133270D01*
G01X138384D02*
X137207D01*
G01X142321D02*
X141144D01*
G01X146258D02*
X145081D01*
G01X150195D02*
X149018D01*
G01X154132D02*
X152955D01*
G01X158069D02*
X156892D01*
G01X162006D02*
X160829D01*
G01X165943D02*
X164766D01*
G01X169880D02*
X168703D01*
G01X114743Y86264D02*
X113604D01*
G01X122617D02*
X121478D01*
G01X130491D02*
X129352D01*
G01X138365D02*
X137226D01*
G01X146239D02*
X145100D01*
G01X154113D02*
X152974D01*
G01X161987D02*
X160848D01*
G01X169861D02*
X168722D01*
G01X168712Y85996D02*
X169870D01*
G01X160838D02*
X161996D01*
G01X152964D02*
X154122D01*
G01X145090D02*
X146248D01*
G01X137216D02*
X138374D01*
G01X129342D02*
X130500D01*
G01X121468D02*
X122626D01*
G01X113594D02*
X114752D01*
G01X168727Y84477D02*
X169856D01*
G01X160853D02*
X161982D01*
G01X152979D02*
X154108D01*
G01X145105D02*
X146234D01*
G01X137231D02*
X138360D01*
G01X129357D02*
X130486D01*
G01X121483D02*
X122612D01*
G01X113609D02*
X114738D01*
G01X114748Y84209D02*
X113599D01*
G01X122622D02*
X121473D01*
G01X130496D02*
X129347D01*
G01X138370D02*
X137221D01*
G01X146244D02*
X145095D01*
G01X154118D02*
X152969D01*
G01X161992D02*
X160843D01*
G01X169866D02*
X168717D01*
G01X114729Y83760D02*
X113618D01*
G01X122603D02*
X121492D01*
G01X130477D02*
X129366D01*
G01X138351D02*
X137240D01*
G01X146225D02*
X145114D01*
G01X154099D02*
X152988D01*
G01X161973D02*
X160862D01*
G01X169847D02*
X168736D01*
G01X114729Y82776D02*
X113618D01*
G01X122603D02*
X121492D01*
G01X130477D02*
X129366D01*
G01X138351D02*
X137240D01*
G01X146225D02*
X145114D01*
G01X154099D02*
X152988D01*
G01X161973D02*
X160862D01*
G01X169847D02*
X168736D01*
G01X110861Y81299D02*
X109611D01*
G01X114798D02*
X113548D01*
G01X118735D02*
X117485D01*
G01X122672D02*
X121422D01*
G01X126609D02*
X125359D01*
G01X130546D02*
X129296D01*
G01X134483D02*
X133233D01*
G01X138420D02*
X137170D01*
G01X142357D02*
X141107D01*
G01X146294D02*
X145044D01*
G01X150231D02*
X148981D01*
G01X154169D02*
X152918D01*
G01X158106D02*
X156855D01*
G01X162043D02*
X160792D01*
G01X165980D02*
X164729D01*
G01X169917D02*
X168666D01*
G01X168685Y81229D02*
X169897D01*
G01X164748D02*
X165960D01*
G01X160811D02*
X162023D01*
G01X156874D02*
X158086D01*
G01X152937D02*
X154149D01*
G01X149000D02*
X150212D01*
G01X145063D02*
X146275D01*
G01X141126D02*
X142338D01*
G01X137189D02*
X138401D01*
G01X133252D02*
X134464D01*
G01X129315D02*
X130527D01*
G01X125378D02*
X126590D01*
G01X121441D02*
X122653D01*
G01X117504D02*
X118716D01*
G01X113567D02*
X114779D01*
G01X109630D02*
X110842D01*
G01X110851Y81004D02*
X109621D01*
G01X114788D02*
X113558D01*
G01X118725D02*
X117495D01*
G01X122662D02*
X121432D01*
G01X126599D02*
X125369D01*
G01X130536D02*
X129306D01*
G01X134473D02*
X133243D01*
G01X138410D02*
X137180D01*
G01X142347D02*
X141117D01*
G01X146284D02*
X145054D01*
G01X150221D02*
X148991D01*
G01X154158D02*
X152928D01*
G01X158095D02*
X156865D01*
G01X162032D02*
X160802D01*
G01X165969D02*
X164739D01*
G01X169906D02*
X168676D01*
G01X168664Y80389D02*
X169919D01*
G01X164727D02*
X165982D01*
G01X160790D02*
X162045D01*
G01X156853D02*
X158108D01*
G01X152916D02*
X154171D01*
G01X148979D02*
X150234D01*
G01X145042D02*
X146297D01*
G01X141105D02*
X142360D01*
G01X137168D02*
X138423D01*
G01X133231D02*
X134486D01*
G01X129294D02*
X130549D01*
G01X125357D02*
X126612D01*
G01X121420D02*
X122675D01*
G01X117483D02*
X118738D01*
G01X113546D02*
X114801D01*
G01X109609D02*
X110864D01*
G01X110840Y80301D02*
X109633D01*
G01X114777D02*
X113570D01*
G01X118714D02*
X117507D01*
G01X122651D02*
X121444D01*
G01X126588D02*
X125381D01*
G01X130525D02*
X129318D01*
G01X134462D02*
X133255D01*
G01X138399D02*
X137192D01*
G01X142336D02*
X141129D01*
G01X146273D02*
X145066D01*
G01X150210D02*
X149003D01*
G01X154147D02*
X152940D01*
G01X158084D02*
X156877D01*
G01X162021D02*
X160814D01*
G01X165958D02*
X164751D01*
G01X169895D02*
X168688D01*
G01X110851Y80019D02*
X109621D01*
G01X114788D02*
X113558D01*
G01X118725D02*
X117495D01*
G01X122662D02*
X121432D01*
G01X126599D02*
X125369D01*
G01X130536D02*
X129306D01*
G01X134473D02*
X133243D01*
G01X138410D02*
X137180D01*
G01X142347D02*
X141117D01*
G01X146284D02*
X145054D01*
G01X150221D02*
X148991D01*
G01X154158D02*
X152928D01*
G01X158095D02*
X156865D01*
G01X162032D02*
X160802D01*
G01X165969D02*
X164739D01*
G01X169906D02*
X168676D01*
G01X168677Y76674D02*
X169906D01*
G01X164740D02*
X165969D01*
G01X160803D02*
X162032D01*
G01X156866D02*
X158095D01*
G01X152929D02*
X154158D01*
G01X148992D02*
X150221D01*
G01X145055D02*
X146284D01*
G01X141118D02*
X142347D01*
G01X137181D02*
X138410D01*
G01X133244D02*
X134473D01*
G01X129307D02*
X130536D01*
G01X125370D02*
X126599D01*
G01X121433D02*
X122662D01*
G01X117496D02*
X118725D01*
G01X113559D02*
X114788D01*
G01X109622D02*
X110851D01*
G01X168688Y76392D02*
X169895D01*
G01X164751D02*
X165958D01*
G01X160814D02*
X162021D01*
G01X156877D02*
X158084D01*
G01X152940D02*
X154147D01*
G01X149003D02*
X150210D01*
G01X145066D02*
X146273D01*
G01X141129D02*
X142336D01*
G01X137192D02*
X138399D01*
G01X133255D02*
X134462D01*
G01X129318D02*
X130525D01*
G01X125381D02*
X126588D01*
G01X121444D02*
X122651D01*
G01X117507D02*
X118714D01*
G01X113570D02*
X114777D01*
G01X109633D02*
X110840D01*
G01X110864Y76304D02*
X109609D01*
G01X114801D02*
X113546D01*
G01X118738D02*
X117483D01*
G01X122675D02*
X121420D01*
G01X126612D02*
X125357D01*
G01X130549D02*
X129294D01*
G01X134486D02*
X133231D01*
G01X138423D02*
X137168D01*
G01X142360D02*
X141105D01*
G01X146297D02*
X145042D01*
G01X150234D02*
X148979D01*
G01X154171D02*
X152916D01*
G01X158108D02*
X156853D01*
G01X162045D02*
X160790D01*
G01X165982D02*
X164727D01*
G01X169919D02*
X168664D01*
G01X168677Y75690D02*
X169906D01*
G01X164740D02*
X165969D01*
G01X160803D02*
X162032D01*
G01X156866D02*
X158095D01*
G01X152929D02*
X154158D01*
G01X148992D02*
X150221D01*
G01X145055D02*
X146284D01*
G01X141118D02*
X142347D01*
G01X137181D02*
X138410D01*
G01X133244D02*
X134473D01*
G01X129307D02*
X130536D01*
G01X125370D02*
X126599D01*
G01X121433D02*
X122662D01*
G01X117496D02*
X118725D01*
G01X113559D02*
X114788D01*
G01X109622D02*
X110851D01*
G01X110842Y75464D02*
X109630D01*
G01X114779D02*
X113567D01*
G01X118716D02*
X117504D01*
G01X122653D02*
X121441D01*
G01X126590D02*
X125378D01*
G01X130527D02*
X129315D01*
G01X134464D02*
X133252D01*
G01X138401D02*
X137189D01*
G01X142338D02*
X141126D01*
G01X146275D02*
X145063D01*
G01X150212D02*
X149000D01*
G01X154149D02*
X152937D01*
G01X158086D02*
X156874D01*
G01X162023D02*
X160811D01*
G01X165960D02*
X164748D01*
G01X169897D02*
X168685D01*
G01X168666Y75394D02*
X169917D01*
G01X164729D02*
X165980D01*
G01X160792D02*
X162043D01*
G01X156855D02*
X158106D01*
G01X152918D02*
X154169D01*
G01X148981D02*
X150231D01*
G01X145044D02*
X146294D01*
G01X141107D02*
X142357D01*
G01X137170D02*
X138420D01*
G01X133233D02*
X134483D01*
G01X129296D02*
X130546D01*
G01X125359D02*
X126609D01*
G01X121422D02*
X122672D01*
G01X117485D02*
X118735D01*
G01X113548D02*
X114798D01*
G01X109611D02*
X110861D01*
G01X168736Y73917D02*
X169847D01*
G01X160862D02*
X161973D01*
G01X152988D02*
X154099D01*
G01X145114D02*
X146225D01*
G01X137240D02*
X138351D01*
G01X129366D02*
X130477D01*
G01X121492D02*
X122603D01*
G01X113618D02*
X114729D01*
G01X168736Y72933D02*
X169847D01*
G01X160862D02*
X161973D01*
G01X152988D02*
X154099D01*
G01X145114D02*
X146225D01*
G01X137240D02*
X138351D01*
G01X129366D02*
X130477D01*
G01X121492D02*
X122603D01*
G01X113618D02*
X114729D01*
G01X168717Y72484D02*
X169866D01*
G01X160843D02*
X161992D01*
G01X152969D02*
X154118D01*
G01X145095D02*
X146244D01*
G01X137221D02*
X138370D01*
G01X129347D02*
X130496D01*
G01X121473D02*
X122622D01*
G01X113599D02*
X114748D01*
G01X114738Y72217D02*
X113609D01*
G01X122612D02*
X121483D01*
G01X130486D02*
X129357D01*
G01X138360D02*
X137231D01*
G01X146234D02*
X145105D01*
G01X154108D02*
X152979D01*
G01X161982D02*
X160853D01*
G01X169856D02*
X168727D01*
G01X114752Y70697D02*
X113594D01*
G01X122626D02*
X121469D01*
G01X130500D02*
X129343D01*
G01X138374D02*
X137217D01*
G01X146248D02*
X145091D01*
G01X154122D02*
X152965D01*
G01X161996D02*
X160839D01*
G01X169870D02*
X168713D01*
G01X168722Y70430D02*
X169861D01*
G01X160848D02*
X161987D01*
G01X152974D02*
X154113D01*
G01X145100D02*
X146239D01*
G01X137226D02*
X138365D01*
G01X129352D02*
X130491D01*
G01X121478D02*
X122617D01*
G01X113604D02*
X114743D01*
G01X168703Y69980D02*
X169880D01*
G01X164766D02*
X165943D01*
G01X160829D02*
X162006D01*
G01X156892D02*
X158069D01*
G01X152955D02*
X154132D01*
G01X149018D02*
X150195D01*
G01X145081D02*
X146258D01*
G01X141144D02*
X142321D01*
G01X137207D02*
X138384D01*
G01X133270D02*
X134447D01*
G01X129333D02*
X130510D01*
G01X125396D02*
X126573D01*
G01X121459D02*
X122636D01*
G01X117522D02*
X118699D01*
G01X113585D02*
X114762D01*
G01X109648D02*
X110825D01*
G01Y68996D02*
X109648D01*
G01X114762D02*
X113585D01*
G01X118699D02*
X117522D01*
G01X122636D02*
X121459D01*
G01X126573D02*
X125396D01*
G01X130510D02*
X129333D01*
G01X134447D02*
X133270D01*
G01X138384D02*
X137207D01*
G01X142321D02*
X141144D01*
G01X146258D02*
X145081D01*
G01X150195D02*
X149018D01*
G01X154132D02*
X152955D01*
G01X158069D02*
X156892D01*
G01X162006D02*
X160829D01*
G01X165943D02*
X164766D01*
G01X169880D02*
X168703D01*
G01X110806Y68547D02*
X109667D01*
G01X118680D02*
X117541D01*
G01X126554D02*
X125415D01*
G01X134428D02*
X133289D01*
G01X142302D02*
X141163D01*
G01X150176D02*
X149037D01*
G01X158050D02*
X156911D01*
G01X165924D02*
X164785D01*
G01X164776Y68280D02*
X165933D01*
G01X156902D02*
X158059D01*
G01X149028D02*
X150185D01*
G01X141154D02*
X142311D01*
G01X133280D02*
X134437D01*
G01X125406D02*
X126563D01*
G01X117531D02*
X118689D01*
G01X109657D02*
X110815D01*
G01X164790Y66760D02*
X165919D01*
G01X156916D02*
X158045D01*
G01X149042D02*
X150171D01*
G01X141168D02*
X142297D01*
G01X133294D02*
X134423D01*
G01X125420D02*
X126549D01*
G01X117546D02*
X118675D01*
G01X109672D02*
X110801D01*
G01X110811Y66493D02*
X109662D01*
G01X118685D02*
X117536D01*
G01X126559D02*
X125410D01*
G01X134433D02*
X133284D01*
G01X142307D02*
X141158D01*
G01X150181D02*
X149032D01*
G01X158055D02*
X156906D01*
G01X165929D02*
X164780D01*
G01X164799Y66043D02*
X165910D01*
G01X156925D02*
X158036D01*
G01X149051D02*
X150162D01*
G01X141177D02*
X142288D01*
G01X133303D02*
X134414D01*
G01X125429D02*
X126540D01*
G01X117555D02*
X118666D01*
G01X109681D02*
X110792D01*
G01X164799Y65059D02*
X165910D01*
G01X156925D02*
X158036D01*
G01X149051D02*
X150162D01*
G01X141177D02*
X142288D01*
G01X133303D02*
X134414D01*
G01X125429D02*
X126540D01*
G01X117555D02*
X118666D01*
G01X109681D02*
X110792D01*
G01X168688Y80301D02*
X168719Y81890D01*
G01X168698D02*
X168685Y81229D01*
G01X165948Y74803D02*
X165960Y75464D01*
G01X165958Y76392D02*
X165928Y74803D01*
G01X164751Y80301D02*
X164781Y81890D01*
G01X164761D02*
X164748Y81229D01*
G01X168657Y74803D02*
X168666Y75394D01*
G01X168664Y76304D02*
X168639Y74803D01*
G01X165982Y80389D02*
X166007Y81890D01*
G01X165989D02*
X165980Y81299D01*
G01X164720Y74803D02*
X164729Y75394D01*
G01X164727Y76304D02*
X164702Y74803D01*
G01X168727Y72217D02*
X168722Y70430D01*
G01X168713Y70697D02*
X168717Y72484D01*
G01X165933Y68280D02*
X165929Y66493D01*
G01X165919Y66760D02*
X165924Y68547D01*
G01X164790Y89933D02*
X164785Y88146D01*
G01X164775Y88414D02*
X164780Y90201D01*
G01X168859Y73917D02*
Y72933D01*
G01X168858Y82776D02*
Y83760D01*
G01X168703Y69980D02*
Y68996D01*
G01Y86713D02*
Y87697D01*
G01X165943Y68996D02*
Y69980D01*
G01Y86713D02*
Y87697D01*
G01X165787Y66043D02*
Y65059D01*
G01Y91634D02*
Y90650D01*
G01X164922Y66043D02*
Y65059D01*
G01X164921Y90650D02*
Y91634D01*
G01X164766Y69980D02*
Y68996D01*
G01Y87697D02*
Y86713D01*
G01X168722Y86264D02*
X168727Y84477D01*
G01X168717Y84209D02*
X168712Y85996D01*
G01X165929Y90201D02*
X165933Y88414D01*
G01X165924Y88146D02*
X165919Y89933D01*
G01X164785Y68547D02*
X164790Y66760D01*
G01X164780Y66493D02*
X164776Y68280D01*
G01X168666Y81299D02*
X168656Y81890D01*
G01X168639D02*
X168664Y80389D01*
G01X166007Y74803D02*
X165982Y76304D01*
G01X165980Y75394D02*
X165989Y74803D01*
G01X164729Y81299D02*
X164719Y81890D01*
G01X164702D02*
X164727Y80389D01*
G01X168719Y74803D02*
X168688Y76392D01*
G01X168685Y75464D02*
X168698Y74803D01*
G01X165960Y81229D02*
X165948Y81890D01*
G01X165928D02*
X165958Y80301D01*
G01X164781Y74803D02*
X164751Y76392D01*
G01X164748Y75464D02*
X164761Y74803D01*
G01X162011D02*
X162023Y75464D01*
G01X162021Y76392D02*
X161991Y74803D01*
G01X160814Y80301D02*
X160844Y81890D01*
G01X160824D02*
X160811Y81229D01*
G01X158074Y74803D02*
X158086Y75464D01*
G01X158084Y76392D02*
X158054Y74803D01*
G01X156877Y80301D02*
X156907Y81890D01*
G01X156887D02*
X156874Y81229D01*
G01X154137Y74803D02*
X154149Y75464D01*
G01X154147Y76392D02*
X154117Y74803D01*
G01X152940Y80301D02*
X152970Y81890D01*
G01X152950D02*
X152937Y81229D01*
G01X162045Y80389D02*
X162070Y81890D01*
G01X162052D02*
X162043Y81299D01*
G01X160783Y74803D02*
X160792Y75394D01*
G01X160790Y76304D02*
X160765Y74803D01*
G01X158108Y80389D02*
X158133Y81890D01*
G01X158115D02*
X158106Y81299D01*
G01X156846Y74803D02*
X156855Y75394D01*
G01X156853Y76304D02*
X156828Y74803D01*
G01X154171Y80389D02*
X154196Y81890D01*
G01X154178D02*
X154169Y81299D01*
G01X152909Y74803D02*
X152918Y75394D01*
G01X152916Y76304D02*
X152891Y74803D01*
G01X161996Y85996D02*
X161992Y84209D01*
G01X161982Y84477D02*
X161987Y86264D01*
G01X160853Y72217D02*
X160848Y70430D01*
G01X160839Y70697D02*
X160843Y72484D01*
G01X158059Y68280D02*
X158055Y66493D01*
G01X158045Y66760D02*
X158050Y68547D01*
G01X156916Y89933D02*
X156911Y88146D01*
G01X156901Y88414D02*
X156906Y90201D01*
G01X154122Y85996D02*
X154118Y84209D01*
G01X154108Y84477D02*
X154113Y86264D01*
G01X152979Y72217D02*
X152974Y70430D01*
G01X152965Y70697D02*
X152969Y72484D01*
G01X150185Y68280D02*
X150181Y66493D01*
G01X150171Y66760D02*
X150176Y68547D01*
G01X162006Y69980D02*
Y68996D01*
G01Y87697D02*
Y86713D01*
G01X161850Y73917D02*
Y72933D01*
G01Y83760D02*
Y82776D01*
G01X160985Y73917D02*
Y72933D01*
G01X160984Y82776D02*
Y83760D01*
G01X160829Y68996D02*
Y69980D01*
G01Y86713D02*
Y87697D01*
G01X158701Y98425D02*
Y92815D01*
G01X158069Y68996D02*
Y69980D01*
G01Y86713D02*
Y87697D01*
G01X157913Y66043D02*
Y65059D01*
G01Y91634D02*
Y90650D01*
G01X157048Y66043D02*
Y65059D01*
G01X157047Y90650D02*
Y91634D01*
G01X156892Y69980D02*
Y68996D01*
G01Y87697D02*
Y86713D01*
G01X154132Y69980D02*
Y68996D01*
G01Y87697D02*
Y86713D01*
G01X153976Y73917D02*
Y72933D01*
G01Y83760D02*
Y82776D01*
G01X153701Y98425D02*
Y92815D01*
G01X153111Y73917D02*
Y72933D01*
G01X153110Y82776D02*
Y83760D01*
G01X152955Y68996D02*
Y69980D01*
G01Y86713D02*
Y87697D01*
G01X150195Y68996D02*
Y69980D01*
G01Y86713D02*
Y87697D01*
G01X150039Y66043D02*
Y65059D01*
G01Y91634D02*
Y90650D01*
G01X161992Y72484D02*
X161996Y70697D01*
G01X161987Y70430D02*
X161982Y72217D01*
G01X160848Y86264D02*
X160853Y84477D01*
G01X160843Y84209D02*
X160838Y85996D01*
G01X158055Y90201D02*
X158059Y88414D01*
G01X158050Y88146D02*
X158045Y89933D01*
G01X156911Y68547D02*
X156916Y66760D01*
G01X156906Y66493D02*
X156902Y68280D01*
G01X154118Y72484D02*
X154122Y70697D01*
G01X154113Y70430D02*
X154108Y72217D01*
G01X152974Y86264D02*
X152979Y84477D01*
G01X152969Y84209D02*
X152964Y85996D01*
G01X150181Y90201D02*
X150185Y88414D01*
G01X150176Y88146D02*
X150171Y89933D01*
G01X162070Y74803D02*
X162045Y76304D01*
G01X162043Y75394D02*
X162052Y74803D01*
G01X160792Y81299D02*
X160782Y81890D01*
G01X160765D02*
X160790Y80389D01*
G01X158133Y74803D02*
X158108Y76304D01*
G01X158106Y75394D02*
X158115Y74803D01*
G01X156855Y81299D02*
X156845Y81890D01*
G01X156828D02*
X156853Y80389D01*
G01X154196Y74803D02*
X154171Y76304D01*
G01X154169Y75394D02*
X154178Y74803D01*
G01X152918Y81299D02*
X152908Y81890D01*
G01X152891D02*
X152916Y80389D01*
G01X150259Y74803D02*
X150234Y76304D01*
G01X150231Y75394D02*
X150241Y74803D01*
G01X162023Y81229D02*
X162011Y81890D01*
G01X161991D02*
X162021Y80301D01*
G01X160844Y74803D02*
X160814Y76392D01*
G01X160811Y75464D02*
X160824Y74803D01*
G01X158086Y81229D02*
X158074Y81890D01*
G01X158054D02*
X158084Y80301D01*
G01X156907Y74803D02*
X156877Y76392D01*
G01X156874Y75464D02*
X156887Y74803D01*
G01X154149Y81229D02*
X154137Y81890D01*
G01X154117D02*
X154147Y80301D01*
G01X152970Y74803D02*
X152940Y76392D01*
G01X152937Y75464D02*
X152950Y74803D01*
G01X150212Y81229D02*
X150200Y81890D01*
G01X150180D02*
X150210Y80301D01*
G01X150200Y74803D02*
X150212Y75464D01*
G01X150210Y76392D02*
X150180Y74803D01*
G01X149003Y80301D02*
X149033Y81890D01*
G01X149013D02*
X149000Y81229D01*
G01X146263Y74803D02*
X146275Y75464D01*
G01X146273Y76392D02*
X146243Y74803D01*
G01X145066Y80301D02*
X145096Y81890D01*
G01X145076D02*
X145063Y81229D01*
G01X142326Y74803D02*
X142338Y75464D01*
G01X142336Y76392D02*
X142306Y74803D01*
G01X141129Y80301D02*
X141159Y81890D01*
G01X141139D02*
X141126Y81229D01*
G01X138389Y74803D02*
X138401Y75464D01*
G01X138399Y76392D02*
X138369Y74803D01*
G01X150234Y80389D02*
X150259Y81890D01*
G01X150241D02*
X150231Y81299D01*
G01X148972Y74803D02*
X148981Y75394D01*
G01X148979Y76304D02*
X148954Y74803D01*
G01X146297Y80389D02*
X146322Y81890D01*
G01X146304D02*
X146294Y81299D01*
G01X145035Y74803D02*
X145044Y75394D01*
G01X145042Y76304D02*
X145017Y74803D01*
G01X142360Y80389D02*
X142385Y81890D01*
G01X142367D02*
X142357Y81299D01*
G01X141098Y74803D02*
X141107Y75394D01*
G01X141105Y76304D02*
X141080Y74803D01*
G01X138423Y80389D02*
X138448Y81890D01*
G01X138430D02*
X138420Y81299D01*
G01X149042Y89933D02*
X149037Y88146D01*
G01X149027Y88414D02*
X149032Y90201D01*
G01X146248Y85996D02*
X146244Y84209D01*
G01X146234Y84477D02*
X146239Y86264D01*
G01X145105Y72217D02*
X145100Y70430D01*
G01X145091Y70697D02*
X145095Y72484D01*
G01X142311Y68280D02*
X142307Y66493D01*
G01X142297Y66760D02*
X142302Y68547D01*
G01X141168Y89933D02*
X141163Y88146D01*
G01X141153Y88414D02*
X141158Y90201D01*
G01X138374Y85996D02*
X138370Y84209D01*
G01X138360Y84477D02*
X138365Y86264D01*
G01X137231Y72217D02*
X137226Y70430D01*
G01X137217Y70697D02*
X137221Y72484D01*
G01X149174Y66043D02*
Y65059D01*
G01X149173Y90650D02*
Y91634D01*
G01X149018Y69980D02*
Y68996D01*
G01Y87697D02*
Y86713D01*
G01X146258Y69980D02*
Y68996D01*
G01Y87697D02*
Y86713D01*
G01X146102Y73917D02*
Y72933D01*
G01Y83760D02*
Y82776D01*
G01X145237Y73917D02*
Y72933D01*
G01X145236Y82776D02*
Y83760D01*
G01X145081Y68996D02*
Y69980D01*
G01Y86713D02*
Y87697D01*
G01X142321Y68996D02*
Y69980D01*
G01Y86713D02*
Y87697D01*
G01X142165Y66043D02*
Y65059D01*
G01Y91634D02*
Y90650D01*
G01X141300Y66043D02*
Y65059D01*
G01X141299Y90650D02*
Y91634D01*
G01X141144Y69980D02*
Y68996D01*
G01Y87697D02*
Y86713D01*
G01X138384Y69980D02*
Y68996D01*
G01Y87697D02*
Y86713D01*
G01X138228Y73917D02*
Y72933D01*
G01Y83760D02*
Y82776D01*
G01X137795Y98425D02*
Y92815D01*
G01X137363Y73917D02*
Y72933D01*
G01X137362Y82776D02*
Y83760D01*
G01X137207Y68996D02*
Y69980D01*
G01Y86713D02*
Y87697D01*
G01X149037Y68547D02*
X149042Y66760D01*
G01X149032Y66493D02*
X149028Y68280D01*
G01X146244Y72484D02*
X146248Y70697D01*
G01X146239Y70430D02*
X146234Y72217D01*
G01X145100Y86264D02*
X145105Y84477D01*
G01X145095Y84209D02*
X145090Y85996D01*
G01X142307Y90201D02*
X142311Y88414D01*
G01X142302Y88146D02*
X142297Y89933D01*
G01X141163Y68547D02*
X141168Y66760D01*
G01X141158Y66493D02*
X141154Y68280D01*
G01X138370Y72484D02*
X138374Y70697D01*
G01X138365Y70430D02*
X138360Y72217D01*
G01X137226Y86264D02*
X137231Y84477D01*
G01X137221Y84209D02*
X137216Y85996D01*
G01X148981Y81299D02*
X148971Y81890D01*
G01X148954D02*
X148979Y80389D01*
G01X146322Y74803D02*
X146297Y76304D01*
G01X146294Y75394D02*
X146304Y74803D01*
G01X145044Y81299D02*
X145034Y81890D01*
G01X145017D02*
X145042Y80389D01*
G01X142385Y74803D02*
X142360Y76304D01*
G01X142357Y75394D02*
X142367Y74803D01*
G01X141107Y81299D02*
X141097Y81890D01*
G01X141080D02*
X141105Y80389D01*
G01X138448Y74803D02*
X138423Y76304D01*
G01X138420Y75394D02*
X138430Y74803D01*
G01X137170Y81299D02*
X137160Y81890D01*
G01X137143D02*
X137168Y80389D01*
G01X149033Y74803D02*
X149003Y76392D01*
G01X149000Y75464D02*
X149013Y74803D01*
G01X146275Y81229D02*
X146263Y81890D01*
G01X146243D02*
X146273Y80301D01*
G01X145096Y74803D02*
X145066Y76392D01*
G01X145063Y75464D02*
X145076Y74803D01*
G01X142338Y81229D02*
X142326Y81890D01*
G01X142306D02*
X142336Y80301D01*
G01X141159Y74803D02*
X141129Y76392D01*
G01X141126Y75464D02*
X141139Y74803D01*
G01X138401Y81229D02*
X138389Y81890D01*
G01X138369D02*
X138399Y80301D01*
G01X137222Y74803D02*
X137192Y76392D01*
G01X137189Y75464D02*
X137202Y74803D01*
G01X137192Y80301D02*
X137222Y81890D01*
G01X137202D02*
X137189Y81229D01*
G01X134452Y74803D02*
X134464Y75464D01*
G01X134462Y76392D02*
X134431Y74803D01*
G01X133255Y80301D02*
X133285Y81890D01*
G01X133265D02*
X133252Y81229D01*
G01X130515Y74803D02*
X130527Y75464D01*
G01X130525Y76392D02*
X130494Y74803D01*
G01X129318Y80301D02*
X129348Y81890D01*
G01X129328D02*
X129315Y81229D01*
G01X126578Y74803D02*
X126590Y75464D01*
G01X126588Y76392D02*
X126557Y74803D01*
G01X125381Y80301D02*
X125411Y81890D01*
G01X125391D02*
X125378Y81229D01*
G01X137161Y74803D02*
X137170Y75394D01*
G01X137168Y76304D02*
X137143Y74803D01*
G01X134486Y80389D02*
X134511Y81890D01*
G01X134493D02*
X134483Y81299D01*
G01X133224Y74803D02*
X133233Y75394D01*
G01X133231Y76304D02*
X133206Y74803D01*
G01X130549Y80389D02*
X130574Y81890D01*
G01X130556D02*
X130546Y81299D01*
G01X129287Y74803D02*
X129296Y75394D01*
G01X129294Y76304D02*
X129269Y74803D01*
G01X126612Y80389D02*
X126637Y81890D01*
G01X126619D02*
X126609Y81299D01*
G01X125350Y74803D02*
X125359Y75394D01*
G01X125357Y76304D02*
X125332Y74803D01*
G01X134437Y68280D02*
X134433Y66493D01*
G01X134423Y66760D02*
X134428Y68547D01*
G01X133294Y89933D02*
X133289Y88146D01*
G01X133279Y88414D02*
X133284Y90201D01*
G01X130500Y85996D02*
X130496Y84209D01*
G01X130486Y84477D02*
X130491Y86264D01*
G01X129357Y72217D02*
X129352Y70430D01*
G01X129343Y70697D02*
X129347Y72484D01*
G01X126563Y68280D02*
X126559Y66493D01*
G01X126549Y66760D02*
X126554Y68547D01*
G01X125420Y89933D02*
X125415Y88146D01*
G01X125405Y88414D02*
X125410Y90201D01*
G01X134447Y68996D02*
Y69980D01*
G01Y86713D02*
Y87697D01*
G01X134291Y66043D02*
Y65059D01*
G01Y91634D02*
Y90650D01*
G01X133426Y66043D02*
Y65059D01*
G01X133425Y90650D02*
Y91634D01*
G01X133270Y69980D02*
Y68996D01*
G01Y87697D02*
Y86713D01*
G01X132795Y98425D02*
Y92815D01*
G01X130510Y69980D02*
Y68996D01*
G01Y87697D02*
Y86713D01*
G01X130354Y73917D02*
Y72933D01*
G01Y83760D02*
Y82776D01*
G01X129489Y73917D02*
Y72933D01*
G01X129488Y82776D02*
Y83760D01*
G01X129333Y68996D02*
Y69980D01*
G01Y86713D02*
Y87697D01*
G01X126573Y68996D02*
Y69980D01*
G01Y86713D02*
Y87697D01*
G01X126417Y66043D02*
Y65059D01*
G01Y91634D02*
Y90650D01*
G01X125552Y66043D02*
Y65059D01*
G01X125551Y90650D02*
Y91634D01*
G01X125396Y69980D02*
Y68996D01*
G01Y87697D02*
Y86713D01*
G01X134433Y90201D02*
X134437Y88414D01*
G01X134428Y88146D02*
X134423Y89933D01*
G01X133289Y68547D02*
X133294Y66760D01*
G01X133284Y66493D02*
X133280Y68280D01*
G01X130496Y72484D02*
X130500Y70697D01*
G01X130491Y70430D02*
X130486Y72217D01*
G01X129352Y86264D02*
X129357Y84477D01*
G01X129347Y84209D02*
X129342Y85996D01*
G01X126559Y90201D02*
X126563Y88414D01*
G01X126554Y88146D02*
X126549Y89933D01*
G01X125415Y68547D02*
X125420Y66760D01*
G01X125410Y66493D02*
X125406Y68280D01*
G01X134511Y74803D02*
X134486Y76304D01*
G01X134483Y75394D02*
X134493Y74803D01*
G01X133233Y81299D02*
X133223Y81890D01*
G01X133206D02*
X133231Y80389D01*
G01X130574Y74803D02*
X130549Y76304D01*
G01X130546Y75394D02*
X130556Y74803D01*
G01X129296Y81299D02*
X129286Y81890D01*
G01X129269D02*
X129294Y80389D01*
G01X126637Y74803D02*
X126612Y76304D01*
G01X126609Y75394D02*
X126619Y74803D01*
G01X125359Y81299D02*
X125349Y81890D01*
G01X125331D02*
X125357Y80389D01*
G01X134464Y81229D02*
X134452Y81890D01*
G01X134431D02*
X134462Y80301D01*
G01X133285Y74803D02*
X133255Y76392D01*
G01X133252Y75464D02*
X133265Y74803D01*
G01X130527Y81229D02*
X130515Y81890D01*
G01X130494D02*
X130525Y80301D01*
G01X129348Y74803D02*
X129318Y76392D01*
G01X129315Y75464D02*
X129328Y74803D01*
G01X126590Y81229D02*
X126578Y81890D01*
G01X126557D02*
X126588Y80301D01*
G01X125411Y74803D02*
X125381Y76392D01*
G01X125378Y75464D02*
X125391Y74803D01*
G01X122641D02*
X122653Y75464D01*
G01X122651Y76392D02*
X122620Y74803D01*
G01X121444Y80301D02*
X121474Y81890D01*
G01X121454D02*
X121441Y81229D01*
G01X118704Y74803D02*
X118716Y75464D01*
G01X118714Y76392D02*
X118683Y74803D01*
G01X117507Y80301D02*
X117537Y81890D01*
G01X117517D02*
X117504Y81229D01*
G01X114767Y74803D02*
X114779Y75464D01*
G01X114777Y76392D02*
X114746Y74803D01*
G01X113570Y80301D02*
X113600Y81890D01*
G01X113580D02*
X113567Y81229D01*
G01X122675Y80389D02*
X122700Y81890D01*
G01X122682D02*
X122672Y81299D01*
G01X121413Y74803D02*
X121422Y75394D01*
G01X121420Y76304D02*
X121395Y74803D01*
G01X118738Y80389D02*
X118763Y81890D01*
G01X118745D02*
X118735Y81299D01*
G01X117476Y74803D02*
X117485Y75394D01*
G01X117483Y76304D02*
X117458Y74803D01*
G01X114801Y80389D02*
X114826Y81890D01*
G01X114808D02*
X114798Y81299D01*
G01X113539Y74803D02*
X113548Y75394D01*
G01X113546Y76304D02*
X113521Y74803D01*
G01X122626Y85996D02*
X122622Y84209D01*
G01X122612Y84477D02*
X122617Y86264D01*
G01X121483Y72217D02*
X121478Y70430D01*
G01X121469Y70697D02*
X121473Y72484D01*
G01X118689Y68280D02*
X118685Y66493D01*
G01X118675Y66760D02*
X118680Y68547D01*
G01X117546Y89933D02*
X117541Y88146D01*
G01X117531Y88414D02*
X117536Y90201D01*
G01X114752Y85996D02*
X114748Y84209D01*
G01X114738Y84477D02*
X114743Y86264D01*
G01X113609Y72217D02*
X113604Y70430D01*
G01X113594Y70697D02*
X113599Y72484D01*
G01X122636Y69980D02*
Y68996D01*
G01Y87697D02*
Y86713D01*
G01X122480Y73917D02*
Y72933D01*
G01Y83760D02*
Y82776D01*
G01X121615Y73917D02*
Y72933D01*
G01X121614Y82776D02*
Y83760D01*
G01X121459Y68996D02*
Y69980D01*
G01Y86713D02*
Y87697D01*
G01X118699Y68996D02*
Y69980D01*
G01Y86713D02*
Y87697D01*
G01X118543Y66043D02*
Y65059D01*
G01Y91634D02*
Y90650D01*
G01X117678Y66043D02*
Y65059D01*
G01X117677Y90650D02*
Y91634D01*
G01X117522Y69980D02*
Y68996D01*
G01Y87697D02*
Y86713D01*
G01X116890Y98425D02*
Y92815D01*
G01X114762Y69980D02*
Y68996D01*
G01Y87697D02*
Y86713D01*
G01X114606Y73917D02*
Y72933D01*
G01Y83760D02*
Y82776D01*
G01X113741Y73917D02*
Y72933D01*
G01X113740Y82776D02*
Y83760D01*
G01X113585Y68996D02*
Y69980D01*
G01Y86713D02*
Y87697D01*
G01X111890Y98425D02*
Y92815D01*
G01X122622Y72484D02*
X122626Y70697D01*
G01X122617Y70430D02*
X122612Y72217D01*
G01X121478Y86264D02*
X121483Y84477D01*
G01X121473Y84209D02*
X121468Y85996D01*
G01X118685Y90201D02*
X118689Y88414D01*
G01X118680Y88146D02*
X118675Y89933D01*
G01X117541Y68547D02*
X117546Y66760D01*
G01X117536Y66493D02*
X117531Y68280D01*
G01X114748Y72484D02*
X114752Y70697D01*
G01X114743Y70430D02*
X114738Y72217D01*
G01X113604Y86264D02*
X113609Y84477D01*
G01X113599Y84209D02*
X113594Y85996D01*
G01X122700Y74803D02*
X122675Y76304D01*
G01X122672Y75394D02*
X122682Y74803D01*
G01X121422Y81299D02*
X121412Y81890D01*
G01X121394D02*
X121420Y80389D01*
G01X118763Y74803D02*
X118738Y76304D01*
G01X118735Y75394D02*
X118745Y74803D01*
G01X117485Y81299D02*
X117475Y81890D01*
G01X117457D02*
X117483Y80389D01*
G01X114826Y74803D02*
X114801Y76304D01*
G01X114798Y75394D02*
X114808Y74803D01*
G01X113548Y81299D02*
X113538Y81890D01*
G01X113520D02*
X113546Y80389D01*
G01X110889Y74803D02*
X110864Y76304D01*
G01X110861Y75394D02*
X110871Y74803D01*
G01X122653Y81229D02*
X122641Y81890D01*
G01X122620D02*
X122651Y80301D01*
G01X121474Y74803D02*
X121444Y76392D01*
G01X121441Y75464D02*
X121454Y74803D01*
G01X118716Y81229D02*
X118704Y81890D01*
G01X118683D02*
X118714Y80301D01*
G01X117537Y74803D02*
X117507Y76392D01*
G01X117504Y75464D02*
X117517Y74803D01*
G01X114779Y81229D02*
X114767Y81890D01*
G01X114746D02*
X114777Y80301D01*
G01X113600Y74803D02*
X113570Y76392D01*
G01X113567Y75464D02*
X113580Y74803D01*
G01X110842Y81229D02*
X110830Y81890D01*
G01X110809D02*
X110840Y80301D01*
G01X110830Y74803D02*
X110842Y75464D01*
G01X110840Y76392D02*
X110809Y74803D01*
G01X109633Y80301D02*
X109663Y81890D01*
G01X109643D02*
X109630Y81229D01*
G01X110864Y80389D02*
X110889Y81890D01*
G01X110871D02*
X110861Y81299D01*
G01X109602Y74803D02*
X109611Y75394D01*
G01X109609Y76304D02*
X109584Y74803D01*
G01X110815Y68280D02*
X110811Y66493D01*
G01X110801Y66760D02*
X110806Y68547D01*
G01X109672Y89933D02*
X109667Y88146D01*
G01X109657Y88414D02*
X109662Y90201D01*
G01X110825Y68996D02*
Y69980D01*
G01Y87697D02*
Y86713D01*
G01X110669Y66043D02*
Y65059D01*
G01Y91634D02*
Y90650D01*
G01X109804Y66043D02*
Y65059D01*
G01X109803Y90650D02*
Y91634D01*
G01X109648Y69980D02*
Y68996D01*
G01Y86713D02*
Y87697D01*
G01X110811Y90201D02*
X110815Y88414D01*
G01X110806Y88146D02*
X110801Y89933D01*
G01X109667Y68547D02*
X109672Y66760D01*
G01X109662Y66493D02*
X109657Y68280D01*
G01X109611Y81299D02*
X109601Y81890D01*
G01X109583D02*
X109609Y80389D01*
G01X109663Y74803D02*
X109633Y76392D01*
G01X109630Y75464D02*
X109643Y74803D01*
G01X115157Y161811D02*
G03X119094Y165748I0J3937D01*
G01X151575Y122441D02*
G03X147638Y118504I0J-3937D01*
G01X143701Y114567D02*
G03X147638Y118504I0J3937D01*
G01X143701Y114567D02*
X112205D01*
G01X143701D02*
G03X147638Y118504I0J3937D01*
G01X151575Y122441D02*
G03X147638Y118504I0J-3937D01*
G01X151575Y122441D02*
G03X147638Y118504I0J-3937D01*
G01X143701Y114567D02*
G03X147638Y118504I0J3937D01*
G01X222441Y122441D02*
X151575D01*
G01X143701Y106693D02*
X112205D01*
G01X119094Y177559D02*
G03X115157Y181496I-3937J0D01*
G01X119094Y177559D02*
Y165748D01*
G01X147638Y337796D02*
G03X151575Y333859I3937J0D01*
G01X147638Y337796D02*
G03X143701Y341733I-3937J0D01*
G01D02*
X112205D01*
G01X147638Y337796D02*
G03X151575Y333859I3937J0D01*
G01X147638Y337796D02*
G03X143701Y341733I-3937J0D01*
G01X147638Y337796D02*
G03X151575Y333859I3937J0D01*
G01X147638Y337796D02*
G03X143701Y341733I-3937J0D01*
G01X151575Y333859D02*
X222441D01*
G01X115157Y396851D02*
G03X119094Y400788I0J3937D01*
G01Y412599D02*
Y400788D01*
G01X151575Y357481D02*
G03X147638Y353544I0J-3937D01*
G01X143701Y349607D02*
G03X147638Y353544I0J3937D01*
G01X143701Y349607D02*
X112205D01*
G01X143701D02*
G03X147638Y353544I0J3937D01*
G01X151575Y357481D02*
G03X147638Y353544I0J-3937D01*
G01X151575Y357481D02*
G03X147638Y353544I0J-3937D01*
G01X143701Y349607D02*
G03X147638Y353544I0J3937D01*
G01X222441Y357481D02*
X151575D01*
G01X119094Y412599D02*
G03X115157Y416536I-3937J0D01*
G01X147638Y572835D02*
G03X151575Y568898I3937J0D01*
G01X147638Y572835D02*
G03X143701Y576772I-3937J0D01*
G01D02*
X112205D01*
G01X147638Y572835D02*
G03X151575Y568898I3937J0D01*
G01X147638Y572835D02*
G03X143701Y576772I-3937J0D01*
G01X147638Y572835D02*
G03X151575Y568898I3937J0D01*
G01X147638Y572835D02*
G03X143701Y576772I-3937J0D01*
G01X151575Y568898D02*
X222441D01*
G01X151575Y592520D02*
G03X147638Y588583I0J-3937D01*
G01X143701Y584646D02*
G03X147638Y588583I0J3937D01*
G01X143701Y584646D02*
X112205D01*
G01X143701D02*
G03X147638Y588583I0J3937D01*
G01X151575Y592520D02*
G03X147638Y588583I0J-3937D01*
G01X151575Y592520D02*
G03X147638Y588583I0J-3937D01*
G01X143701Y584646D02*
G03X147638Y588583I0J3937D01*
G01X119094Y647639D02*
G03X115157Y651576I-3937J0D01*
G01Y631891D02*
G03X119094Y635828I0J3937D01*
G01Y647639D02*
Y635828D01*
G01X222441Y592520D02*
X151575D01*
G01X185945Y-426126D02*
Y-443449D01*
G01X229724Y22047D02*
Y5512D01*
G01X226969D02*
Y22047D01*
G01X225787D02*
Y5512D01*
G01X223031D02*
Y22047D01*
G01X221850D02*
Y5512D01*
G01X219094D02*
Y22047D01*
G01X217913D02*
Y5512D01*
G01X215157D02*
Y22047D01*
G01X213976D02*
Y5512D01*
G01X211220D02*
Y22047D01*
G01X210039D02*
Y5512D01*
G01X207283D02*
Y22047D01*
G01X206102D02*
Y5512D01*
G01X203346D02*
Y22047D01*
G01X202165D02*
Y5512D01*
G01X199409D02*
Y22047D01*
G01X198228D02*
Y5512D01*
G01X195472D02*
Y22047D01*
G01X194291D02*
Y5512D01*
G01X191535D02*
Y22047D01*
G01X190354D02*
Y5512D01*
G01X187598D02*
Y22047D01*
G01X186417D02*
Y5512D01*
G01X183661D02*
Y22047D01*
G01X182480D02*
Y5512D01*
G01X179724D02*
Y22047D01*
G01X178543D02*
Y5512D01*
G01X175787D02*
Y22047D01*
G01X174606D02*
Y5512D01*
G01X171850D02*
Y22047D01*
G01X170669D02*
Y5512D01*
G01X226969Y22047D02*
X229724D01*
G01X223031D02*
X225787D01*
G01X219094D02*
X221850D01*
G01X215157D02*
X217913D01*
G01X211220D02*
X213976D01*
G01X207283D02*
X210039D01*
G01X203346D02*
X206102D01*
G01X199409D02*
X202165D01*
G01X195472D02*
X198228D01*
G01X191535D02*
X194291D01*
G01X187598D02*
X190354D01*
G01X183661D02*
X186417D01*
G01X179724D02*
X182480D01*
G01X175787D02*
X178543D01*
G01X171850D02*
X174606D01*
G01Y5512D02*
X171850D01*
G01X178543D02*
X175787D01*
G01X182480D02*
X179724D01*
G01X186417D02*
X183661D01*
G01X190354D02*
X187598D01*
G01X194291D02*
X191535D01*
G01X198228D02*
X195472D01*
G01X202165D02*
X199409D01*
G01X206102D02*
X203346D01*
G01X210039D02*
X207283D01*
G01X213976D02*
X211220D01*
G01X217913D02*
X215157D01*
G01X221850D02*
X219094D01*
G01X225787D02*
X223031D01*
G01X229724D02*
X226969D01*
G01X222441Y98819D02*
G03X226378Y102756I0J3937D01*
G01X230315Y106693D02*
G03X226378Y102756I0J-3937D01*
G01X222441Y98819D02*
X261811D01*
G01X230315Y106693D02*
G03X226378Y102756I0J-3937D01*
G01X222441Y98819D02*
G03X226378Y102756I0J3937D01*
G01X222441Y98819D02*
G03X226378Y102756I0J3937D01*
G01X230315Y106693D02*
G03X226378Y102756I0J-3937D01*
G01X195512Y98425D02*
X179606D01*
G01X216417D02*
X200512D01*
G01X237323D02*
X221417D01*
G01X228940Y74803D02*
X228952Y75464D01*
G01X228950Y76392D02*
X228920Y74803D01*
G01X228974Y80389D02*
X228999Y81890D01*
G01X228981D02*
X228972Y81299D01*
G01X228926Y68280D02*
X228921Y66493D01*
G01X228911Y66760D02*
X228917Y68547D01*
G01X227782Y89933D02*
X227777Y88146D01*
G01X227767Y88414D02*
X227772Y90201D01*
G01X228935Y68996D02*
Y69980D01*
G01Y86713D02*
Y87697D01*
G01X228780Y66043D02*
Y65059D01*
G01Y91634D02*
Y90650D01*
G01X227914Y66043D02*
Y65059D01*
G01X227913Y90650D02*
Y91634D01*
G01X227758Y69980D02*
Y68996D01*
G01Y87697D02*
Y86713D01*
G01X228921Y90201D02*
X228926Y88414D01*
G01X228916Y88146D02*
X228911Y89933D01*
G01X227777Y68547D02*
X227782Y66760D01*
G01X227772Y66493D02*
X227768Y68280D01*
G01X228999Y74803D02*
X228974Y76304D01*
G01X228972Y75394D02*
X228981Y74803D01*
G01X227721Y81299D02*
X227711Y81890D01*
G01X227694D02*
X227719Y80389D01*
G01X228952Y81229D02*
X228940Y81890D01*
G01X228920D02*
X228950Y80301D01*
G01X227774Y74803D02*
X227743Y76392D01*
G01X227741Y75464D02*
X227754Y74803D01*
G01X173784Y91634D02*
X172673D01*
G01X181658D02*
X180547D01*
G01X189532D02*
X188421D01*
G01X197406D02*
X196295D01*
G01X205280D02*
X204169D01*
G01X213154D02*
X212043D01*
G01X221028D02*
X219917D01*
G01X228902D02*
X227791D01*
G01X173784Y90650D02*
X172673D01*
G01X181658D02*
X180547D01*
G01X189532D02*
X188421D01*
G01X197406D02*
X196295D01*
G01X205280D02*
X204169D01*
G01X213154D02*
X212043D01*
G01X221028D02*
X219917D01*
G01X228902D02*
X227791D01*
G01X227772Y90201D02*
X228921D01*
G01X219898D02*
X221047D01*
G01X212024D02*
X213173D01*
G01X204150D02*
X205299D01*
G01X196276D02*
X197425D01*
G01X188402D02*
X189551D01*
G01X180528D02*
X181677D01*
G01X172654D02*
X173803D01*
G01X173793Y89933D02*
X172664D01*
G01X181667D02*
X180538D01*
G01X189541D02*
X188412D01*
G01X197415D02*
X196286D01*
G01X205289D02*
X204160D01*
G01X213163D02*
X212034D01*
G01X221037D02*
X219908D01*
G01X228911D02*
X227782D01*
G01X173807Y88414D02*
X172649D01*
G01X181681D02*
X180523D01*
G01X189556D02*
X188397D01*
G01X197430D02*
X196271D01*
G01X205304D02*
X204145D01*
G01X213178D02*
X212019D01*
G01X221052D02*
X219893D01*
G01X228926D02*
X227767D01*
G01X227777Y88146D02*
X228916D01*
G01X219903D02*
X221042D01*
G01X212029D02*
X213168D01*
G01X204155D02*
X205294D01*
G01X196281D02*
X197420D01*
G01X188407D02*
X189546D01*
G01X180533D02*
X181672D01*
G01X172659D02*
X173798D01*
G01X173817Y87697D02*
X172640D01*
G01X177754D02*
X176577D01*
G01X181691D02*
X180514D01*
G01X185628D02*
X184451D01*
G01X189565D02*
X188388D01*
G01X193502D02*
X192325D01*
G01X197439D02*
X196262D01*
G01X201376D02*
X200199D01*
G01X205313D02*
X204136D01*
G01X209250D02*
X208073D01*
G01X213187D02*
X212010D01*
G01X217124D02*
X215947D01*
G01X221061D02*
X219884D01*
G01X224998D02*
X223821D01*
G01X228935D02*
X227758D01*
G01X173817Y86713D02*
X172640D01*
G01X177754D02*
X176577D01*
G01X181691D02*
X180514D01*
G01X185628D02*
X184451D01*
G01X189565D02*
X188388D01*
G01X193502D02*
X192325D01*
G01X197439D02*
X196262D01*
G01X201376D02*
X200199D01*
G01X205313D02*
X204136D01*
G01X209250D02*
X208073D01*
G01X213187D02*
X212010D01*
G01X217124D02*
X215947D01*
G01X221061D02*
X219884D01*
G01X224998D02*
X223821D01*
G01X228935D02*
X227758D01*
G01X177735Y86264D02*
X176596D01*
G01X185609D02*
X184470D01*
G01X193483D02*
X192344D01*
G01X201357D02*
X200218D01*
G01X209231D02*
X208092D01*
G01X217105D02*
X215966D01*
G01X224979D02*
X223840D01*
G01X223830Y85996D02*
X224989D01*
G01X215956D02*
X217115D01*
G01X208082D02*
X209241D01*
G01X200208D02*
X201367D01*
G01X192334D02*
X193493D01*
G01X184460D02*
X185619D01*
G01X176586D02*
X177744D01*
G01X223845Y84477D02*
X224974D01*
G01X215971D02*
X217100D01*
G01X208097D02*
X209226D01*
G01X200223D02*
X201352D01*
G01X192349D02*
X193478D01*
G01X184475D02*
X185604D01*
G01X176601D02*
X177730D01*
G01X177740Y84209D02*
X176591D01*
G01X185614D02*
X184465D01*
G01X193488D02*
X192339D01*
G01X201362D02*
X200213D01*
G01X209236D02*
X208087D01*
G01X217110D02*
X215961D01*
G01X224984D02*
X223835D01*
G01X177721Y83760D02*
X176610D01*
G01X185595D02*
X184484D01*
G01X193469D02*
X192358D01*
G01X201343D02*
X200232D01*
G01X209217D02*
X208106D01*
G01X217091D02*
X215980D01*
G01X224965D02*
X223854D01*
G01X177721Y82776D02*
X176610D01*
G01X185595D02*
X184484D01*
G01X193469D02*
X192358D01*
G01X201343D02*
X200232D01*
G01X209217D02*
X208106D01*
G01X217091D02*
X215980D01*
G01X224965D02*
X223854D01*
G01X173854Y81299D02*
X172603D01*
G01X177791D02*
X176540D01*
G01X181728D02*
X180477D01*
G01X185665D02*
X184414D01*
G01X189602D02*
X188351D01*
G01X193539D02*
X192288D01*
G01X197476D02*
X196225D01*
G01X201413D02*
X200162D01*
G01X205350D02*
X204099D01*
G01X209287D02*
X208036D01*
G01X213224D02*
X211973D01*
G01X217161D02*
X215910D01*
G01X221098D02*
X219847D01*
G01X225035D02*
X223784D01*
G01X228972D02*
X227721D01*
G01X227741Y81229D02*
X228952D01*
G01X223804D02*
X225015D01*
G01X219867D02*
X221078D01*
G01X215930D02*
X217141D01*
G01X211993D02*
X213204D01*
G01X208056D02*
X209267D01*
G01X204119D02*
X205330D01*
G01X200181D02*
X201393D01*
G01X196244D02*
X197456D01*
G01X192307D02*
X193519D01*
G01X188370D02*
X189582D01*
G01X184433D02*
X185645D01*
G01X180496D02*
X181708D01*
G01X176559D02*
X177771D01*
G01X172622D02*
X173834D01*
G01X227743Y80301D02*
X227774Y81890D01*
G01X227754D02*
X227741Y81229D01*
G01X225003Y74803D02*
X225015Y75464D01*
G01X225013Y76392D02*
X224983Y74803D01*
G01X223806Y80301D02*
X223837Y81890D01*
G01X223817D02*
X223804Y81229D01*
G01X221066Y74803D02*
X221078Y75464D01*
G01X221076Y76392D02*
X221046Y74803D01*
G01X219869Y80301D02*
X219900Y81890D01*
G01X219880D02*
X219867Y81229D01*
G01X217129Y74803D02*
X217141Y75464D01*
G01X217139Y76392D02*
X217109Y74803D01*
G01X215932Y80301D02*
X215963Y81890D01*
G01X215943D02*
X215930Y81229D01*
G01X227712Y74803D02*
X227721Y75394D01*
G01X227719Y76304D02*
X227694Y74803D01*
G01X225037Y80389D02*
X225062Y81890D01*
G01X225044D02*
X225035Y81299D01*
G01X223775Y74803D02*
X223784Y75394D01*
G01X223782Y76304D02*
X223757Y74803D01*
G01X221100Y80389D02*
X221125Y81890D01*
G01X221107D02*
X221098Y81299D01*
G01X219838Y74803D02*
X219847Y75394D01*
G01X219845Y76304D02*
X219820Y74803D01*
G01X217163Y80389D02*
X217188Y81890D01*
G01X217170D02*
X217161Y81299D01*
G01X215901Y74803D02*
X215910Y75394D01*
G01X215908Y76304D02*
X215883Y74803D01*
G01X224989Y85996D02*
X224984Y84209D01*
G01X224974Y84477D02*
X224979Y86264D01*
G01X223845Y72217D02*
X223840Y70430D01*
G01X223831Y70697D02*
X223835Y72484D01*
G01X221052Y68280D02*
X221047Y66493D01*
G01X221037Y66760D02*
X221043Y68547D01*
G01X219908Y89933D02*
X219903Y88146D01*
G01X219893Y88414D02*
X219898Y90201D01*
G01X217115Y85996D02*
X217110Y84209D01*
G01X217100Y84477D02*
X217105Y86264D01*
G01X215971Y72217D02*
X215966Y70430D01*
G01X215957Y70697D02*
X215961Y72484D01*
G01X224998Y69980D02*
Y68996D01*
G01Y87697D02*
Y86713D01*
G01X224843Y73917D02*
Y72933D01*
G01Y83760D02*
Y82776D01*
G01X223977Y73917D02*
Y72933D01*
G01X223976Y82776D02*
Y83760D01*
G01X223821Y68996D02*
Y69980D01*
G01Y86713D02*
Y87697D01*
G01X221417Y98425D02*
Y92815D01*
G01X221061Y68996D02*
Y69980D01*
G01Y87697D02*
Y86713D01*
G01X220906Y66043D02*
Y65059D01*
G01Y91634D02*
Y90650D01*
G01X220040Y66043D02*
Y65059D01*
G01X220039Y90650D02*
Y91634D01*
G01X219884Y69980D02*
Y68996D01*
G01Y86713D02*
Y87697D01*
G01X217124Y68996D02*
Y69980D01*
G01Y87697D02*
Y86713D01*
G01X216969Y73917D02*
Y72933D01*
G01Y83760D02*
Y82776D01*
G01X216417Y98425D02*
Y92815D01*
G01X216103Y73917D02*
Y72933D01*
G01X216102Y82776D02*
Y83760D01*
G01X215947Y69980D02*
Y68996D01*
G01Y86713D02*
Y87697D01*
G01X224984Y72484D02*
X224989Y70697D01*
G01X224980Y70430D02*
X224974Y72217D01*
G01X223840Y86264D02*
X223845Y84477D01*
G01X223835Y84209D02*
X223830Y85996D01*
G01X221047Y90201D02*
X221052Y88414D01*
G01X221042Y88146D02*
X221037Y89933D01*
G01X219903Y68547D02*
X219908Y66760D01*
G01X219898Y66493D02*
X219894Y68280D01*
G01X217110Y72484D02*
X217115Y70697D01*
G01X217106Y70430D02*
X217100Y72217D01*
G01X215966Y86264D02*
X215971Y84477D01*
G01X215961Y84209D02*
X215956Y85996D01*
G01X225062Y74803D02*
X225037Y76304D01*
G01X225035Y75394D02*
X225044Y74803D01*
G01X223784Y81299D02*
X223774Y81890D01*
G01X223757D02*
X223782Y80389D01*
G01X221125Y74803D02*
X221100Y76304D01*
G01X221098Y75394D02*
X221107Y74803D01*
G01X219847Y81299D02*
X219837Y81890D01*
G01X219820D02*
X219845Y80389D01*
G01X217188Y74803D02*
X217163Y76304D01*
G01X217161Y75394D02*
X217170Y74803D01*
G01X215910Y81299D02*
X215900Y81890D01*
G01X215883D02*
X215908Y80389D01*
G01X225015Y81229D02*
X225003Y81890D01*
G01X224983D02*
X225013Y80301D01*
G01X223837Y74803D02*
X223806Y76392D01*
G01X223804Y75464D02*
X223817Y74803D01*
G01X221078Y81229D02*
X221066Y81890D01*
G01X221046D02*
X221076Y80301D01*
G01X219900Y74803D02*
X219869Y76392D01*
G01X219867Y75464D02*
X219880Y74803D01*
G01X217141Y81229D02*
X217129Y81890D01*
G01X217109D02*
X217139Y80301D01*
G01X215963Y74803D02*
X215932Y76392D01*
G01X215930Y75464D02*
X215943Y74803D01*
G01X173843Y81004D02*
X172613D01*
G01X177780D02*
X176550D01*
G01X181717D02*
X180487D01*
G01X185654D02*
X184424D01*
G01X189591D02*
X188361D01*
G01X193528D02*
X192298D01*
G01X197465D02*
X196235D01*
G01X201402D02*
X200172D01*
G01X205339D02*
X204109D01*
G01X209276D02*
X208046D01*
G01X213213D02*
X211983D01*
G01X217150D02*
X215920D01*
G01X221087D02*
X219857D01*
G01X225024D02*
X223794D01*
G01X228961D02*
X227731D01*
G01X227719Y80389D02*
X228974D01*
G01X223782D02*
X225037D01*
G01X219845D02*
X221100D01*
G01X215908D02*
X217163D01*
G01X211971D02*
X213226D01*
G01X208034D02*
X209289D01*
G01X204097D02*
X205352D01*
G01X200160D02*
X201415D01*
G01X196223D02*
X197478D01*
G01X192286D02*
X193541D01*
G01X188349D02*
X189604D01*
G01X184412D02*
X185667D01*
G01X180475D02*
X181730D01*
G01X176538D02*
X177793D01*
G01X172601D02*
X173856D01*
G01X173832Y80301D02*
X172625D01*
G01X177769D02*
X176562D01*
G01X181706D02*
X180499D01*
G01X185643D02*
X184436D01*
G01X189580D02*
X188373D01*
G01X193517D02*
X192310D01*
G01X197454D02*
X196247D01*
G01X201391D02*
X200184D01*
G01X205328D02*
X204121D01*
G01X209265D02*
X208058D01*
G01X213202D02*
X211995D01*
G01X217139D02*
X215932D01*
G01X221076D02*
X219869D01*
G01X225013D02*
X223806D01*
G01X228950D02*
X227743D01*
G01X173843Y80019D02*
X172613D01*
G01X177780D02*
X176550D01*
G01X181717D02*
X180487D01*
G01X185654D02*
X184424D01*
G01X189591D02*
X188361D01*
G01X193528D02*
X192298D01*
G01X197465D02*
X196235D01*
G01X201402D02*
X200172D01*
G01X205339D02*
X204109D01*
G01X209276D02*
X208046D01*
G01X213213D02*
X211983D01*
G01X217150D02*
X215920D01*
G01X221087D02*
X219857D01*
G01X225024D02*
X223794D01*
G01X228961D02*
X227731D01*
G01X227732Y76674D02*
X228961D01*
G01X223795D02*
X225024D01*
G01X219858D02*
X221087D01*
G01X215921D02*
X217150D01*
G01X211984D02*
X213213D01*
G01X208047D02*
X209276D01*
G01X204110D02*
X205339D01*
G01X200173D02*
X201402D01*
G01X196236D02*
X197465D01*
G01X192299D02*
X193528D01*
G01X188362D02*
X189591D01*
G01X184425D02*
X185654D01*
G01X180488D02*
X181717D01*
G01X176551D02*
X177780D01*
G01X172614D02*
X173843D01*
G01X227743Y76392D02*
X228950D01*
G01X223806D02*
X225013D01*
G01X219869D02*
X221076D01*
G01X215932D02*
X217139D01*
G01X211995D02*
X213202D01*
G01X208058D02*
X209265D01*
G01X204121D02*
X205328D01*
G01X200184D02*
X201391D01*
G01X196247D02*
X197454D01*
G01X192310D02*
X193517D01*
G01X188373D02*
X189580D01*
G01X184436D02*
X185643D01*
G01X180499D02*
X181706D01*
G01X176562D02*
X177769D01*
G01X172625D02*
X173832D01*
G01X173856Y76304D02*
X172601D01*
G01X177793D02*
X176538D01*
G01X181730D02*
X180475D01*
G01X185667D02*
X184412D01*
G01X189604D02*
X188349D01*
G01X193541D02*
X192286D01*
G01X197478D02*
X196223D01*
G01X201415D02*
X200160D01*
G01X205352D02*
X204097D01*
G01X209289D02*
X208034D01*
G01X213226D02*
X211971D01*
G01X217163D02*
X215908D01*
G01X221100D02*
X219845D01*
G01X225037D02*
X223782D01*
G01X228974D02*
X227719D01*
G01X227732Y75690D02*
X228961D01*
G01X223795D02*
X225024D01*
G01X219858D02*
X221087D01*
G01X215921D02*
X217150D01*
G01X211984D02*
X213213D01*
G01X208047D02*
X209276D01*
G01X204110D02*
X205339D01*
G01X200173D02*
X201402D01*
G01X196236D02*
X197465D01*
G01X192299D02*
X193528D01*
G01X188362D02*
X189591D01*
G01X184425D02*
X185654D01*
G01X180488D02*
X181717D01*
G01X176551D02*
X177780D01*
G01X172614D02*
X173843D01*
G01X173834Y75464D02*
X172622D01*
G01X177771D02*
X176559D01*
G01X181708D02*
X180496D01*
G01X185645D02*
X184433D01*
G01X189582D02*
X188370D01*
G01X193519D02*
X192307D01*
G01X197456D02*
X196244D01*
G01X201393D02*
X200181D01*
G01X205330D02*
X204119D01*
G01X209267D02*
X208056D01*
G01X213204D02*
X211993D01*
G01X217141D02*
X215930D01*
G01X221078D02*
X219867D01*
G01X225015D02*
X223804D01*
G01X228952D02*
X227741D01*
G01X227721Y75394D02*
X228972D01*
G01X223784D02*
X225035D01*
G01X219847D02*
X221098D01*
G01X215910D02*
X217161D01*
G01X211973D02*
X213224D01*
G01X208036D02*
X209287D01*
G01X204099D02*
X205350D01*
G01X200162D02*
X201413D01*
G01X196225D02*
X197476D01*
G01X192288D02*
X193539D01*
G01X188351D02*
X189602D01*
G01X184414D02*
X185665D01*
G01X180477D02*
X181728D01*
G01X176540D02*
X177791D01*
G01X172603D02*
X173854D01*
G01X223854Y73917D02*
X224965D01*
G01X215980D02*
X217091D01*
G01X208106D02*
X209217D01*
G01X200232D02*
X201343D01*
G01X192358D02*
X193469D01*
G01X184484D02*
X185595D01*
G01X176610D02*
X177721D01*
G01X223854Y72933D02*
X224965D01*
G01X215980D02*
X217091D01*
G01X208106D02*
X209217D01*
G01X200232D02*
X201343D01*
G01X192358D02*
X193469D01*
G01X184484D02*
X185595D01*
G01X176610D02*
X177721D01*
G01X223835Y72484D02*
X224984D01*
G01X215961D02*
X217110D01*
G01X208087D02*
X209236D01*
G01X200213D02*
X201362D01*
G01X192339D02*
X193488D01*
G01X184465D02*
X185614D01*
G01X176591D02*
X177740D01*
G01X177730Y72217D02*
X176601D01*
G01X185604D02*
X184475D01*
G01X193478D02*
X192349D01*
G01X201352D02*
X200223D01*
G01X209226D02*
X208097D01*
G01X217100D02*
X215971D01*
G01X224974D02*
X223845D01*
G01X177744Y70697D02*
X176587D01*
G01X185619D02*
X184461D01*
G01X193493D02*
X192335D01*
G01X201367D02*
X200209D01*
G01X209241D02*
X208083D01*
G01X217115D02*
X215957D01*
G01X224989D02*
X223831D01*
G01X223840Y70430D02*
X224980D01*
G01X215966D02*
X217106D01*
G01X208092D02*
X209231D01*
G01X200218D02*
X201357D01*
G01X192344D02*
X193483D01*
G01X184470D02*
X185609D01*
G01X176596D02*
X177735D01*
G01X227758Y69980D02*
X228935D01*
G01X223821D02*
X224998D01*
G01X219884D02*
X221061D01*
G01X215947D02*
X217124D01*
G01X212010D02*
X213187D01*
G01X208073D02*
X209250D01*
G01X204136D02*
X205313D01*
G01X200199D02*
X201376D01*
G01X196262D02*
X197439D01*
G01X192325D02*
X193502D01*
G01X188388D02*
X189565D01*
G01X184451D02*
X185628D01*
G01X180514D02*
X181691D01*
G01X176577D02*
X177754D01*
G01X172640D02*
X173817D01*
G01Y68996D02*
X172640D01*
G01X177754D02*
X176577D01*
G01X181691D02*
X180514D01*
G01X185628D02*
X184451D01*
G01X189565D02*
X188388D01*
G01X193502D02*
X192325D01*
G01X197439D02*
X196262D01*
G01X201376D02*
X200199D01*
G01X205313D02*
X204136D01*
G01X209250D02*
X208073D01*
G01X213187D02*
X212010D01*
G01X217124D02*
X215947D01*
G01X221061D02*
X219884D01*
G01X224998D02*
X223821D01*
G01X228935D02*
X227758D01*
G01X173798Y68547D02*
X172659D01*
G01X181672D02*
X180533D01*
G01X189546D02*
X188407D01*
G01X197420D02*
X196281D01*
G01X205294D02*
X204155D01*
G01X213169D02*
X212029D01*
G01X221043D02*
X219903D01*
G01X228917D02*
X227777D01*
G01X227768Y68280D02*
X228926D01*
G01X219894D02*
X221052D01*
G01X212020D02*
X213178D01*
G01X204146D02*
X205304D01*
G01X196272D02*
X197430D01*
G01X188398D02*
X189556D01*
G01X180524D02*
X181681D01*
G01X172650D02*
X173807D01*
G01X213192Y74803D02*
X213204Y75464D01*
G01X213202Y76392D02*
X213172Y74803D01*
G01X211995Y80301D02*
X212026Y81890D01*
G01X212006D02*
X211993Y81229D01*
G01X209255Y74803D02*
X209267Y75464D01*
G01X209265Y76392D02*
X209235Y74803D01*
G01X208058Y80301D02*
X208089Y81890D01*
G01X208069D02*
X208056Y81229D01*
G01X205318Y74803D02*
X205330Y75464D01*
G01X205328Y76392D02*
X205298Y74803D01*
G01X204121Y80301D02*
X204152Y81890D01*
G01X204131D02*
X204119Y81229D01*
G01X213226Y80389D02*
X213251Y81890D01*
G01X213233D02*
X213224Y81299D01*
G01X211964Y74803D02*
X211973Y75394D01*
G01X211971Y76304D02*
X211946Y74803D01*
G01X209289Y80389D02*
X209314Y81890D01*
G01X209296D02*
X209287Y81299D01*
G01X208027Y74803D02*
X208036Y75394D01*
G01X208034Y76304D02*
X208009Y74803D01*
G01X205352Y80389D02*
X205377Y81890D01*
G01X205359D02*
X205350Y81299D01*
G01X204090Y74803D02*
X204099Y75394D01*
G01X204097Y76304D02*
X204072Y74803D01*
G01X213178Y68280D02*
X213173Y66493D01*
G01X213163Y66760D02*
X213169Y68547D01*
G01X212034Y89933D02*
X212029Y88146D01*
G01X212019Y88414D02*
X212024Y90201D01*
G01X209241Y85996D02*
X209236Y84209D01*
G01X209226Y84477D02*
X209231Y86264D01*
G01X208097Y72217D02*
X208092Y70430D01*
G01X208083Y70697D02*
X208087Y72484D01*
G01X205304Y68280D02*
X205299Y66493D01*
G01X205289Y66760D02*
X205294Y68547D01*
G01X204160Y89933D02*
X204155Y88146D01*
G01X204145Y88414D02*
X204150Y90201D01*
G01X213187Y68996D02*
Y69980D01*
G01Y86713D02*
Y87697D01*
G01X213031Y66043D02*
Y65059D01*
G01Y91634D02*
Y90650D01*
G01X212166Y66043D02*
Y65059D01*
G01X212165Y90650D02*
Y91634D01*
G01X212010Y69980D02*
Y68996D01*
G01Y87697D02*
Y86713D01*
G01X209250Y69980D02*
Y68996D01*
G01Y87697D02*
Y86713D01*
G01X209094Y73917D02*
Y72933D01*
G01Y83760D02*
Y82776D01*
G01X208229Y73917D02*
Y72933D01*
G01X208228Y82776D02*
Y83760D01*
G01X208073Y68996D02*
Y69980D01*
G01Y86713D02*
Y87697D01*
G01X205313Y68996D02*
Y69980D01*
G01Y86713D02*
Y87697D01*
G01X205157Y66043D02*
Y65059D01*
G01Y91634D02*
Y90650D01*
G01X204292Y66043D02*
Y65059D01*
G01X204291Y90650D02*
Y91634D01*
G01X204136Y69980D02*
Y68996D01*
G01Y87697D02*
Y86713D01*
G01X213173Y90201D02*
X213178Y88414D01*
G01X213168Y88146D02*
X213163Y89933D01*
G01X212029Y68547D02*
X212034Y66760D01*
G01X212024Y66493D02*
X212020Y68280D01*
G01X209236Y72484D02*
X209241Y70697D01*
G01X209231Y70430D02*
X209226Y72217D01*
G01X208092Y86264D02*
X208097Y84477D01*
G01X208087Y84209D02*
X208082Y85996D01*
G01X205299Y90201D02*
X205304Y88414D01*
G01X205294Y88146D02*
X205289Y89933D01*
G01X204155Y68547D02*
X204160Y66760D01*
G01X204150Y66493D02*
X204146Y68280D01*
G01X213251Y74803D02*
X213226Y76304D01*
G01X213224Y75394D02*
X213233Y74803D01*
G01X211973Y81299D02*
X211963Y81890D01*
G01X211946D02*
X211971Y80389D01*
G01X209314Y74803D02*
X209289Y76304D01*
G01X209287Y75394D02*
X209296Y74803D01*
G01X208036Y81299D02*
X208026Y81890D01*
G01X208009D02*
X208034Y80389D01*
G01X205377Y74803D02*
X205352Y76304D01*
G01X205350Y75394D02*
X205359Y74803D01*
G01X204099Y81299D02*
X204089Y81890D01*
G01X204072D02*
X204097Y80389D01*
G01X201440Y74803D02*
X201415Y76304D01*
G01X201413Y75394D02*
X201422Y74803D01*
G01X213204Y81229D02*
X213192Y81890D01*
G01X213172D02*
X213202Y80301D01*
G01X212026Y74803D02*
X211995Y76392D01*
G01X211993Y75464D02*
X212006Y74803D01*
G01X209267Y81229D02*
X209255Y81890D01*
G01X209235D02*
X209265Y80301D01*
G01X208089Y74803D02*
X208058Y76392D01*
G01X208056Y75464D02*
X208069Y74803D01*
G01X205330Y81229D02*
X205318Y81890D01*
G01X205298D02*
X205328Y80301D01*
G01X204152Y74803D02*
X204121Y76392D01*
G01X204119Y75464D02*
X204131Y74803D01*
G01X201393Y81229D02*
X201381Y81890D01*
G01X201361D02*
X201391Y80301D01*
G01X227782Y66760D02*
X228911D01*
G01X219908D02*
X221037D01*
G01X212034D02*
X213163D01*
G01X204160D02*
X205289D01*
G01X196286D02*
X197415D01*
G01X188412D02*
X189541D01*
G01X180538D02*
X181667D01*
G01X172664D02*
X173793D01*
G01X173803Y66493D02*
X172654D01*
G01X181677D02*
X180528D01*
G01X189551D02*
X188402D01*
G01X197425D02*
X196276D01*
G01X205299D02*
X204150D01*
G01X213173D02*
X212024D01*
G01X221047D02*
X219898D01*
G01X228921D02*
X227772D01*
G01X172673Y66043D02*
X173784D01*
G01X181658D02*
X180547D01*
G01X189532D02*
X188421D01*
G01X197406D02*
X196295D01*
G01X205280D02*
X204169D01*
G01X213154D02*
X212043D01*
G01X221028D02*
X219917D01*
G01X228902D02*
X227791D01*
G01Y65059D02*
X228902D01*
G01X219917D02*
X221028D01*
G01X212043D02*
X213154D01*
G01X204169D02*
X205280D01*
G01X196295D02*
X197406D01*
G01X188421D02*
X189532D01*
G01X180547D02*
X181658D01*
G01X172673D02*
X173784D01*
G01X201381Y74803D02*
X201393Y75464D01*
G01X201391Y76392D02*
X201361Y74803D01*
G01X200184Y80301D02*
X200215Y81890D01*
G01X200194D02*
X200181Y81229D01*
G01X197444Y74803D02*
X197456Y75464D01*
G01X197454Y76392D02*
X197424Y74803D01*
G01X196247Y80301D02*
X196278Y81890D01*
G01X196257D02*
X196244Y81229D01*
G01X193507Y74803D02*
X193519Y75464D01*
G01X193517Y76392D02*
X193487Y74803D01*
G01X192310Y80301D02*
X192341Y81890D01*
G01X192320D02*
X192307Y81229D01*
G01X189570Y74803D02*
X189582Y75464D01*
G01X189580Y76392D02*
X189550Y74803D01*
G01X201415Y80389D02*
X201440Y81890D01*
G01X201422D02*
X201413Y81299D01*
G01X200153Y74803D02*
X200162Y75394D01*
G01X200160Y76304D02*
X200135Y74803D01*
G01X197478Y80389D02*
X197503Y81890D01*
G01X197485D02*
X197476Y81299D01*
G01X196216Y74803D02*
X196225Y75394D01*
G01X196223Y76304D02*
X196198Y74803D01*
G01X193541Y80389D02*
X193566Y81890D01*
G01X193548D02*
X193539Y81299D01*
G01X192279Y74803D02*
X192288Y75394D01*
G01X192286Y76304D02*
X192261Y74803D01*
G01X189604Y80389D02*
X189629Y81890D01*
G01X189611D02*
X189602Y81299D01*
G01X201367Y85996D02*
X201362Y84209D01*
G01X201352Y84477D02*
X201357Y86264D01*
G01X200223Y72217D02*
X200218Y70430D01*
G01X200209Y70697D02*
X200213Y72484D01*
G01X197430Y68280D02*
X197425Y66493D01*
G01X197415Y66760D02*
X197420Y68547D01*
G01X196286Y89933D02*
X196281Y88146D01*
G01X196271Y88414D02*
X196276Y90201D01*
G01X193493Y85996D02*
X193488Y84209D01*
G01X193478Y84477D02*
X193483Y86264D01*
G01X192349Y72217D02*
X192344Y70430D01*
G01X192335Y70697D02*
X192339Y72484D01*
G01X189556Y68280D02*
X189551Y66493D01*
G01X189541Y66760D02*
X189546Y68547D01*
G01X201376Y69980D02*
Y68996D01*
G01Y87697D02*
Y86713D01*
G01X201220Y73917D02*
Y72933D01*
G01Y83760D02*
Y82776D01*
G01X200512Y98425D02*
Y92815D01*
G01X200355Y73917D02*
Y72933D01*
G01X200354Y82776D02*
Y83760D01*
G01X200199Y68996D02*
Y69980D01*
G01Y86713D02*
Y87697D01*
G01X197439Y68996D02*
Y69980D01*
G01Y86713D02*
Y87697D01*
G01X197283Y66043D02*
Y65059D01*
G01Y91634D02*
Y90650D01*
G01X196418Y66043D02*
Y65059D01*
G01X196417Y90650D02*
Y91634D01*
G01X196262Y69980D02*
Y68996D01*
G01Y87697D02*
Y86713D01*
G01X195512Y98425D02*
Y92815D01*
G01X193502Y69980D02*
Y68996D01*
G01Y87697D02*
Y86713D01*
G01X193346Y73917D02*
Y72933D01*
G01Y83760D02*
Y82776D01*
G01X192481Y73917D02*
Y72933D01*
G01X192480Y82776D02*
Y83760D01*
G01X192325Y68996D02*
Y69980D01*
G01Y86713D02*
Y87697D01*
G01X189565Y68996D02*
Y69980D01*
G01Y86713D02*
Y87697D01*
G01X189409Y66043D02*
Y65059D01*
G01Y91634D02*
Y90650D01*
G01X201362Y72484D02*
X201367Y70697D01*
G01X201357Y70430D02*
X201352Y72217D01*
G01X200218Y86264D02*
X200223Y84477D01*
G01X200213Y84209D02*
X200208Y85996D01*
G01X197425Y90201D02*
X197430Y88414D01*
G01X197420Y88146D02*
X197415Y89933D01*
G01X196281Y68547D02*
X196286Y66760D01*
G01X196276Y66493D02*
X196272Y68280D01*
G01X193488Y72484D02*
X193493Y70697D01*
G01X193483Y70430D02*
X193478Y72217D01*
G01X192344Y86264D02*
X192349Y84477D01*
G01X192339Y84209D02*
X192334Y85996D01*
G01X189551Y90201D02*
X189556Y88414D01*
G01X189546Y88146D02*
X189541Y89933D01*
G01X200162Y81299D02*
X200152Y81890D01*
G01X200135D02*
X200160Y80389D01*
G01X197503Y74803D02*
X197478Y76304D01*
G01X197476Y75394D02*
X197485Y74803D01*
G01X196225Y81299D02*
X196215Y81890D01*
G01X196198D02*
X196223Y80389D01*
G01X193566Y74803D02*
X193541Y76304D01*
G01X193539Y75394D02*
X193548Y74803D01*
G01X192288Y81299D02*
X192278Y81890D01*
G01X192261D02*
X192286Y80389D01*
G01X189629Y74803D02*
X189604Y76304D01*
G01X189602Y75394D02*
X189611Y74803D01*
G01X188351Y81299D02*
X188341Y81890D01*
G01X188324D02*
X188349Y80389D01*
G01X200215Y74803D02*
X200184Y76392D01*
G01X200181Y75464D02*
X200194Y74803D01*
G01X197456Y81229D02*
X197444Y81890D01*
G01X197424D02*
X197454Y80301D01*
G01X196278Y74803D02*
X196247Y76392D01*
G01X196244Y75464D02*
X196257Y74803D01*
G01X193519Y81229D02*
X193507Y81890D01*
G01X193487D02*
X193517Y80301D01*
G01X192341Y74803D02*
X192310Y76392D01*
G01X192307Y75464D02*
X192320Y74803D01*
G01X189582Y81229D02*
X189570Y81890D01*
G01X189550D02*
X189580Y80301D01*
G01X188404Y74803D02*
X188373Y76392D01*
G01X188370Y75464D02*
X188383Y74803D01*
G01X188373Y80301D02*
X188404Y81890D01*
G01X188383D02*
X188370Y81229D01*
G01X185633Y74803D02*
X185645Y75464D01*
G01X185643Y76392D02*
X185613Y74803D01*
G01X184436Y80301D02*
X184467Y81890D01*
G01X184446D02*
X184433Y81229D01*
G01X181696Y74803D02*
X181708Y75464D01*
G01X181706Y76392D02*
X181676Y74803D01*
G01X180499Y80301D02*
X180530Y81890D01*
G01X180509D02*
X180496Y81229D01*
G01X177759Y74803D02*
X177771Y75464D01*
G01X177769Y76392D02*
X177739Y74803D01*
G01X176562Y80301D02*
X176593Y81890D01*
G01X176572D02*
X176559Y81229D01*
G01X188342Y74803D02*
X188351Y75394D01*
G01X188349Y76304D02*
X188324Y74803D01*
G01X185667Y80389D02*
X185692Y81890D01*
G01X185674D02*
X185665Y81299D01*
G01X184405Y74803D02*
X184414Y75394D01*
G01X184412Y76304D02*
X184387Y74803D01*
G01X181730Y80389D02*
X181755Y81890D01*
G01X181737D02*
X181728Y81299D01*
G01X180468Y74803D02*
X180477Y75394D01*
G01X180475Y76304D02*
X180450Y74803D01*
G01X177793Y80389D02*
X177818Y81890D01*
G01X177800D02*
X177791Y81299D01*
G01X176531Y74803D02*
X176540Y75394D01*
G01X176538Y76304D02*
X176513Y74803D01*
G01X188412Y89933D02*
X188407Y88146D01*
G01X188397Y88414D02*
X188402Y90201D01*
G01X185619Y85996D02*
X185614Y84209D01*
G01X185604Y84477D02*
X185609Y86264D01*
G01X184475Y72217D02*
X184470Y70430D01*
G01X184461Y70697D02*
X184465Y72484D01*
G01X181681Y68280D02*
X181677Y66493D01*
G01X181667Y66760D02*
X181672Y68547D01*
G01X180538Y89933D02*
X180533Y88146D01*
G01X180523Y88414D02*
X180528Y90201D01*
G01X177744Y85996D02*
X177740Y84209D01*
G01X177730Y84477D02*
X177735Y86264D01*
G01X176601Y72217D02*
X176596Y70430D01*
G01X176587Y70697D02*
X176591Y72484D01*
G01X188544Y66043D02*
Y65059D01*
G01X188543Y90650D02*
Y91634D01*
G01X188388Y69980D02*
Y68996D01*
G01Y87697D02*
Y86713D01*
G01X185628Y69980D02*
Y68996D01*
G01Y87697D02*
Y86713D01*
G01X185472Y73917D02*
Y72933D01*
G01Y83760D02*
Y82776D01*
G01X184607Y73917D02*
Y72933D01*
G01X184606Y82776D02*
Y83760D01*
G01X184451Y68996D02*
Y69980D01*
G01Y86713D02*
Y87697D01*
G01X181691Y68996D02*
Y69980D01*
G01Y86713D02*
Y87697D01*
G01X181535Y66043D02*
Y65059D01*
G01Y91634D02*
Y90650D01*
G01X180670Y66043D02*
Y65059D01*
G01X180669Y90650D02*
Y91634D01*
G01X180514Y69980D02*
Y68996D01*
G01Y87697D02*
Y86713D01*
G01X179606Y98425D02*
Y92815D01*
G01X177754Y69980D02*
Y68996D01*
G01Y87697D02*
Y86713D01*
G01X177598Y73917D02*
Y72933D01*
G01Y83760D02*
Y82776D01*
G01X176733Y73917D02*
Y72933D01*
G01X176732Y82776D02*
Y83760D01*
G01X176577Y68996D02*
Y69980D01*
G01Y86713D02*
Y87697D01*
G01X188407Y68547D02*
X188412Y66760D01*
G01X188402Y66493D02*
X188398Y68280D01*
G01X185614Y72484D02*
X185619Y70697D01*
G01X185609Y70430D02*
X185604Y72217D01*
G01X184470Y86264D02*
X184475Y84477D01*
G01X184465Y84209D02*
X184460Y85996D01*
G01X181677Y90201D02*
X181681Y88414D01*
G01X181672Y88146D02*
X181667Y89933D01*
G01X180533Y68547D02*
X180538Y66760D01*
G01X180528Y66493D02*
X180524Y68280D01*
G01X177740Y72484D02*
X177744Y70697D01*
G01X177735Y70430D02*
X177730Y72217D01*
G01X176596Y86264D02*
X176601Y84477D01*
G01X176591Y84209D02*
X176586Y85996D01*
G01X185692Y74803D02*
X185667Y76304D01*
G01X185665Y75394D02*
X185674Y74803D01*
G01X184414Y81299D02*
X184404Y81890D01*
G01X184387D02*
X184412Y80389D01*
G01X181755Y74803D02*
X181730Y76304D01*
G01X181728Y75394D02*
X181737Y74803D01*
G01X180477Y81299D02*
X180467Y81890D01*
G01X180450D02*
X180475Y80389D01*
G01X177818Y74803D02*
X177793Y76304D01*
G01X177791Y75394D02*
X177800Y74803D01*
G01X176540Y81299D02*
X176530Y81890D01*
G01X176513D02*
X176538Y80389D01*
G01X185645Y81229D02*
X185633Y81890D01*
G01X185613D02*
X185643Y80301D01*
G01X184467Y74803D02*
X184436Y76392D01*
G01X184433Y75464D02*
X184446Y74803D01*
G01X181708Y81229D02*
X181696Y81890D01*
G01X181676D02*
X181706Y80301D01*
G01X180530Y74803D02*
X180499Y76392D01*
G01X180496Y75464D02*
X180509Y74803D01*
G01X177771Y81229D02*
X177759Y81890D01*
G01X177739D02*
X177769Y80301D01*
G01X176593Y74803D02*
X176562Y76392D01*
G01X176559Y75464D02*
X176572Y74803D01*
G01X173822D02*
X173834Y75464D01*
G01X173832Y76392D02*
X173802Y74803D01*
G01X172625Y80301D02*
X172656Y81890D01*
G01X172635D02*
X172622Y81229D01*
G01X169885Y74803D02*
X169897Y75464D01*
G01X169895Y76392D02*
X169865Y74803D01*
G01X173856Y80389D02*
X173881Y81890D01*
G01X173863D02*
X173854Y81299D01*
G01X172594Y74803D02*
X172603Y75394D01*
G01X172601Y76304D02*
X172576Y74803D01*
G01X169919Y80389D02*
X169944Y81890D01*
G01X169926D02*
X169917Y81299D01*
G01X173807Y68280D02*
X173803Y66493D01*
G01X173793Y66760D02*
X173798Y68547D01*
G01X172664Y89933D02*
X172659Y88146D01*
G01X172649Y88414D02*
X172654Y90201D01*
G01X169870Y85996D02*
X169866Y84209D01*
G01X169856Y84477D02*
X169861Y86264D01*
G01X174606Y98425D02*
Y92815D01*
G01X173817Y68996D02*
Y69980D01*
G01Y86713D02*
Y87697D01*
G01X173661Y66043D02*
Y65059D01*
G01Y91634D02*
Y90650D01*
G01X172796Y66043D02*
Y65059D01*
G01X172795Y90650D02*
Y91634D01*
G01X172640Y69980D02*
Y68996D01*
G01Y87697D02*
Y86713D01*
G01X169880Y68996D02*
Y69980D01*
G01Y87697D02*
Y86713D01*
G01X169724Y73917D02*
Y72933D01*
G01Y83760D02*
Y82776D01*
G01X173803Y90201D02*
X173807Y88414D01*
G01X173798Y88146D02*
X173793Y89933D01*
G01X172659Y68547D02*
X172664Y66760D01*
G01X172654Y66493D02*
X172650Y68280D01*
G01X169866Y72484D02*
X169870Y70697D01*
G01X169861Y70430D02*
X169856Y72217D01*
G01X173881Y74803D02*
X173856Y76304D01*
G01X173854Y75394D02*
X173863Y74803D01*
G01X172603Y81299D02*
X172593Y81890D01*
G01X172576D02*
X172601Y80389D01*
G01X169944Y74803D02*
X169919Y76304D01*
G01X169917Y75394D02*
X169926Y74803D01*
G01X173834Y81229D02*
X173822Y81890D01*
G01X173802D02*
X173832Y80301D01*
G01X172656Y74803D02*
X172625Y76392D01*
G01X172622Y75464D02*
X172635Y74803D01*
G01X169897Y81229D02*
X169885Y81890D01*
G01X169865D02*
X169895Y80301D01*
G01X226378Y118504D02*
G03X222441Y122441I-3937J0D01*
G01X226378Y118504D02*
G03X230315Y114567I3937J0D01*
G01D02*
X261811D01*
G01X226378Y118504D02*
G03X222441Y122441I-3937J0D01*
G01X226378Y118504D02*
G03X230315Y114567I3937J0D01*
G01X226378Y118504D02*
G03X222441Y122441I-3937J0D01*
G01X226378Y118504D02*
G03X230315Y114567I3937J0D01*
G01X370079D02*
X230315D01*
G01Y106693D02*
X261811D01*
G01X230315D02*
X370079D01*
G01X222441Y333859D02*
G03X226378Y337796I0J3937D01*
G01X230315Y341733D02*
G03X226378Y337796I0J-3937D01*
G01X230315Y341733D02*
X261811D01*
G01X230315D02*
G03X226378Y337796I0J-3937D01*
G01X222441Y333859D02*
G03X226378Y337796I0J3937D01*
G01X222441Y333859D02*
G03X226378Y337796I0J3937D01*
G01X230315Y341733D02*
G03X226378Y337796I0J-3937D01*
G01X230315Y341733D02*
X370079D01*
G01X226378Y353544D02*
G03X222441Y357481I-3937J0D01*
G01X226378Y353544D02*
G03X230315Y349607I3937J0D01*
G01D02*
X261811D01*
G01X226378Y353544D02*
G03X222441Y357481I-3937J0D01*
G01X226378Y353544D02*
G03X230315Y349607I3937J0D01*
G01X226378Y353544D02*
G03X222441Y357481I-3937J0D01*
G01X226378Y353544D02*
G03X230315Y349607I3937J0D01*
G01X370079D02*
X230315D01*
G01X222441Y568898D02*
G03X226378Y572835I0J3937D01*
G01X230315Y576772D02*
G03X226378Y572835I0J-3937D01*
G01X230315Y576772D02*
X261811D01*
G01X230315D02*
G03X226378Y572835I0J-3937D01*
G01X222441Y568898D02*
G03X226378Y572835I0J3937D01*
G01X222441Y568898D02*
G03X226378Y572835I0J3937D01*
G01X230315Y576772D02*
G03X226378Y572835I0J-3937D01*
G01X230315Y576772D02*
X370079D01*
G01X226378Y588583D02*
G03X222441Y592520I-3937J0D01*
G01X226378Y588583D02*
G03X230315Y584646I3937J0D01*
G01D02*
X261811D01*
G01X226378Y588583D02*
G03X222441Y592520I-3937J0D01*
G01X226378Y588583D02*
G03X230315Y584646I3937J0D01*
G01X226378Y588583D02*
G03X222441Y592520I-3937J0D01*
G01X226378Y588583D02*
G03X230315Y584646I3937J0D01*
G01X370079D02*
X230315D01*
G01X185945Y934504D02*
Y917181D01*
G01X280906Y43701D02*
G03X284843Y39764I3937J0D01*
G01X270669D02*
G03X274606Y43701I0J3937D01*
G01X254921D02*
G03X258858Y39764I3937J0D01*
G01X289961Y5512D02*
Y22047D01*
G01X288780D02*
Y5512D01*
G01X286024D02*
Y22047D01*
G01X284843D02*
Y5512D01*
G01X282087D02*
Y22047D01*
G01X280906D02*
Y5512D01*
G01X278150D02*
Y22047D01*
G01X276969D02*
Y5512D01*
G01X274213D02*
Y22047D01*
G01X273031D02*
Y5512D01*
G01X270276D02*
Y22047D01*
G01X269094D02*
Y5512D01*
G01X266339D02*
Y22047D01*
G01X265157D02*
Y5512D01*
G01X262402D02*
Y22047D01*
G01X261220D02*
Y5512D01*
G01X258465D02*
Y22047D01*
G01X257283D02*
Y5512D01*
G01X254528D02*
Y22047D01*
G01X253346D02*
Y5512D01*
G01X250591D02*
Y22047D01*
G01X249409D02*
Y5512D01*
G01X246654D02*
Y22047D01*
G01X245472D02*
Y5512D01*
G01X242717D02*
Y22047D01*
G01X241535D02*
Y5512D01*
G01X238780D02*
Y22047D01*
G01X237598D02*
Y5512D01*
G01X234843D02*
Y22047D01*
G01X233661D02*
Y5512D01*
G01X230906D02*
Y22047D01*
G01X270669Y39764D02*
X258858D01*
G01X296654D02*
X284843D01*
G01X289961Y22047D02*
X292717D01*
G01X286024D02*
X288780D01*
G01X282087D02*
X284843D01*
G01X278150D02*
X280906D01*
G01X274213D02*
X276969D01*
G01X270276D02*
X273031D01*
G01X266339D02*
X269094D01*
G01X262402D02*
X265157D01*
G01X258465D02*
X261220D01*
G01X254528D02*
X257283D01*
G01X250591D02*
X253346D01*
G01X246654D02*
X249409D01*
G01X242717D02*
X245472D01*
G01X238780D02*
X241535D01*
G01X234843D02*
X237598D01*
G01X230906D02*
X233661D01*
G01Y5512D02*
X230906D01*
G01X237598D02*
X234843D01*
G01X241535D02*
X238780D01*
G01X245472D02*
X242717D01*
G01X249409D02*
X246654D01*
G01X253346D02*
X250591D01*
G01X257283D02*
X254528D01*
G01X261220D02*
X258465D01*
G01X265157D02*
X262402D01*
G01X269094D02*
X266339D01*
G01X273031D02*
X270276D01*
G01X276969D02*
X274213D01*
G01X280906D02*
X278150D01*
G01X284843D02*
X282087D01*
G01X288780D02*
X286024D01*
G01X292717D02*
X289961D01*
G01X261811Y98819D02*
Y106693D01*
G01X284843Y59449D02*
G03X280906Y55512I0J-3937D01*
G01X258858Y59449D02*
G03X254921Y55512I0J-3937D01*
G01X274606D02*
G03X270669Y59449I-3937J0D01*
G01X290735Y80301D02*
X290766Y81890D01*
G01X290746D02*
X290733Y81229D01*
G01X287995Y74803D02*
X288007Y75464D01*
G01X288006Y76392D02*
X287975Y74803D01*
G01X286798Y80301D02*
X286829Y81890D01*
G01X286809D02*
X286796Y81229D01*
G01X284058Y74803D02*
X284070Y75464D01*
G01X284069Y76392D02*
X284038Y74803D01*
G01X282861Y80301D02*
X282892Y81890D01*
G01X282872D02*
X282859Y81229D01*
G01X280121Y74803D02*
X280133Y75464D01*
G01X280131Y76392D02*
X280101Y74803D01*
G01X290704D02*
X290713Y75394D01*
G01X290711Y76304D02*
X290686Y74803D01*
G01X288030Y80389D02*
X288054Y81890D01*
G01X288037D02*
X288027Y81299D01*
G01X286767Y74803D02*
X286776Y75394D01*
G01X286774Y76304D02*
X286749Y74803D01*
G01X284093Y80389D02*
X284117Y81890D01*
G01X284100D02*
X284090Y81299D01*
G01X282830Y74803D02*
X282839Y75394D01*
G01X282837Y76304D02*
X282812Y74803D01*
G01X280156Y80389D02*
X280180Y81890D01*
G01X280163D02*
X280153Y81299D01*
G01X290774Y89933D02*
X290769Y88146D01*
G01X290759Y88414D02*
X290765Y90201D01*
G01X287981Y85996D02*
X287976Y84209D01*
G01X287967Y84477D02*
X287971Y86264D01*
G01X286837Y72217D02*
X286832Y70430D01*
G01X286823Y70697D02*
X286828Y72484D01*
G01X284044Y68280D02*
X284039Y66493D01*
G01X284030Y66760D02*
X284035Y68547D01*
G01X282900Y89933D02*
X282895Y88146D01*
G01X282885Y88414D02*
X282891Y90201D01*
G01X280107Y85996D02*
X280102Y84209D01*
G01X280093Y84477D02*
X280097Y86264D01*
G01X291339Y65551D02*
Y65354D01*
G01X290906Y66043D02*
Y65059D01*
G01Y90650D02*
Y91634D01*
G01X290750Y69980D02*
Y68996D01*
G01Y87697D02*
Y86713D01*
G01X287990Y69980D02*
Y68996D01*
G01Y87697D02*
Y86713D01*
G01X287835Y73917D02*
Y72933D01*
G01Y83760D02*
Y82776D01*
G01X286969Y73917D02*
Y72933D01*
G01Y82776D02*
Y83760D01*
G01X286813Y68996D02*
Y69980D01*
G01Y86713D02*
Y87697D01*
G01X284134Y98425D02*
Y92815D01*
G01X284053Y68996D02*
Y69980D01*
G01Y87697D02*
Y86713D01*
G01X283898Y66043D02*
Y65059D01*
G01Y91634D02*
Y90650D01*
G01X283032Y66043D02*
Y65059D01*
G01X283031Y90650D02*
Y91634D01*
G01X282876Y69980D02*
Y68996D01*
G01Y86713D02*
Y87697D01*
G01X280906Y43701D02*
Y55512D01*
G01X280116Y69980D02*
Y68996D01*
G01Y87697D02*
Y86713D01*
G01X279961Y73917D02*
Y72933D01*
G01Y83760D02*
Y82776D01*
G01X290769Y68547D02*
X290774Y66760D01*
G01X290765Y66493D02*
X290760Y68280D01*
G01X287976Y72484D02*
X287981Y70697D01*
G01X287972Y70430D02*
X287967Y72217D01*
G01X286832Y86264D02*
X286837Y84477D01*
G01X286828Y84209D02*
X286822Y85996D01*
G01X284039Y90201D02*
X284044Y88414D01*
G01X284034Y88146D02*
X284030Y89933D01*
G01X282895Y68547D02*
X282900Y66760D01*
G01X282891Y66493D02*
X282886Y68280D01*
G01X280102Y72484D02*
X280107Y70697D01*
G01X280098Y70430D02*
X280093Y72217D01*
G01X290713Y81299D02*
X290704Y81890D01*
G01X290686D02*
X290711Y80389D01*
G01X288054Y74803D02*
X288030Y76304D01*
G01X288027Y75394D02*
X288037Y74803D01*
G01X286776Y81299D02*
X286767Y81890D01*
G01X286749D02*
X286774Y80389D01*
G01X284117Y74803D02*
X284093Y76304D01*
G01X284090Y75394D02*
X284100Y74803D01*
G01X282839Y81299D02*
X282830Y81890D01*
G01X282812D02*
X282837Y80389D01*
G01X280180Y74803D02*
X280156Y76304D01*
G01X280153Y75394D02*
X280163Y74803D01*
G01X290766D02*
X290735Y76392D01*
G01X290733Y75464D02*
X290746Y74803D01*
G01X288007Y81229D02*
X287995Y81890D01*
G01X287975D02*
X288006Y80301D01*
G01X286829Y74803D02*
X286798Y76392D01*
G01X286796Y75464D02*
X286809Y74803D01*
G01X284070Y81229D02*
X284058Y81890D01*
G01X284038D02*
X284069Y80301D01*
G01X282892Y74803D02*
X282861Y76392D01*
G01X282859Y75464D02*
X282872Y74803D01*
G01X280133Y81229D02*
X280121Y81890D01*
G01X280101D02*
X280131Y80301D01*
G01X278924D02*
X278955Y81890D01*
G01X278935D02*
X278922Y81229D01*
G01X276184Y74803D02*
X276196Y75464D01*
G01X276194Y76392D02*
X276164Y74803D01*
G01X274987Y80301D02*
X275018Y81890D01*
G01X274998D02*
X274985Y81229D01*
G01X272247Y74803D02*
X272259Y75464D01*
G01X272257Y76392D02*
X272227Y74803D01*
G01X271050Y80301D02*
X271081Y81890D01*
G01X271061D02*
X271048Y81229D01*
G01X268310Y74803D02*
X268322Y75464D01*
G01X268320Y76392D02*
X268290Y74803D01*
G01X267113Y80301D02*
X267144Y81890D01*
G01X267124D02*
X267111Y81229D01*
G01X278893Y74803D02*
X278902Y75394D01*
G01X278900Y76304D02*
X278875Y74803D01*
G01X276219Y80389D02*
X276243Y81890D01*
G01X276226D02*
X276216Y81299D01*
G01X274956Y74803D02*
X274965Y75394D01*
G01X274963Y76304D02*
X274938Y74803D01*
G01X272281Y80389D02*
X272306Y81890D01*
G01X272289D02*
X272279Y81299D01*
G01X271019Y74803D02*
X271028Y75394D01*
G01X271026Y76304D02*
X271001Y74803D01*
G01X268344Y80389D02*
X268369Y81890D01*
G01X268352D02*
X268342Y81299D01*
G01X267082Y74803D02*
X267091Y75394D01*
G01X267089Y76304D02*
X267064Y74803D01*
G01X278963Y72217D02*
X278958Y70430D01*
G01X278949Y70697D02*
X278954Y72484D01*
G01X276170Y68280D02*
X276165Y66493D01*
G01X276156Y66760D02*
X276161Y68547D01*
G01X275026Y89933D02*
X275021Y88146D01*
G01X275011Y88414D02*
X275017Y90201D01*
G01X272233Y85996D02*
X272228Y84209D01*
G01X272219Y84477D02*
X272223Y86264D01*
G01X271089Y72217D02*
X271084Y70430D01*
G01X271075Y70697D02*
X271080Y72484D01*
G01X268296Y68280D02*
X268291Y66493D01*
G01X268281Y66760D02*
X268287Y68547D01*
G01X267152Y89933D02*
X267147Y88146D01*
G01X267137Y88414D02*
X267143Y90201D01*
G01X279134Y98425D02*
Y92815D01*
G01X279095Y73917D02*
Y72933D01*
G01X279094Y82776D02*
Y83760D01*
G01X278939Y68996D02*
Y69980D01*
G01Y86713D02*
Y87697D01*
G01X276179Y68996D02*
Y69980D01*
G01Y86713D02*
Y87697D01*
G01X276024Y66043D02*
Y65059D01*
G01Y91634D02*
Y90650D01*
G01X275158Y66043D02*
Y65059D01*
G01X275157Y90650D02*
Y91634D01*
G01X275002Y69980D02*
Y68996D01*
G01Y87697D02*
Y86713D01*
G01X274606Y55512D02*
Y43701D01*
G01X272242Y69980D02*
Y68996D01*
G01Y86713D02*
Y87697D01*
G01X272087Y73917D02*
Y72933D01*
G01Y83760D02*
Y82776D01*
G01X271221Y73917D02*
Y72933D01*
G01X271220Y82776D02*
Y83760D01*
G01X271065Y68996D02*
Y69980D01*
G01Y87697D02*
Y86713D01*
G01X268305Y68996D02*
Y69980D01*
G01Y86713D02*
Y87697D01*
G01X268150Y66043D02*
Y65059D01*
G01Y91634D02*
Y90650D01*
G01X267284Y66043D02*
Y65059D01*
G01X267283Y90650D02*
Y91634D01*
G01X267128Y69980D02*
Y68996D01*
G01Y87697D02*
Y86713D01*
G01X278958Y86264D02*
X278963Y84477D01*
G01X278954Y84209D02*
X278948Y85996D01*
G01X276165Y90201D02*
X276170Y88414D01*
G01X276160Y88146D02*
X276156Y89933D01*
G01X275021Y68547D02*
X275026Y66760D01*
G01X275017Y66493D02*
X275012Y68280D01*
G01X272228Y72484D02*
X272233Y70697D01*
G01X272224Y70430D02*
X272219Y72217D01*
G01X271084Y86264D02*
X271089Y84477D01*
G01X271080Y84209D02*
X271074Y85996D01*
G01X268291Y90201D02*
X268296Y88414D01*
G01X268286Y88146D02*
X268281Y89933D01*
G01X267147Y68547D02*
X267152Y66760D01*
G01X267143Y66493D02*
X267138Y68280D01*
G01X278902Y81299D02*
X278893Y81890D01*
G01X278875D02*
X278900Y80389D01*
G01X276243Y74803D02*
X276219Y76304D01*
G01X276216Y75394D02*
X276226Y74803D01*
G01X274965Y81299D02*
X274956Y81890D01*
G01X274938D02*
X274963Y80389D01*
G01X272306Y74803D02*
X272281Y76304D01*
G01X272279Y75394D02*
X272289Y74803D01*
G01X271028Y81299D02*
X271019Y81890D01*
G01X271001D02*
X271026Y80389D01*
G01X268369Y74803D02*
X268344Y76304D01*
G01X268342Y75394D02*
X268352Y74803D01*
G01X267091Y81299D02*
X267081Y81890D01*
G01X267064D02*
X267089Y80389D01*
G01X278955Y74803D02*
X278924Y76392D01*
G01X278922Y75464D02*
X278935Y74803D01*
G01X276196Y81229D02*
X276184Y81890D01*
G01X276164D02*
X276194Y80301D01*
G01X275018Y74803D02*
X274987Y76392D01*
G01X274985Y75464D02*
X274998Y74803D01*
G01X272259Y81229D02*
X272247Y81890D01*
G01X272227D02*
X272257Y80301D01*
G01X271081Y74803D02*
X271050Y76392D01*
G01X271048Y75464D02*
X271061Y74803D01*
G01X268322Y81229D02*
X268310Y81890D01*
G01X268290D02*
X268320Y80301D01*
G01X267144Y74803D02*
X267113Y76392D01*
G01X267111Y75464D02*
X267124Y74803D01*
G01X264373D02*
X264385Y75464D01*
G01X264383Y76392D02*
X264353Y74803D01*
G01X263176Y80301D02*
X263207Y81890D01*
G01X263187D02*
X263174Y81229D01*
G01X260436Y74803D02*
X260448Y75464D01*
G01X260446Y76392D02*
X260416Y74803D01*
G01X259239Y80301D02*
X259270Y81890D01*
G01X259250D02*
X259237Y81229D01*
G01X256499Y74803D02*
X256511Y75464D01*
G01X256509Y76392D02*
X256479Y74803D01*
G01X255302Y80301D02*
X255333Y81890D01*
G01X255313D02*
X255300Y81229D01*
G01X264407Y80389D02*
X264432Y81890D01*
G01X264415D02*
X264405Y81299D01*
G01X263145Y74803D02*
X263154Y75394D01*
G01X263152Y76304D02*
X263127Y74803D01*
G01X260470Y80389D02*
X260495Y81890D01*
G01X260478D02*
X260468Y81299D01*
G01X259208Y74803D02*
X259217Y75394D01*
G01X259215Y76304D02*
X259190Y74803D01*
G01X256533Y80389D02*
X256558Y81890D01*
G01X256541D02*
X256531Y81299D01*
G01X255271Y74803D02*
X255280Y75394D01*
G01X255278Y76304D02*
X255253Y74803D01*
G01X264359Y85996D02*
X264354Y84209D01*
G01X264344Y84477D02*
X264349Y86264D01*
G01X263215Y72217D02*
X263210Y70430D01*
G01X263201Y70697D02*
X263206Y72484D01*
G01X260422Y68280D02*
X260417Y66493D01*
G01X260407Y66760D02*
X260413Y68547D01*
G01X259278Y89933D02*
X259273Y88146D01*
G01X259263Y88414D02*
X259269Y90201D01*
G01X256485Y85996D02*
X256480Y84209D01*
G01X256470Y84477D02*
X256475Y86264D01*
G01X255341Y72217D02*
X255336Y70430D01*
G01X255327Y70697D02*
X255331Y72484D01*
G01X264368Y69980D02*
Y68996D01*
G01Y87697D02*
Y86713D01*
G01X264213Y73917D02*
Y72933D01*
G01Y83760D02*
Y82776D01*
G01X263347Y73917D02*
Y72933D01*
G01X263346Y82776D02*
Y83760D01*
G01X263228Y98425D02*
Y92815D01*
G01X263191Y68996D02*
Y69980D01*
G01Y86713D02*
Y87697D01*
G01X260431Y68996D02*
Y69980D01*
G01Y86713D02*
Y87697D01*
G01X260276Y66043D02*
Y65059D01*
G01Y91634D02*
Y90650D01*
G01X259410Y66043D02*
Y65059D01*
G01X259409Y90650D02*
Y91634D01*
G01X259254Y69980D02*
Y68996D01*
G01Y87697D02*
Y86713D01*
G01X258228Y98425D02*
Y92815D01*
G01X256494Y69980D02*
Y68996D01*
G01Y87697D02*
Y86713D01*
G01X256339Y73917D02*
Y72933D01*
G01Y83760D02*
Y82776D01*
G01X255473Y73917D02*
Y72933D01*
G01X255472Y82776D02*
Y83760D01*
G01X255317Y68996D02*
Y69980D01*
G01Y86713D02*
Y87697D01*
G01X254921Y43701D02*
Y55512D01*
G01X264354Y72484D02*
X264359Y70697D01*
G01X264350Y70430D02*
X264344Y72217D01*
G01X263210Y86264D02*
X263215Y84477D01*
G01X263206Y84209D02*
X263200Y85996D01*
G01X260417Y90201D02*
X260422Y88414D01*
G01X260412Y88146D02*
X260407Y89933D01*
G01X259273Y68547D02*
X259278Y66760D01*
G01X259269Y66493D02*
X259264Y68280D01*
G01X256480Y72484D02*
X256485Y70697D01*
G01X256476Y70430D02*
X256470Y72217D01*
G01X255336Y86264D02*
X255341Y84477D01*
G01X255331Y84209D02*
X255326Y85996D01*
G01X264432Y74803D02*
X264407Y76304D01*
G01X264405Y75394D02*
X264415Y74803D01*
G01X263154Y81299D02*
X263144Y81890D01*
G01X263127D02*
X263152Y80389D01*
G01X260495Y74803D02*
X260470Y76304D01*
G01X260468Y75394D02*
X260478Y74803D01*
G01X259217Y81299D02*
X259207Y81890D01*
G01X259190D02*
X259215Y80389D01*
G01X256558Y74803D02*
X256533Y76304D01*
G01X256531Y75394D02*
X256541Y74803D01*
G01X255280Y81299D02*
X255270Y81890D01*
G01X255253D02*
X255278Y80389D01*
G01X264385Y81229D02*
X264373Y81890D01*
G01X264353D02*
X264383Y80301D01*
G01X263207Y74803D02*
X263176Y76392D01*
G01X263174Y75464D02*
X263187Y74803D01*
G01X260448Y81229D02*
X260436Y81890D01*
G01X260416D02*
X260446Y80301D01*
G01X259270Y74803D02*
X259239Y76392D01*
G01X259237Y75464D02*
X259250Y74803D01*
G01X256511Y81229D02*
X256499Y81890D01*
G01X256479D02*
X256509Y80301D01*
G01X255333Y74803D02*
X255302Y76392D01*
G01X255300Y75464D02*
X255313Y74803D01*
G01X252562D02*
X252574Y75464D01*
G01X252572Y76392D02*
X252542Y74803D01*
G01X251365Y80301D02*
X251396Y81890D01*
G01X251376D02*
X251363Y81229D01*
G01X248625Y74803D02*
X248637Y75464D01*
G01X248635Y76392D02*
X248605Y74803D01*
G01X247428Y80301D02*
X247459Y81890D01*
G01X247439D02*
X247426Y81229D01*
G01X244688Y74803D02*
X244700Y75464D01*
G01X244698Y76392D02*
X244668Y74803D01*
G01X243491Y80301D02*
X243522Y81890D01*
G01X243502D02*
X243489Y81229D01*
G01X252596Y80389D02*
X252621Y81890D01*
G01X252604D02*
X252594Y81299D01*
G01X251334Y74803D02*
X251343Y75394D01*
G01X251341Y76304D02*
X251316Y74803D01*
G01X248659Y80389D02*
X248684Y81890D01*
G01X248667D02*
X248657Y81299D01*
G01X247397Y74803D02*
X247406Y75394D01*
G01X247404Y76304D02*
X247379Y74803D01*
G01X244722Y80389D02*
X244747Y81890D01*
G01X244730D02*
X244720Y81299D01*
G01X243460Y74803D02*
X243469Y75394D01*
G01X243467Y76304D02*
X243442Y74803D01*
G01X252548Y68280D02*
X252543Y66493D01*
G01X252533Y66760D02*
X252539Y68547D01*
G01X251404Y89933D02*
X251399Y88146D01*
G01X251389Y88414D02*
X251394Y90201D01*
G01X248611Y85996D02*
X248606Y84209D01*
G01X248596Y84477D02*
X248601Y86264D01*
G01X247467Y72217D02*
X247462Y70430D01*
G01X247453Y70697D02*
X247457Y72484D01*
G01X244674Y68280D02*
X244669Y66493D01*
G01X244659Y66760D02*
X244665Y68547D01*
G01X243530Y89933D02*
X243525Y88146D01*
G01X243515Y88414D02*
X243520Y90201D01*
G01X240737Y85996D02*
X240732Y84209D01*
G01X240722Y84477D02*
X240727Y86264D01*
G01X252557Y68996D02*
Y69980D01*
G01Y86713D02*
Y87697D01*
G01X252402Y66043D02*
Y65059D01*
G01Y91634D02*
Y90650D01*
G01X251536Y66043D02*
Y65059D01*
G01X251535Y90650D02*
Y91634D01*
G01X251380Y69980D02*
Y68996D01*
G01Y87697D02*
Y86713D01*
G01X248620Y68996D02*
Y69980D01*
G01Y87697D02*
Y86713D01*
G01X248465Y73917D02*
Y72933D01*
G01Y83760D02*
Y82776D01*
G01X247599Y73917D02*
Y72933D01*
G01X247598Y82776D02*
Y83760D01*
G01X247443Y69980D02*
Y68996D01*
G01Y86713D02*
Y87697D01*
G01X244683Y68996D02*
Y69980D01*
G01Y86713D02*
Y87697D01*
G01X244528Y66043D02*
Y65059D01*
G01Y91634D02*
Y90650D01*
G01X243662Y66043D02*
Y65059D01*
G01X243661Y90650D02*
Y91634D01*
G01X243506Y69980D02*
Y68996D01*
G01Y87697D02*
Y86713D01*
G01X242323Y98425D02*
Y92815D01*
G01X240746Y69980D02*
Y68996D01*
G01Y87697D02*
Y86713D01*
G01X252543Y90201D02*
X252548Y88414D01*
G01X252538Y88146D02*
X252533Y89933D01*
G01X251399Y68547D02*
X251404Y66760D01*
G01X251394Y66493D02*
X251390Y68280D01*
G01X248606Y72484D02*
X248611Y70697D01*
G01X248602Y70430D02*
X248596Y72217D01*
G01X247462Y86264D02*
X247467Y84477D01*
G01X247457Y84209D02*
X247452Y85996D01*
G01X244669Y90201D02*
X244674Y88414D01*
G01X244664Y88146D02*
X244659Y89933D01*
G01X243525Y68547D02*
X243530Y66760D01*
G01X243520Y66493D02*
X243516Y68280D01*
G01X240732Y72484D02*
X240737Y70697D01*
G01X240728Y70430D02*
X240722Y72217D01*
G01X252621Y74803D02*
X252596Y76304D01*
G01X252594Y75394D02*
X252604Y74803D01*
G01X251343Y81299D02*
X251333Y81890D01*
G01X251316D02*
X251341Y80389D01*
G01X248684Y74803D02*
X248659Y76304D01*
G01X248657Y75394D02*
X248667Y74803D01*
G01X247406Y81299D02*
X247396Y81890D01*
G01X247379D02*
X247404Y80389D01*
G01X244747Y74803D02*
X244722Y76304D01*
G01X244720Y75394D02*
X244730Y74803D01*
G01X243469Y81299D02*
X243459Y81890D01*
G01X243442D02*
X243467Y80389D01*
G01X240810Y74803D02*
X240785Y76304D01*
G01X240783Y75394D02*
X240793Y74803D01*
G01X252574Y81229D02*
X252562Y81890D01*
G01X252542D02*
X252572Y80301D01*
G01X251396Y74803D02*
X251365Y76392D01*
G01X251363Y75464D02*
X251376Y74803D01*
G01X248637Y81229D02*
X248625Y81890D01*
G01X248605D02*
X248635Y80301D01*
G01X247459Y74803D02*
X247428Y76392D01*
G01X247426Y75464D02*
X247439Y74803D01*
G01X244700Y81229D02*
X244688Y81890D01*
G01X244668D02*
X244698Y80301D01*
G01X243522Y74803D02*
X243491Y76392D01*
G01X243489Y75464D02*
X243502Y74803D01*
G01X240763Y81229D02*
X240751Y81890D01*
G01X240731D02*
X240761Y80301D01*
G01X258228Y98425D02*
X242323D01*
G01X279134D02*
X263228D01*
G01X300039D02*
X284134D01*
G01X240751Y74803D02*
X240763Y75464D01*
G01X240761Y76392D02*
X240731Y74803D01*
G01X239554Y80301D02*
X239585Y81890D01*
G01X239565D02*
X239552Y81229D01*
G01X236814Y74803D02*
X236826Y75464D01*
G01X236824Y76392D02*
X236794Y74803D01*
G01X235617Y80301D02*
X235648Y81890D01*
G01X235628D02*
X235615Y81229D01*
G01X232877Y74803D02*
X232889Y75464D01*
G01X232887Y76392D02*
X232857Y74803D01*
G01X231680Y80301D02*
X231711Y81890D01*
G01X231691D02*
X231678Y81229D01*
G01X240785Y80389D02*
X240810Y81890D01*
G01X240793D02*
X240783Y81299D01*
G01X239523Y74803D02*
X239532Y75394D01*
G01X239530Y76304D02*
X239505Y74803D01*
G01X236848Y80389D02*
X236873Y81890D01*
G01X236856D02*
X236846Y81299D01*
G01X235586Y74803D02*
X235595Y75394D01*
G01X235593Y76304D02*
X235568Y74803D01*
G01X232911Y80389D02*
X232936Y81890D01*
G01X232919D02*
X232909Y81299D01*
G01X231649Y74803D02*
X231658Y75394D01*
G01X231656Y76304D02*
X231631Y74803D01*
G01X239593Y72217D02*
X239588Y70430D01*
G01X239579Y70697D02*
X239583Y72484D01*
G01X236800Y68280D02*
X236795Y66493D01*
G01X236785Y66760D02*
X236791Y68547D01*
G01X235656Y89933D02*
X235651Y88146D01*
G01X235641Y88414D02*
X235646Y90201D01*
G01X232863Y85996D02*
X232858Y84209D01*
G01X232848Y84477D02*
X232853Y86264D01*
G01X231719Y72217D02*
X231714Y70430D01*
G01X231705Y70697D02*
X231709Y72484D01*
G01X240591Y73917D02*
Y72933D01*
G01Y83760D02*
Y82776D01*
G01X239725Y73917D02*
Y72933D01*
G01X239724Y82776D02*
Y83760D01*
G01X239569Y68996D02*
Y69980D01*
G01Y86713D02*
Y87697D01*
G01X237323Y98425D02*
Y92815D01*
G01X236809Y68996D02*
Y69980D01*
G01Y86713D02*
Y87697D01*
G01X236654Y66043D02*
Y65059D01*
G01Y91634D02*
Y90650D01*
G01X235788Y66043D02*
Y65059D01*
G01X235787Y90650D02*
Y91634D01*
G01X235632Y69980D02*
Y68996D01*
G01Y87697D02*
Y86713D01*
G01X232872Y69980D02*
Y68996D01*
G01Y87697D02*
Y86713D01*
G01X232717Y73917D02*
Y72933D01*
G01Y83760D02*
Y82776D01*
G01X231851Y73917D02*
Y72933D01*
G01X231850Y82776D02*
Y83760D01*
G01X231695Y68996D02*
Y69980D01*
G01Y86713D02*
Y87697D01*
G01X239588Y86264D02*
X239593Y84477D01*
G01X239583Y84209D02*
X239578Y85996D01*
G01X236795Y90201D02*
X236800Y88414D01*
G01X236790Y88146D02*
X236785Y89933D01*
G01X235651Y68547D02*
X235656Y66760D01*
G01X235646Y66493D02*
X235642Y68280D01*
G01X232858Y72484D02*
X232863Y70697D01*
G01X232854Y70430D02*
X232848Y72217D01*
G01X231714Y86264D02*
X231719Y84477D01*
G01X231709Y84209D02*
X231704Y85996D01*
G01X239532Y81299D02*
X239522Y81890D01*
G01X239505D02*
X239530Y80389D01*
G01X236873Y74803D02*
X236848Y76304D01*
G01X236846Y75394D02*
X236856Y74803D01*
G01X235595Y81299D02*
X235585Y81890D01*
G01X235568D02*
X235593Y80389D01*
G01X232936Y74803D02*
X232911Y76304D01*
G01X232909Y75394D02*
X232919Y74803D01*
G01X231658Y81299D02*
X231648Y81890D01*
G01X231631D02*
X231656Y80389D01*
G01X239585Y74803D02*
X239554Y76392D01*
G01X239552Y75464D02*
X239565Y74803D01*
G01X236826Y81229D02*
X236814Y81890D01*
G01X236794D02*
X236824Y80301D01*
G01X235648Y74803D02*
X235617Y76392D01*
G01X235615Y75464D02*
X235628Y74803D01*
G01X232889Y81229D02*
X232877Y81890D01*
G01X232857D02*
X232887Y80301D01*
G01X231711Y74803D02*
X231680Y76392D01*
G01X231678Y75464D02*
X231691Y74803D01*
G01X236776Y91634D02*
X235665D01*
G01X244650D02*
X243539D01*
G01X252524D02*
X251413D01*
G01X260398D02*
X259287D01*
G01X268272D02*
X267161D01*
G01X276146D02*
X275035D01*
G01X284020D02*
X282909D01*
G01X291894D02*
X290783D01*
G01X236776Y90650D02*
X235665D01*
G01X244650D02*
X243539D01*
G01X252524D02*
X251413D01*
G01X260398D02*
X259287D01*
G01X268272D02*
X267161D01*
G01X276146D02*
X275035D01*
G01X284020D02*
X282909D01*
G01X291894D02*
X290783D01*
G01X290765Y90201D02*
X291913D01*
G01X282891D02*
X284039D01*
G01X275017D02*
X276165D01*
G01X267143D02*
X268291D01*
G01X259269D02*
X260417D01*
G01X251394D02*
X252543D01*
G01X243520D02*
X244669D01*
G01X235646D02*
X236795D01*
G01X236785Y89933D02*
X235656D01*
G01X244659D02*
X243530D01*
G01X252533D02*
X251404D01*
G01X260407D02*
X259278D01*
G01X268281D02*
X267152D01*
G01X276156D02*
X275026D01*
G01X284030D02*
X282900D01*
G01X291904D02*
X290774D01*
G01X236800Y88414D02*
X235641D01*
G01X244674D02*
X243515D01*
G01X252548D02*
X251389D01*
G01X260422D02*
X259263D01*
G01X268296D02*
X267137D01*
G01X276170D02*
X275011D01*
G01X284044D02*
X282885D01*
G01X291918D02*
X290759D01*
G01X290769Y88146D02*
X291908D01*
G01X282895D02*
X284034D01*
G01X275021D02*
X276160D01*
G01X267147D02*
X268286D01*
G01X259273D02*
X260412D01*
G01X251399D02*
X252538D01*
G01X243525D02*
X244664D01*
G01X235651D02*
X236790D01*
G01X232872Y87697D02*
X231695D01*
G01X236809D02*
X235632D01*
G01X240746D02*
X239569D01*
G01X244683D02*
X243506D01*
G01X248620D02*
X247443D01*
G01X252557D02*
X251380D01*
G01X256494D02*
X255317D01*
G01X260431D02*
X259254D01*
G01X264368D02*
X263191D01*
G01X268305D02*
X267128D01*
G01X272242D02*
X271065D01*
G01X276179D02*
X275002D01*
G01X280116D02*
X278939D01*
G01X284053D02*
X282876D01*
G01X287990D02*
X286813D01*
G01X291927D02*
X290750D01*
G01X232872Y86713D02*
X231695D01*
G01X236809D02*
X235632D01*
G01X240746D02*
X239569D01*
G01X244683D02*
X243506D01*
G01X248620D02*
X247443D01*
G01X252557D02*
X251380D01*
G01X256494D02*
X255317D01*
G01X260431D02*
X259254D01*
G01X264368D02*
X263191D01*
G01X268305D02*
X267128D01*
G01X272242D02*
X271065D01*
G01X276179D02*
X275002D01*
G01X280116D02*
X278939D01*
G01X284053D02*
X282876D01*
G01X287990D02*
X286813D01*
G01X291927D02*
X290750D01*
G01X232853Y86264D02*
X231714D01*
G01X240727D02*
X239588D01*
G01X248601D02*
X247462D01*
G01X256475D02*
X255336D01*
G01X264349D02*
X263210D01*
G01X272223D02*
X271084D01*
G01X280097D02*
X278958D01*
G01X287971D02*
X286832D01*
G01X286822Y85996D02*
X287981D01*
G01X278948D02*
X280107D01*
G01X271074D02*
X272233D01*
G01X263200D02*
X264359D01*
G01X255326D02*
X256485D01*
G01X247452D02*
X248611D01*
G01X239578D02*
X240737D01*
G01X231704D02*
X232863D01*
G01X286837Y84477D02*
X287967D01*
G01X278963D02*
X280093D01*
G01X271089D02*
X272219D01*
G01X263215D02*
X264344D01*
G01X255341D02*
X256470D01*
G01X247467D02*
X248596D01*
G01X239593D02*
X240722D01*
G01X231719D02*
X232848D01*
G01X232858Y84209D02*
X231709D01*
G01X240732D02*
X239583D01*
G01X248606D02*
X247457D01*
G01X256480D02*
X255331D01*
G01X264354D02*
X263206D01*
G01X272228D02*
X271080D01*
G01X280102D02*
X278954D01*
G01X287976D02*
X286828D01*
G01X232839Y83760D02*
X231728D01*
G01X240713D02*
X239602D01*
G01X248587D02*
X247476D01*
G01X256461D02*
X255350D01*
G01X264335D02*
X263224D01*
G01X272209D02*
X271098D01*
G01X280083D02*
X278972D01*
G01X287957D02*
X286846D01*
G01X232839Y82776D02*
X231728D01*
G01X240713D02*
X239602D01*
G01X248587D02*
X247476D01*
G01X256461D02*
X255350D01*
G01X264335D02*
X263224D01*
G01X272209D02*
X271098D01*
G01X280083D02*
X278972D01*
G01X287957D02*
X286846D01*
G01X232909Y81299D02*
X231658D01*
G01X236846D02*
X235595D01*
G01X240783D02*
X239532D01*
G01X244720D02*
X243469D01*
G01X248657D02*
X247406D01*
G01X252594D02*
X251343D01*
G01X256531D02*
X255280D01*
G01X260468D02*
X259217D01*
G01X264405D02*
X263154D01*
G01X268342D02*
X267091D01*
G01X272279D02*
X271028D01*
G01X276216D02*
X274965D01*
G01X280153D02*
X278902D01*
G01X284090D02*
X282839D01*
G01X288027D02*
X286776D01*
G01X291964D02*
X290713D01*
G01X290733Y81229D02*
X291944D01*
G01X286796D02*
X288007D01*
G01X282859D02*
X284070D01*
G01X278922D02*
X280133D01*
G01X274985D02*
X276196D01*
G01X271048D02*
X272259D01*
G01X267111D02*
X268322D01*
G01X263174D02*
X264385D01*
G01X259237D02*
X260448D01*
G01X255300D02*
X256511D01*
G01X251363D02*
X252574D01*
G01X247426D02*
X248637D01*
G01X243489D02*
X244700D01*
G01X239552D02*
X240763D01*
G01X235615D02*
X236826D01*
G01X231678D02*
X232889D01*
G01X232898Y81004D02*
X231669D01*
G01X236835D02*
X235606D01*
G01X240772D02*
X239543D01*
G01X244709D02*
X243480D01*
G01X248646D02*
X247417D01*
G01X252583D02*
X251354D01*
G01X256520D02*
X255291D01*
G01X260457D02*
X259228D01*
G01X264394D02*
X263165D01*
G01X268331D02*
X267102D01*
G01X272269D02*
X271039D01*
G01X276206D02*
X274976D01*
G01X280143D02*
X278913D01*
G01X284080D02*
X282850D01*
G01X288017D02*
X286787D01*
G01X291954D02*
X290724D01*
G01X290711Y80389D02*
X291967D01*
G01X286774D02*
X288030D01*
G01X282837D02*
X284093D01*
G01X278900D02*
X280156D01*
G01X274963D02*
X276219D01*
G01X271026D02*
X272281D01*
G01X267089D02*
X268344D01*
G01X263152D02*
X264407D01*
G01X259215D02*
X260470D01*
G01X255278D02*
X256533D01*
G01X251341D02*
X252596D01*
G01X247404D02*
X248659D01*
G01X243467D02*
X244722D01*
G01X239530D02*
X240785D01*
G01X235593D02*
X236848D01*
G01X231656D02*
X232911D01*
G01X232887Y80301D02*
X231680D01*
G01X236824D02*
X235617D01*
G01X240761D02*
X239554D01*
G01X244698D02*
X243491D01*
G01X248635D02*
X247428D01*
G01X252572D02*
X251365D01*
G01X256509D02*
X255302D01*
G01X260446D02*
X259239D01*
G01X264383D02*
X263176D01*
G01X268320D02*
X267113D01*
G01X272257D02*
X271050D01*
G01X276194D02*
X274987D01*
G01X280131D02*
X278924D01*
G01X284069D02*
X282861D01*
G01X288006D02*
X286798D01*
G01X291943D02*
X290735D01*
G01X232898Y80019D02*
X231669D01*
G01X236835D02*
X235606D01*
G01X240772D02*
X239543D01*
G01X244709D02*
X243480D01*
G01X248646D02*
X247417D01*
G01X252583D02*
X251354D01*
G01X256520D02*
X255291D01*
G01X260457D02*
X259228D01*
G01X264394D02*
X263165D01*
G01X268331D02*
X267102D01*
G01X272269D02*
X271039D01*
G01X276206D02*
X274976D01*
G01X280143D02*
X278913D01*
G01X284080D02*
X282850D01*
G01X288017D02*
X286787D01*
G01X291954D02*
X290724D01*
G01Y76674D02*
X291954D01*
G01X286787D02*
X288017D01*
G01X282850D02*
X284080D01*
G01X278913D02*
X280143D01*
G01X274976D02*
X276206D01*
G01X271039D02*
X272269D01*
G01X267102D02*
X268331D01*
G01X263165D02*
X264394D01*
G01X259228D02*
X260457D01*
G01X255291D02*
X256520D01*
G01X251354D02*
X252583D01*
G01X247417D02*
X248646D01*
G01X243480D02*
X244709D01*
G01X239543D02*
X240772D01*
G01X235606D02*
X236835D01*
G01X231669D02*
X232898D01*
G01X290735Y76392D02*
X291943D01*
G01X286798D02*
X288006D01*
G01X282861D02*
X284069D01*
G01X278924D02*
X280131D01*
G01X274987D02*
X276194D01*
G01X271050D02*
X272257D01*
G01X267113D02*
X268320D01*
G01X263176D02*
X264383D01*
G01X259239D02*
X260446D01*
G01X255302D02*
X256509D01*
G01X251365D02*
X252572D01*
G01X247428D02*
X248635D01*
G01X243491D02*
X244698D01*
G01X239554D02*
X240761D01*
G01X235617D02*
X236824D01*
G01X231680D02*
X232887D01*
G01X232911Y76304D02*
X231656D01*
G01X236848D02*
X235593D01*
G01X240785D02*
X239530D01*
G01X244722D02*
X243467D01*
G01X248659D02*
X247404D01*
G01X252596D02*
X251341D01*
G01X256533D02*
X255278D01*
G01X260470D02*
X259215D01*
G01X264407D02*
X263152D01*
G01X268344D02*
X267089D01*
G01X272281D02*
X271026D01*
G01X276219D02*
X274963D01*
G01X280156D02*
X278900D01*
G01X284093D02*
X282837D01*
G01X288030D02*
X286774D01*
G01X291967D02*
X290711D01*
G01X290724Y75690D02*
X291954D01*
G01X286787D02*
X288017D01*
G01X282850D02*
X284080D01*
G01X278913D02*
X280143D01*
G01X274976D02*
X276206D01*
G01X271039D02*
X272269D01*
G01X267102D02*
X268331D01*
G01X263165D02*
X264394D01*
G01X259228D02*
X260457D01*
G01X255291D02*
X256520D01*
G01X251354D02*
X252583D01*
G01X247417D02*
X248646D01*
G01X243480D02*
X244709D01*
G01X239543D02*
X240772D01*
G01X235606D02*
X236835D01*
G01X231669D02*
X232898D01*
G01X232889Y75464D02*
X231678D01*
G01X236826D02*
X235615D01*
G01X240763D02*
X239552D01*
G01X244700D02*
X243489D01*
G01X248637D02*
X247426D01*
G01X252574D02*
X251363D01*
G01X256511D02*
X255300D01*
G01X260448D02*
X259237D01*
G01X264385D02*
X263174D01*
G01X268322D02*
X267111D01*
G01X272259D02*
X271048D01*
G01X276196D02*
X274985D01*
G01X280133D02*
X278922D01*
G01X284070D02*
X282859D01*
G01X288007D02*
X286796D01*
G01X291944D02*
X290733D01*
G01X290713Y75394D02*
X291964D01*
G01X286776D02*
X288027D01*
G01X282839D02*
X284090D01*
G01X278902D02*
X280153D01*
G01X274965D02*
X276216D01*
G01X271028D02*
X272279D01*
G01X267091D02*
X268342D01*
G01X263154D02*
X264405D01*
G01X259217D02*
X260468D01*
G01X255280D02*
X256531D01*
G01X251343D02*
X252594D01*
G01X247406D02*
X248657D01*
G01X243469D02*
X244720D01*
G01X239532D02*
X240783D01*
G01X235595D02*
X236846D01*
G01X231658D02*
X232909D01*
G01X286846Y73917D02*
X287957D01*
G01X278972D02*
X280083D01*
G01X271098D02*
X272209D01*
G01X263224D02*
X264335D01*
G01X255350D02*
X256461D01*
G01X247476D02*
X248587D01*
G01X239602D02*
X240713D01*
G01X231728D02*
X232839D01*
G01X286846Y72933D02*
X287957D01*
G01X278972D02*
X280083D01*
G01X271098D02*
X272209D01*
G01X263224D02*
X264335D01*
G01X255350D02*
X256461D01*
G01X247476D02*
X248587D01*
G01X239602D02*
X240713D01*
G01X231728D02*
X232839D01*
G01X286828Y72484D02*
X287976D01*
G01X278954D02*
X280102D01*
G01X271080D02*
X272228D01*
G01X263206D02*
X264354D01*
G01X255331D02*
X256480D01*
G01X247457D02*
X248606D01*
G01X239583D02*
X240732D01*
G01X231709D02*
X232858D01*
G01X232848Y72217D02*
X231719D01*
G01X240722D02*
X239593D01*
G01X248596D02*
X247467D01*
G01X256470D02*
X255341D01*
G01X264344D02*
X263215D01*
G01X272219D02*
X271089D01*
G01X280093D02*
X278963D01*
G01X287967D02*
X286837D01*
G01X232863Y70697D02*
X231705D01*
G01X240737D02*
X239579D01*
G01X248611D02*
X247453D01*
G01X256485D02*
X255327D01*
G01X264359D02*
X263201D01*
G01X272233D02*
X271075D01*
G01X280107D02*
X278949D01*
G01X287981D02*
X286823D01*
G01X286832Y70430D02*
X287972D01*
G01X278958D02*
X280098D01*
G01X271084D02*
X272224D01*
G01X263210D02*
X264350D01*
G01X255336D02*
X256476D01*
G01X247462D02*
X248602D01*
G01X239588D02*
X240728D01*
G01X231714D02*
X232854D01*
G01X290750Y69980D02*
X291927D01*
G01X286813D02*
X287990D01*
G01X282876D02*
X284053D01*
G01X278939D02*
X280116D01*
G01X275002D02*
X276179D01*
G01X271065D02*
X272242D01*
G01X267128D02*
X268305D01*
G01X263191D02*
X264368D01*
G01X259254D02*
X260431D01*
G01X255317D02*
X256494D01*
G01X251380D02*
X252557D01*
G01X247443D02*
X248620D01*
G01X243506D02*
X244683D01*
G01X239569D02*
X240746D01*
G01X235632D02*
X236809D01*
G01X231695D02*
X232872D01*
G01Y68996D02*
X231695D01*
G01X236809D02*
X235632D01*
G01X240746D02*
X239569D01*
G01X244683D02*
X243506D01*
G01X248620D02*
X247443D01*
G01X252557D02*
X251380D01*
G01X256494D02*
X255317D01*
G01X260431D02*
X259254D01*
G01X264368D02*
X263191D01*
G01X268305D02*
X267128D01*
G01X272242D02*
X271065D01*
G01X276179D02*
X275002D01*
G01X280116D02*
X278939D01*
G01X284053D02*
X282876D01*
G01X287990D02*
X286813D01*
G01X291927D02*
X290750D01*
G01X236791Y68547D02*
X235651D01*
G01X244665D02*
X243525D01*
G01X252539D02*
X251399D01*
G01X260413D02*
X259273D01*
G01X268287D02*
X267147D01*
G01X276161D02*
X275021D01*
G01X284035D02*
X282895D01*
G01X291909D02*
X290769D01*
G01X290760Y68280D02*
X291918D01*
G01X282886D02*
X284044D01*
G01X275012D02*
X276170D01*
G01X267138D02*
X268296D01*
G01X259264D02*
X260422D01*
G01X251390D02*
X252548D01*
G01X243516D02*
X244674D01*
G01X235642D02*
X236800D01*
G01X290774Y66760D02*
X291904D01*
G01X282900D02*
X284030D01*
G01X275026D02*
X276156D01*
G01X267152D02*
X268281D01*
G01X259278D02*
X260407D01*
G01X251404D02*
X252533D01*
G01X243530D02*
X244659D01*
G01X235656D02*
X236785D01*
G01X236795Y66493D02*
X235646D01*
G01X244669D02*
X243520D01*
G01X252543D02*
X251394D01*
G01X260417D02*
X259269D01*
G01X268291D02*
X267143D01*
G01X276165D02*
X275017D01*
G01X284039D02*
X282891D01*
G01X291913D02*
X290765D01*
G01X236776Y66043D02*
X235665D01*
G01X244650D02*
X243539D01*
G01X252524D02*
X251413D01*
G01X260398D02*
X259287D01*
G01X268272D02*
X267161D01*
G01X276146D02*
X275035D01*
G01X284020D02*
X282909D01*
G01X291894D02*
X290783D01*
G01X300197Y65354D02*
X291339D01*
G01X290783Y65059D02*
X291894D01*
G01X282909D02*
X284020D01*
G01X275035D02*
X276146D01*
G01X267161D02*
X268272D01*
G01X259287D02*
X260398D01*
G01X251413D02*
X252524D01*
G01X243539D02*
X244650D01*
G01X235665D02*
X236776D01*
G01X284843Y59449D02*
X296654D01*
G01X258858D02*
X270669D01*
G01X284843Y106693D02*
G03Y114567I0J3937D01*
G01X280906Y278741D02*
G03X284843Y274804I3937J0D01*
G01X270669D02*
G03X274606Y278741I0J3937D01*
G01X254921D02*
G03X258858Y274804I3937J0D01*
G01X280906Y278741D02*
Y290552D01*
G01X274606D02*
Y278741D01*
G01X254921D02*
Y290552D01*
G01X270669Y274804D02*
X258858D01*
G01X296654D02*
X284843D01*
G01Y294489D02*
G03X280906Y290552I0J-3937D01*
G01X258858Y294489D02*
G03X254921Y290552I0J-3937D01*
G01X274606D02*
G03X270669Y294489I-3937J0D01*
G01X284843D02*
X296654D01*
G01X258858D02*
X270669D01*
G01X284843Y341733D02*
G03Y349607I0J3937D01*
G01X280906Y513780D02*
G03X284843Y509843I3937J0D01*
G01Y529528D02*
G03X280906Y525591I0J-3937D01*
G01X270669Y509843D02*
G03X274606Y513780I0J3937D01*
G01X254921D02*
G03X258858Y509843I3937J0D01*
G01Y529528D02*
G03X254921Y525591I0J-3937D01*
G01X274606D02*
G03X270669Y529528I-3937J0D01*
G01X280906Y513780D02*
Y525591D01*
G01X274606D02*
Y513780D01*
G01X254921D02*
Y525591D01*
G01X284843Y529528D02*
X296654D01*
G01X258858D02*
X270669D01*
G01Y509843D02*
X258858D01*
G01X296654D02*
X284843D01*
G01Y576772D02*
G03Y584646I0J3937D01*
G01X308858Y29331D02*
G03X301378I-3740J0D01*
G01X322638Y39764D02*
G03X326575Y43701I0J3937D01*
G01X306890D02*
G03X310827Y39764I3937J0D01*
G01X296654D02*
G03X300591Y43701I0J3937D01*
G01X350669Y17047D02*
X350013Y15079D01*
G01X350259D02*
X350423Y15581D01*
G01X350833Y16880D02*
X350465Y15749D01*
G01X351772Y22047D02*
Y9449D01*
G01X349685Y16419D02*
Y16754D01*
G01X349439Y15079D02*
Y16712D01*
G01X349193Y17047D02*
Y15079D01*
G01X349016Y9449D02*
Y22047D01*
G01X347835Y5512D02*
Y22047D01*
G01X345079D02*
Y5512D01*
G01X351203Y15749D02*
X350833Y16880D01*
G01X351244Y15581D02*
X351407Y15079D01*
G01X350984Y0D02*
X352953Y1969D01*
G01X343898Y5512D02*
Y22047D01*
G01X341142D02*
Y5512D01*
G01X339961D02*
Y22047D01*
G01X337205D02*
Y5512D01*
G01X336024D02*
Y22047D01*
G01X333268D02*
Y5512D01*
G01X332087D02*
Y22047D01*
G01X351654Y15079D02*
X350998Y17047D01*
G01X329331Y22047D02*
Y5512D01*
G01X328150D02*
Y22047D01*
G01X325394D02*
Y5512D01*
G01X324213D02*
Y22047D01*
G01X321457D02*
Y5512D01*
G01X320276D02*
Y22047D01*
G01X311614Y17244D02*
X310958Y15276D01*
G01X300157Y17047D02*
X299502Y15079D01*
G01X311204Y15276D02*
X311368Y15778D01*
G01X311778Y17077D02*
X311409Y15946D01*
G01X299748Y15079D02*
X299911Y15581D01*
G01X300322Y16880D02*
X299953Y15749D01*
G01X317520Y22047D02*
Y5512D01*
G01X316339D02*
Y22047D01*
G01X313583D02*
Y5512D01*
G01X312402D02*
Y22047D01*
G01X310630Y16616D02*
Y16951D01*
G01X310384Y15276D02*
Y16909D01*
G01X310138Y17244D02*
Y15276D01*
G01X309810Y16616D02*
Y16951D01*
G01X309646Y22047D02*
Y5512D01*
G01X309564Y15276D02*
Y16909D01*
G01X309318Y17244D02*
Y15276D01*
G01X308858Y1969D02*
Y29331D01*
G01X312148Y15946D02*
X311778Y17077D01*
G01X312189Y15778D02*
X312352Y15276D01*
G01X312598D02*
X311943Y17244D01*
G01X299409Y0D02*
X301378Y1969D01*
G01X297123Y16587D02*
X297205Y16712D01*
G01X296918Y16754D02*
X296877Y16587D01*
G01X301378Y1969D02*
Y29331D01*
G01X300591Y22047D02*
Y5512D01*
G01X299173Y16419D02*
Y16754D01*
G01X298927Y15079D02*
Y16712D01*
G01X298681Y17047D02*
Y15079D01*
G01X298353D02*
Y15288D01*
G01X297835Y5512D02*
Y22047D01*
G01X297123Y16503D02*
Y16587D01*
G01X296877Y15288D02*
Y15079D01*
G01Y16587D02*
Y16503D01*
G01X296654Y22047D02*
Y5512D01*
G01X293898D02*
Y22047D01*
G01X292717D02*
Y5512D01*
G01X298312Y16587D02*
X298271Y16754D01*
G01X296877Y16503D02*
X296918Y16335D01*
G01X300691Y15749D02*
X300322Y16880D01*
G01X300732Y15581D02*
X300896Y15079D01*
G01X301142D02*
X300486Y17047D01*
G01X349685Y16754D02*
X349439Y17047D01*
G01Y16712D02*
X349685Y16419D01*
G01X297082Y16922D02*
X296918Y16754D01*
G01X297205Y16335D02*
X297123Y16503D01*
G01X297246Y17006D02*
X297082Y16922D01*
G01X297205Y16712D02*
X297328Y16796D01*
G01X298025Y16712D02*
X298107Y16587D01*
G01X296918Y16335D02*
X297000Y16210D01*
G01X310630Y16951D02*
X310384Y17244D01*
G01Y16909D02*
X310630Y16616D01*
G01X309810Y16951D02*
X309564Y17244D01*
G01Y16909D02*
X309810Y16616D01*
G01X299173Y16754D02*
X298927Y17047D01*
G01Y16712D02*
X299173Y16419D01*
G01X298271Y16754D02*
X298107Y16922D01*
G01X308858Y1969D02*
X310827Y0D01*
G01X298353Y15288D02*
X297205Y16335D01*
G01X297000Y16210D02*
X298025Y15288D01*
G01X297902Y16796D02*
X298025Y16712D01*
G01X298107Y16922D02*
X297943Y17006D01*
G01X297697Y16838D02*
X297902Y16796D01*
G01X297943Y17006D02*
X297656Y17047D01*
G01X322638Y39764D02*
X310827D01*
G01X349016Y22047D02*
X351772D01*
G01X297835D02*
X300591D01*
G01X293898D02*
X296654D01*
G01X312402D02*
X309646D01*
G01X316339D02*
X313583D01*
G01X320276D02*
X317520D01*
G01X324213D02*
X321457D01*
G01X328150D02*
X325394D01*
G01X332087D02*
X329331D01*
G01X336024D02*
X333268D01*
G01X339961D02*
X337205D01*
G01X343898D02*
X341142D01*
G01X347835D02*
X345079D01*
G01X309564Y17244D02*
X309318D01*
G01X310384D02*
X310138D01*
G01X311943D02*
X311614D01*
G01X297656Y17047D02*
X297492D01*
G01X298927D02*
X298681D01*
G01X300486D02*
X300157D01*
G01X349439D02*
X349193D01*
G01X350998D02*
X350669D01*
G01X297533Y16838D02*
X297697D01*
G01X298107Y16587D02*
X298312D01*
G01X311409Y15946D02*
X312148D01*
G01X311368Y15778D02*
X312189D01*
G01X350465Y15749D02*
X351203D01*
G01X299953D02*
X300691D01*
G01X350423Y15581D02*
X351244D01*
G01X299911D02*
X300732D01*
G01X298025Y15288D02*
X296877D01*
G01X312352Y15276D02*
X312598D01*
G01X310138D02*
X310384D01*
G01X310958D02*
X311204D01*
G01X309318D02*
X309564D01*
G01X351407Y15079D02*
X351654D01*
G01X350013D02*
X350259D01*
G01X349193D02*
X349439D01*
G01X300896D02*
X301142D01*
G01X299502D02*
X299748D01*
G01X298681D02*
X298927D01*
G01X296877D02*
X298353D01*
G01X351772Y9449D02*
X349016D01*
G01X345079Y5512D02*
X347835D01*
G01X341142D02*
X343898D01*
G01X337205D02*
X339961D01*
G01X333268D02*
X336024D01*
G01X329331D02*
X332087D01*
G01X325394D02*
X328150D01*
G01X321457D02*
X324213D01*
G01X317520D02*
X320276D01*
G01X313583D02*
X316339D01*
G01X309646D02*
X312402D01*
G01X308858D02*
X352953D01*
G01X296654D02*
X293898D01*
G01X300591D02*
X297835D01*
G01X309572D02*
X309326D01*
G01X310966D02*
X310720D01*
G01X350984Y0D02*
X310827D01*
G01X297492Y17047D02*
X297246Y17006D01*
G01X297328Y16796D02*
X297533Y16838D01*
G01X301969Y76873D02*
G03Y79820I2559J1474D01*
G01X308268Y80107D02*
G03X301969Y81593I-3740J-1761D01*
G01Y75100D02*
G03X308268Y76586I2559J3247D01*
G01Y80719D02*
G03X301969Y81962I-3740J-2372D01*
G01Y74731D02*
G03X308268Y75974I2559J3615D01*
G01X310827Y59449D02*
G03X306890Y55512I0J-3937D01*
G01X326575D02*
G03X322638Y59449I-3937J0D01*
G01X300591Y55512D02*
G03X296654Y59449I-3937J0D01*
G01X350459Y66535D02*
X350591Y66133D01*
G01X350624Y66000D02*
X350919Y65095D01*
G01X350263Y66535D02*
X350787Y64961D01*
G01X350987Y74803D02*
X351000Y75464D01*
G01X350998Y76392D02*
X350967Y74803D01*
G01X349790Y80301D02*
X349821Y81890D01*
G01X349801D02*
X349788Y81229D01*
G01X347050Y74803D02*
X347063Y75464D01*
G01X347061Y76392D02*
X347030Y74803D01*
G01X345853Y80301D02*
X345884Y81890D01*
G01X345864D02*
X345851Y81229D01*
G01X351022Y80389D02*
X351046Y81890D01*
G01X351029D02*
X351019Y81299D01*
G01X349759Y74803D02*
X349769Y75394D01*
G01X349766Y76304D02*
X349741Y74803D01*
G01X347085Y80389D02*
X347109Y81890D01*
G01X347092D02*
X347082Y81299D01*
G01X345822Y74803D02*
X345831Y75394D01*
G01X345829Y76304D02*
X345804Y74803D01*
G01X350973Y85996D02*
X350968Y84209D01*
G01X350959Y84477D02*
X350963Y86264D01*
G01X349829Y72217D02*
X349824Y70430D01*
G01X349815Y70697D02*
X349820Y72484D01*
G01X347036Y68280D02*
X347031Y66493D01*
G01X347022Y66760D02*
X347027Y68547D01*
G01X345892Y89933D02*
X345887Y88146D01*
G01X345878Y88414D02*
X345883Y90201D01*
G01X350982Y69980D02*
Y68996D01*
G01Y87697D02*
Y86713D01*
G01X350827Y73917D02*
Y72933D01*
G01Y83760D02*
Y82776D01*
G01X350000Y65463D02*
Y65195D01*
G01X349961Y73917D02*
Y72933D01*
G01Y82776D02*
Y83760D01*
G01X349806Y68996D02*
Y69980D01*
G01Y86713D02*
Y87697D01*
G01X349803Y66535D02*
Y65229D01*
G01X349606Y64961D02*
Y66535D01*
G01X347045Y68996D02*
Y69980D01*
G01Y86713D02*
Y87697D01*
G01X346890Y66043D02*
Y65059D01*
G01Y91634D02*
Y90650D01*
G01X346850Y98425D02*
Y92815D01*
G01X346457Y91142D02*
Y90945D01*
G01X346024Y66043D02*
Y65059D01*
G01Y90650D02*
Y91634D01*
G01X345869Y69980D02*
Y68996D01*
G01Y87697D02*
Y86713D01*
G01X345226Y65354D02*
Y65551D01*
G01X344980Y90945D02*
Y91142D01*
G01X344734Y65354D02*
Y65551D01*
G01X344488Y65354D02*
Y65551D01*
G01X350968Y72484D02*
X350973Y70697D01*
G01X350964Y70430D02*
X350959Y72217D01*
G01X349824Y86264D02*
X349829Y84477D01*
G01X349820Y84209D02*
X349815Y85996D01*
G01X347031Y90201D02*
X347036Y88414D01*
G01X347026Y88146D02*
X347022Y89933D01*
G01X345887Y68547D02*
X345892Y66760D01*
G01X345883Y66493D02*
X345878Y68280D01*
G01X351046Y74803D02*
X351022Y76304D01*
G01X351019Y75394D02*
X351029Y74803D01*
G01X349769Y81299D02*
X349759Y81890D01*
G01X349741D02*
X349766Y80389D01*
G01X347109Y74803D02*
X347085Y76304D01*
G01X347082Y75394D02*
X347092Y74803D01*
G01X345831Y81299D02*
X345822Y81890D01*
G01X345804D02*
X345829Y80389D01*
G01X351000Y81229D02*
X350987Y81890D01*
G01X350967D02*
X350998Y80301D01*
G01X349821Y74803D02*
X349790Y76392D01*
G01X349788Y75464D02*
X349801Y74803D01*
G01X347063Y81229D02*
X347050Y81890D01*
G01X347030D02*
X347061Y80301D01*
G01X345884Y74803D02*
X345853Y76392D01*
G01X345851Y75464D02*
X345864Y74803D01*
G01X351575Y66535D02*
X351050Y64961D01*
G01X351214Y66000D02*
X350919Y65095D01*
G01X351378Y66535D02*
X351247Y66133D01*
G01X343113Y74803D02*
X343126Y75464D01*
G01X343124Y76392D02*
X343093Y74803D01*
G01X341916Y80301D02*
X341947Y81890D01*
G01X341927D02*
X341914Y81229D01*
G01X339176Y74803D02*
X339189Y75464D01*
G01X339187Y76392D02*
X339156Y74803D01*
G01X337979Y80301D02*
X338010Y81890D01*
G01X337990D02*
X337977Y81229D01*
G01X335239Y74803D02*
X335252Y75464D01*
G01X335250Y76392D02*
X335219Y74803D01*
G01X334042Y80301D02*
X334073Y81890D01*
G01X334053D02*
X334040Y81229D01*
G01X343148Y80389D02*
X343172Y81890D01*
G01X343155D02*
X343145Y81299D01*
G01X341885Y74803D02*
X341894Y75394D01*
G01X341892Y76304D02*
X341867Y74803D01*
G01X339211Y80389D02*
X339235Y81890D01*
G01X339218D02*
X339208Y81299D01*
G01X337948Y74803D02*
X337957Y75394D01*
G01X337955Y76304D02*
X337930Y74803D01*
G01X335274Y80389D02*
X335298Y81890D01*
G01X335281D02*
X335271Y81299D01*
G01X334011Y74803D02*
X334020Y75394D01*
G01X334018Y76304D02*
X333993Y74803D01*
G01X343099Y85996D02*
X343094Y84209D01*
G01X343085Y84477D02*
X343089Y86264D01*
G01X341955Y72217D02*
X341950Y70430D01*
G01X341941Y70697D02*
X341946Y72484D01*
G01X339162Y68280D02*
X339157Y66493D01*
G01X339148Y66760D02*
X339153Y68547D01*
G01X338018Y89933D02*
X338013Y88146D01*
G01X338004Y88414D02*
X338009Y90201D01*
G01X335225Y85996D02*
X335220Y84209D01*
G01X335211Y84477D02*
X335215Y86264D01*
G01X334081Y72217D02*
X334076Y70430D01*
G01X334067Y70697D02*
X334072Y72484D01*
G01X344242Y65354D02*
Y65551D01*
G01X343750Y65354D02*
Y65551D01*
G01X343504Y65354D02*
Y65551D01*
G01X343258Y65354D02*
Y65551D01*
G01X343108Y69980D02*
Y68996D01*
G01Y87697D02*
Y86713D01*
G01X343012Y65551D02*
Y65354D01*
G01X342953Y73917D02*
Y72933D01*
G01Y83760D02*
Y82776D01*
G01X342766Y65354D02*
Y65551D01*
G01X342520Y65354D02*
Y65551D01*
G01X342274Y65354D02*
Y65551D01*
G01X342087Y73917D02*
Y72933D01*
G01Y82776D02*
Y83760D01*
G01X341931Y68996D02*
Y69980D01*
G01Y86713D02*
Y87697D01*
G01X341850Y98425D02*
Y92815D01*
G01X341535Y65354D02*
Y65551D01*
G01X341289Y65354D02*
Y65551D01*
G01X340059Y65354D02*
Y65551D01*
G01X339567Y65354D02*
Y65551D01*
G01X339321Y65354D02*
Y65551D01*
G01X339171Y68996D02*
Y69980D01*
G01Y86713D02*
Y87697D01*
G01X339075Y65354D02*
Y65551D01*
G01X339016Y66043D02*
Y65059D01*
G01Y91634D02*
Y90650D01*
G01X338583Y65354D02*
Y65551D01*
G01X338337Y65354D02*
Y65551D01*
G01X338150Y66043D02*
Y65059D01*
G01Y90650D02*
Y91634D01*
G01X338091Y65354D02*
Y65551D01*
G01X337994Y69980D02*
Y68996D01*
G01Y87697D02*
Y86713D01*
G01X337844Y65354D02*
Y65551D01*
G01X337598Y90945D02*
Y91142D01*
G01Y65354D02*
Y65551D01*
G01X337106Y65354D02*
Y65551D01*
G01X336860Y65354D02*
Y65551D01*
G01X336368Y65354D02*
Y65551D01*
G01X336122Y65354D02*
Y65551D01*
G01X335630Y90945D02*
Y91142D01*
G01X335384Y90945D02*
Y91142D01*
G01X335234Y69980D02*
Y68996D01*
G01Y87697D02*
Y86713D01*
G01X335079Y73917D02*
Y72933D01*
G01Y83760D02*
Y82776D01*
G01X334892Y90945D02*
Y91142D01*
G01X334213Y73917D02*
Y72933D01*
G01Y82776D02*
Y83760D01*
G01X334154Y65551D02*
Y65354D01*
G01Y91142D02*
Y90945D01*
G01X334057Y68996D02*
Y69980D01*
G01Y86713D02*
Y87697D01*
G01X333907Y91142D02*
Y90945D01*
G01X333415Y91142D02*
Y90945D01*
G01X333169Y65354D02*
Y65551D01*
G01X332923Y90945D02*
Y91142D01*
G01X332677D02*
Y90945D01*
G01X331693Y91142D02*
Y90945D01*
G01X343094Y72484D02*
X343099Y70697D01*
G01X343090Y70430D02*
X343085Y72217D01*
G01X341950Y86264D02*
X341955Y84477D01*
G01X341946Y84209D02*
X341941Y85996D01*
G01X339157Y90201D02*
X339162Y88414D01*
G01X339152Y88146D02*
X339148Y89933D01*
G01X338013Y68547D02*
X338018Y66760D01*
G01X338009Y66493D02*
X338004Y68280D01*
G01X335220Y72484D02*
X335225Y70697D01*
G01X335216Y70430D02*
X335211Y72217D01*
G01X334076Y86264D02*
X334081Y84477D01*
G01X334072Y84209D02*
X334067Y85996D01*
G01X331283Y90201D02*
X331288Y88414D01*
G01X331278Y88146D02*
X331274Y89933D01*
G01X343172Y74803D02*
X343148Y76304D01*
G01X343145Y75394D02*
X343155Y74803D01*
G01X341894Y81299D02*
X341885Y81890D01*
G01X341867D02*
X341892Y80389D01*
G01X339235Y74803D02*
X339211Y76304D01*
G01X339208Y75394D02*
X339218Y74803D01*
G01X337957Y81299D02*
X337948Y81890D01*
G01X337930D02*
X337955Y80389D01*
G01X335298Y74803D02*
X335274Y76304D01*
G01X335271Y75394D02*
X335281Y74803D01*
G01X334020Y81299D02*
X334011Y81890D01*
G01X333993D02*
X334018Y80389D01*
G01X331361Y74803D02*
X331337Y76304D01*
G01X331334Y75394D02*
X331344Y74803D01*
G01X343126Y81229D02*
X343113Y81890D01*
G01X343093D02*
X343124Y80301D01*
G01X341947Y74803D02*
X341916Y76392D01*
G01X341914Y75464D02*
X341927Y74803D01*
G01X339189Y81229D02*
X339176Y81890D01*
G01X339156D02*
X339187Y80301D01*
G01X338010Y74803D02*
X337979Y76392D01*
G01X337977Y75464D02*
X337990Y74803D01*
G01X335252Y81229D02*
X335239Y81890D01*
G01X335219D02*
X335250Y80301D01*
G01X334073Y74803D02*
X334042Y76392D01*
G01X334040Y75464D02*
X334053Y74803D01*
G01X331315Y81229D02*
X331302Y81890D01*
G01X331282D02*
X331313Y80301D01*
G01X331302Y74803D02*
X331315Y75464D01*
G01X331313Y76392D02*
X331282Y74803D01*
G01X330105Y80301D02*
X330136Y81890D01*
G01X330116D02*
X330103Y81229D01*
G01X327365Y74803D02*
X327378Y75464D01*
G01X327376Y76392D02*
X327345Y74803D01*
G01X326168Y80301D02*
X326199Y81890D01*
G01X326179D02*
X326166Y81229D01*
G01X323428Y74803D02*
X323441Y75464D01*
G01X323439Y76392D02*
X323408Y74803D01*
G01X322231Y80301D02*
X322262Y81890D01*
G01X322242D02*
X322229Y81229D01*
G01X319491Y74803D02*
X319504Y75464D01*
G01X319502Y76392D02*
X319471Y74803D01*
G01X331337Y80389D02*
X331361Y81890D01*
G01X331344D02*
X331334Y81299D01*
G01X330074Y74803D02*
X330083Y75394D01*
G01X330081Y76304D02*
X330056Y74803D01*
G01X327400Y80389D02*
X327424Y81890D01*
G01X327407D02*
X327397Y81299D01*
G01X326137Y74803D02*
X326146Y75394D01*
G01X326144Y76304D02*
X326119Y74803D01*
G01X323463Y80389D02*
X323487Y81890D01*
G01X323470D02*
X323460Y81299D01*
G01X322200Y74803D02*
X322209Y75394D01*
G01X322207Y76304D02*
X322182Y74803D01*
G01X319526Y80389D02*
X319550Y81890D01*
G01X319533D02*
X319523Y81299D01*
G01X331288Y68280D02*
X331283Y66493D01*
G01X331274Y66760D02*
X331279Y68547D01*
G01X330144Y89933D02*
X330139Y88146D01*
G01X330130Y88414D02*
X330135Y90201D01*
G01X327351Y85996D02*
X327346Y84209D01*
G01X327337Y84477D02*
X327341Y86264D01*
G01X326207Y72217D02*
X326202Y70430D01*
G01X326193Y70697D02*
X326198Y72484D01*
G01X323414Y68280D02*
X323409Y66493D01*
G01X323400Y66760D02*
X323405Y68547D01*
G01X322270Y89933D02*
X322265Y88146D01*
G01X322256Y88414D02*
X322261Y90201D01*
G01X319477Y85996D02*
X319472Y84209D01*
G01X319463Y84477D02*
X319467Y86264D01*
G01X331297Y68996D02*
Y69980D01*
G01Y86713D02*
Y87697D01*
G01X331142Y66043D02*
Y65059D01*
G01Y91634D02*
Y90650D01*
G01X330276Y66043D02*
Y65059D01*
G01Y90650D02*
Y91634D01*
G01X330120Y69980D02*
Y68996D01*
G01Y87697D02*
Y86713D01*
G01X329724Y91142D02*
Y90945D01*
G01X328740Y91142D02*
Y90945D01*
G01X328494D02*
Y91142D01*
G01X328002D02*
Y90945D01*
G01X327510Y91142D02*
Y90945D01*
G01X327360Y69980D02*
Y68996D01*
G01Y86713D02*
Y87697D01*
G01X327264Y91142D02*
Y90945D01*
G01X327205Y73917D02*
Y72933D01*
G01Y83760D02*
Y82776D01*
G01X326772Y65354D02*
Y65551D01*
G01X326575Y55512D02*
Y43701D01*
G01X326526Y90945D02*
Y91142D01*
G01X326339Y73917D02*
Y72933D01*
G01Y82776D02*
Y83760D01*
G01X326183Y68996D02*
Y69980D01*
G01Y87697D02*
Y86713D01*
G01X326033Y90945D02*
Y91142D01*
G01X325945Y98425D02*
Y92815D01*
G01X325787Y90945D02*
Y91142D01*
G01X325295Y65354D02*
Y65551D01*
G01X323819Y90945D02*
Y91142D01*
G01X323423Y68996D02*
Y69980D01*
G01Y86713D02*
Y87697D01*
G01X323327Y65551D02*
Y65354D01*
G01X323268Y66043D02*
Y65059D01*
G01Y91634D02*
Y90650D01*
G01X322402Y66043D02*
Y65059D01*
G01Y90650D02*
Y91634D01*
G01X322246Y69980D02*
Y68996D01*
G01Y87697D02*
Y86713D01*
G01X320945Y98425D02*
Y92815D01*
G01X319882Y90945D02*
Y91142D01*
G01X319486Y69980D02*
Y68996D01*
G01Y87697D02*
Y86713D01*
G01X319390Y65354D02*
Y65551D01*
G01X319331Y73917D02*
Y72933D01*
G01Y83760D02*
Y82776D01*
G01X318465Y73917D02*
Y72933D01*
G01Y82776D02*
Y83760D01*
G01X318406Y90945D02*
Y91142D01*
G01X330139Y68547D02*
X330144Y66760D01*
G01X330135Y66493D02*
X330130Y68280D01*
G01X327346Y72484D02*
X327351Y70697D01*
G01X327342Y70430D02*
X327337Y72217D01*
G01X326202Y86264D02*
X326207Y84477D01*
G01X326198Y84209D02*
X326193Y85996D01*
G01X323409Y90201D02*
X323414Y88414D01*
G01X323404Y88146D02*
X323400Y89933D01*
G01X322265Y68547D02*
X322270Y66760D01*
G01X322261Y66493D02*
X322256Y68280D01*
G01X319472Y72484D02*
X319477Y70697D01*
G01X319468Y70430D02*
X319463Y72217D01*
G01X318328Y86264D02*
X318333Y84477D01*
G01X318324Y84209D02*
X318319Y85996D01*
G01X330083Y81299D02*
X330074Y81890D01*
G01X330056D02*
X330081Y80389D01*
G01X327424Y74803D02*
X327400Y76304D01*
G01X327397Y75394D02*
X327407Y74803D01*
G01X326146Y81299D02*
X326137Y81890D01*
G01X326119D02*
X326144Y80389D01*
G01X323487Y74803D02*
X323463Y76304D01*
G01X323460Y75394D02*
X323470Y74803D01*
G01X322209Y81299D02*
X322200Y81890D01*
G01X322182D02*
X322207Y80389D01*
G01X319550Y74803D02*
X319526Y76304D01*
G01X319523Y75394D02*
X319533Y74803D01*
G01X318272Y81299D02*
X318263Y81890D01*
G01X318245D02*
X318270Y80389D01*
G01X330136Y74803D02*
X330105Y76392D01*
G01X330103Y75464D02*
X330116Y74803D01*
G01X327378Y81229D02*
X327365Y81890D01*
G01X327345D02*
X327376Y80301D01*
G01X326199Y74803D02*
X326168Y76392D01*
G01X326166Y75464D02*
X326179Y74803D01*
G01X323441Y81229D02*
X323428Y81890D01*
G01X323408D02*
X323439Y80301D01*
G01X322262Y74803D02*
X322231Y76392D01*
G01X322229Y75464D02*
X322242Y74803D01*
G01X319504Y81229D02*
X319491Y81890D01*
G01X319471D02*
X319502Y80301D01*
G01X318325Y74803D02*
X318294Y76392D01*
G01X318292Y75464D02*
X318305Y74803D01*
G01X318294Y80301D02*
X318325Y81890D01*
G01X318305D02*
X318292Y81229D01*
G01X315554Y74803D02*
X315567Y75464D01*
G01X315565Y76392D02*
X315534Y74803D01*
G01X314357Y80301D02*
X314388Y81890D01*
G01X314368D02*
X314355Y81229D01*
G01X311617Y74803D02*
X311630Y75464D01*
G01X311628Y76392D02*
X311597Y74803D01*
G01X310420Y80301D02*
X310451Y81890D01*
G01X310431D02*
X310418Y81229D01*
G01X318263Y74803D02*
X318272Y75394D01*
G01X318270Y76304D02*
X318245Y74803D01*
G01X315589Y80389D02*
X315613Y81890D01*
G01X315596D02*
X315586Y81299D01*
G01X314326Y74803D02*
X314335Y75394D01*
G01X314333Y76304D02*
X314308Y74803D01*
G01X311652Y80389D02*
X311676Y81890D01*
G01X311659D02*
X311649Y81299D01*
G01X310389Y74803D02*
X310398Y75394D01*
G01X310396Y76304D02*
X310371Y74803D01*
G01X318333Y72217D02*
X318328Y70430D01*
G01X318319Y70697D02*
X318324Y72484D01*
G01X315540Y68280D02*
X315535Y66493D01*
G01X315526Y66760D02*
X315531Y68547D01*
G01X314396Y89933D02*
X314391Y88146D01*
G01X314381Y88414D02*
X314387Y90201D01*
G01X311603Y85996D02*
X311598Y84209D01*
G01X311589Y84477D02*
X311593Y86264D01*
G01X310459Y72217D02*
X310454Y70430D01*
G01X310445Y70697D02*
X310450Y72484D01*
G01X318309Y68996D02*
Y69980D01*
G01Y86713D02*
Y87697D01*
G01X317913Y65354D02*
Y65551D01*
G01X315549Y69980D02*
Y68996D01*
G01Y86713D02*
Y87697D01*
G01X315394Y66043D02*
Y65059D01*
G01Y91634D02*
Y90650D01*
G01X314528Y66043D02*
Y65059D01*
G01Y90650D02*
Y91634D01*
G01X314469Y91142D02*
Y90945D01*
G01X314372Y68996D02*
Y69980D01*
G01Y87697D02*
Y86713D01*
G01X313976Y65354D02*
Y65551D01*
G01X312500Y90945D02*
Y91142D01*
G01X312008Y65354D02*
Y65551D01*
G01X311762Y65354D02*
Y65551D01*
G01X311612Y69980D02*
Y68996D01*
G01Y87697D02*
Y86713D01*
G01X311457Y73917D02*
Y72933D01*
G01Y83760D02*
Y82776D01*
G01X311270Y65354D02*
Y65551D01*
G01X311024Y90945D02*
Y91142D01*
G01X310591Y73917D02*
Y72933D01*
G01Y82776D02*
Y83760D01*
G01X310531Y65551D02*
Y65354D01*
G01X310435Y68996D02*
Y69980D01*
G01Y86713D02*
Y87697D01*
G01X310285Y65551D02*
Y65354D01*
G01X309793Y65551D02*
Y65354D01*
G01X309301D02*
Y65551D01*
G01X309055D02*
Y65354D01*
G01X308661Y74803D02*
Y81890D01*
G01X308268Y80719D02*
Y75974D01*
G01X308071Y65551D02*
Y65354D01*
G01X308065Y81890D02*
Y83465D01*
G01Y73228D02*
Y74803D01*
G01X306890Y43701D02*
Y55512D01*
G01X306102Y65551D02*
Y65354D01*
G01X315535Y90201D02*
X315540Y88414D01*
G01X315530Y88146D02*
X315526Y89933D01*
G01X314391Y68547D02*
X314396Y66760D01*
G01X314387Y66493D02*
X314382Y68280D01*
G01X311598Y72484D02*
X311603Y70697D01*
G01X311594Y70430D02*
X311589Y72217D01*
G01X310454Y86264D02*
X310459Y84477D01*
G01X310450Y84209D02*
X310444Y85996D01*
G01X315613Y74803D02*
X315589Y76304D01*
G01X315586Y75394D02*
X315596Y74803D01*
G01X314335Y81299D02*
X314326Y81890D01*
G01X314308D02*
X314333Y80389D01*
G01X311676Y74803D02*
X311652Y76304D01*
G01X311649Y75394D02*
X311659Y74803D01*
G01X310398Y81299D02*
X310389Y81890D01*
G01X310371D02*
X310396Y80389D01*
G01X315567Y81229D02*
X315554Y81890D01*
G01X315534D02*
X315565Y80301D01*
G01X314388Y74803D02*
X314357Y76392D01*
G01X314355Y75464D02*
X314368Y74803D01*
G01X311630Y81229D02*
X311617Y81890D01*
G01X311597D02*
X311628Y80301D01*
G01X310451Y74803D02*
X310420Y76392D01*
G01X310418Y75464D02*
X310431Y74803D01*
G01X350000Y65195D02*
X349803Y64961D01*
G01X350000Y65463D02*
X349803Y65229D01*
G01X299806Y74803D02*
X299819Y75464D01*
G01X299817Y76392D02*
X299786Y74803D01*
G01X298609Y80301D02*
X298640Y81890D01*
G01X298620D02*
X298607Y81229D01*
G01X295869Y74803D02*
X295881Y75464D01*
G01X295880Y76392D02*
X295849Y74803D01*
G01X294672Y80301D02*
X294703Y81890D01*
G01X294683D02*
X294670Y81229D01*
G01X299841Y80389D02*
X299865Y81890D01*
G01X299848D02*
X299838Y81299D01*
G01X298578Y74803D02*
X298587Y75394D01*
G01X298585Y76304D02*
X298560Y74803D01*
G01X295904Y80389D02*
X295928Y81890D01*
G01X295911D02*
X295901Y81299D01*
G01X294641Y74803D02*
X294650Y75394D01*
G01X294648Y76304D02*
X294623Y74803D01*
G01X299792Y68280D02*
X299787Y66493D01*
G01X299778Y66760D02*
X299783Y68547D01*
G01X298648Y89933D02*
X298643Y88146D01*
G01X298633Y88414D02*
X298639Y90201D01*
G01X295855Y85996D02*
X295850Y84209D01*
G01X295841Y84477D02*
X295845Y86264D01*
G01X294711Y72217D02*
X294706Y70430D01*
G01X294697Y70697D02*
X294702Y72484D01*
G01X305118Y65551D02*
Y65354D01*
G01X305039Y98425D02*
Y92815D01*
G01X304872Y65354D02*
Y65551D01*
G01X304626Y90945D02*
Y91142D01*
G01X304380Y65551D02*
Y65354D01*
G01X303888Y65551D02*
Y65354D01*
G01X303642Y65551D02*
Y65354D01*
G01Y91142D02*
Y90945D01*
G01X302904Y65354D02*
Y65551D01*
G01X302411Y65354D02*
Y65551D01*
G01X302172Y74803D02*
Y73228D01*
G01Y83465D02*
Y81890D01*
G01X302165Y65354D02*
Y65551D01*
G01X301969Y81962D02*
Y74731D01*
G01X301673Y90945D02*
Y91142D01*
G01X301575Y81890D02*
Y74803D01*
G01X301427Y90945D02*
Y91142D01*
G01X300935Y90945D02*
Y91142D01*
G01X300689Y90945D02*
Y91142D01*
G01X300591Y55512D02*
Y43701D01*
G01X300197Y90945D02*
Y91142D01*
G01Y65354D02*
Y65551D01*
G01X300039Y98425D02*
Y92815D01*
G01X299951Y90945D02*
Y91142D01*
G01X299801Y68996D02*
Y69980D01*
G01Y86713D02*
Y87697D01*
G01X299705Y90945D02*
Y91142D01*
G01X299646Y66043D02*
Y65059D01*
G01Y91634D02*
Y90650D01*
G01X299459Y90945D02*
Y91142D01*
G01X299213Y90945D02*
Y91142D01*
G01X298780Y66043D02*
Y65059D01*
G01Y90650D02*
Y91634D01*
G01X298720Y90945D02*
Y91142D01*
G01X298624Y69980D02*
Y68996D01*
G01Y87697D02*
Y86713D01*
G01X298474Y90945D02*
Y91142D01*
G01X298228Y90945D02*
Y91142D01*
G01X297736Y90945D02*
Y91142D01*
G01X296506Y90945D02*
Y91142D01*
G01X296260Y90945D02*
Y91142D01*
G01X295864Y69980D02*
Y68996D01*
G01Y87697D02*
Y86713D01*
G01X295709Y73917D02*
Y72933D01*
G01Y83760D02*
Y82776D01*
G01X295522Y90945D02*
Y91142D01*
G01X295276Y90945D02*
Y91142D01*
G01X295030Y90945D02*
Y91142D01*
G01X294843Y73917D02*
Y72933D01*
G01Y82776D02*
Y83760D01*
G01X294783Y91142D02*
Y90945D01*
G01X294687Y68996D02*
Y69980D01*
G01Y86713D02*
Y87697D01*
G01X294537Y90945D02*
Y91142D01*
G01X294291Y90945D02*
Y91142D01*
G01X294045Y90945D02*
Y91142D01*
G01X293553Y90945D02*
Y91142D01*
G01X293307Y90945D02*
Y91142D01*
G01X293061Y90945D02*
Y91142D01*
G01X292815Y65354D02*
Y65551D01*
G01X292569Y90945D02*
Y91142D01*
G01X299787Y90201D02*
X299792Y88414D01*
G01X299782Y88146D02*
X299778Y89933D01*
G01X298643Y68547D02*
X298648Y66760D01*
G01X298639Y66493D02*
X298634Y68280D01*
G01X295850Y72484D02*
X295855Y70697D01*
G01X295846Y70430D02*
X295841Y72217D01*
G01X294706Y86264D02*
X294711Y84477D01*
G01X294702Y84209D02*
X294696Y85996D01*
G01X299865Y74803D02*
X299841Y76304D01*
G01X299838Y75394D02*
X299848Y74803D01*
G01X298587Y81299D02*
X298578Y81890D01*
G01X298560D02*
X298585Y80389D01*
G01X295928Y74803D02*
X295904Y76304D01*
G01X295901Y75394D02*
X295911Y74803D01*
G01X294650Y81299D02*
X294641Y81890D01*
G01X294623D02*
X294648Y80389D01*
G01X299819Y81229D02*
X299806Y81890D01*
G01X299786D02*
X299817Y80301D01*
G01X298640Y74803D02*
X298609Y76392D01*
G01X298607Y75464D02*
X298620Y74803D01*
G01X295881Y81229D02*
X295869Y81890D01*
G01X295849D02*
X295880Y80301D01*
G01X294703Y74803D02*
X294672Y76392D01*
G01X294670Y75464D02*
X294683Y74803D01*
G01X291944Y81229D02*
X291932Y81890D01*
G01Y74803D02*
X291944Y75464D01*
G01X291943Y76392D02*
X291912Y74803D01*
G01X291967Y80389D02*
X291991Y81890D01*
G01X291974D02*
X291964Y81299D01*
G01X291918Y68280D02*
X291913Y66493D01*
G01X291904Y66760D02*
X291909Y68547D01*
G01X291927Y68996D02*
Y69980D01*
G01Y86713D02*
Y87697D01*
G01X291772Y66043D02*
Y65059D01*
G01Y91634D02*
Y90650D01*
G01X291913Y90201D02*
X291918Y88414D01*
G01X291908Y88146D02*
X291904Y89933D01*
G01X291991Y74803D02*
X291967Y76304D01*
G01X291964Y75394D02*
X291974Y74803D01*
G01X291912Y81890D02*
X291943Y80301D01*
G01X320945Y98425D02*
X305039D01*
G01X341850D02*
X325945D01*
G01X362205D02*
X346850D01*
G01X299768Y91634D02*
X298657D01*
G01X315516D02*
X314406D01*
G01X323390D02*
X322280D01*
G01X331264D02*
X330154D01*
G01X339138D02*
X338028D01*
G01X347012D02*
X345902D01*
G01X337598Y90945D02*
X346457D01*
G01X301673D02*
X292569D01*
G01X312500D02*
X303642D01*
G01X323819D02*
X314469D01*
G01X335630D02*
X325787D01*
G01X299768Y90650D02*
X298657D01*
G01X315516D02*
X314406D01*
G01X323390D02*
X322280D01*
G01X331264D02*
X330154D01*
G01X339138D02*
X338028D01*
G01X347012D02*
X345902D01*
G01X345883Y90201D02*
X347031D01*
G01X338009D02*
X339157D01*
G01X330135D02*
X331283D01*
G01X322261D02*
X323409D01*
G01X314387D02*
X315535D01*
G01X298639D02*
X299787D01*
G01X299778Y89933D02*
X298648D01*
G01X315526D02*
X314396D01*
G01X323400D02*
X322270D01*
G01X331274D02*
X330144D01*
G01X339148D02*
X338018D01*
G01X347022D02*
X345892D01*
G01X299792Y88414D02*
X298633D01*
G01X315540D02*
X314381D01*
G01X323414D02*
X322256D01*
G01X331288D02*
X330130D01*
G01X339162D02*
X338004D01*
G01X347036D02*
X345878D01*
G01X345887Y88146D02*
X347026D01*
G01X338013D02*
X339152D01*
G01X330139D02*
X331278D01*
G01X322265D02*
X323404D01*
G01X314391D02*
X315530D01*
G01X298643D02*
X299782D01*
G01X295864Y87697D02*
X294687D01*
G01X299801D02*
X298624D01*
G01X311612D02*
X310435D01*
G01X315549D02*
X314372D01*
G01X319486D02*
X318309D01*
G01X323423D02*
X322246D01*
G01X327360D02*
X326183D01*
G01X331297D02*
X330120D01*
G01X335234D02*
X334057D01*
G01X339171D02*
X337994D01*
G01X343108D02*
X341931D01*
G01X347045D02*
X345869D01*
G01X350982D02*
X349806D01*
G01X295864Y86713D02*
X294687D01*
G01X299801D02*
X298624D01*
G01X311612D02*
X310435D01*
G01X315549D02*
X314372D01*
G01X319486D02*
X318309D01*
G01X323423D02*
X322246D01*
G01X327360D02*
X326183D01*
G01X331297D02*
X330120D01*
G01X335234D02*
X334057D01*
G01X339171D02*
X337994D01*
G01X343108D02*
X341931D01*
G01X347045D02*
X345869D01*
G01X350982D02*
X349806D01*
G01X295845Y86264D02*
X294706D01*
G01X311593D02*
X310454D01*
G01X319467D02*
X318328D01*
G01X327341D02*
X326202D01*
G01X335215D02*
X334076D01*
G01X343089D02*
X341950D01*
G01X350963D02*
X349824D01*
G01X349815Y85996D02*
X350973D01*
G01X341941D02*
X343099D01*
G01X334067D02*
X335225D01*
G01X326193D02*
X327351D01*
G01X318319D02*
X319477D01*
G01X310444D02*
X311603D01*
G01X294696D02*
X295855D01*
G01X349829Y84477D02*
X350959D01*
G01X341955D02*
X343085D01*
G01X334081D02*
X335211D01*
G01X326207D02*
X327337D01*
G01X318333D02*
X319463D01*
G01X310459D02*
X311589D01*
G01X294711D02*
X295841D01*
G01X295850Y84209D02*
X294702D01*
G01X311598D02*
X310450D01*
G01X319472D02*
X318324D01*
G01X327346D02*
X326198D01*
G01X335220D02*
X334072D01*
G01X343094D02*
X341946D01*
G01X350968D02*
X349820D01*
G01X295831Y83760D02*
X294720D01*
G01X311579D02*
X310469D01*
G01X319453D02*
X318343D01*
G01X327327D02*
X326217D01*
G01X335201D02*
X334091D01*
G01X343075D02*
X341965D01*
G01X350949D02*
X349839D01*
G01X356102Y83465D02*
X308065D01*
G01X295831Y82776D02*
X294720D01*
G01X311579D02*
X310469D01*
G01X319453D02*
X318343D01*
G01X327327D02*
X326217D01*
G01X335201D02*
X334091D01*
G01X343075D02*
X341965D01*
G01X350949D02*
X349839D01*
G01X295901Y81299D02*
X294650D01*
G01X299838D02*
X298587D01*
G01X311649D02*
X310398D01*
G01X315586D02*
X314335D01*
G01X319523D02*
X318272D01*
G01X323460D02*
X322209D01*
G01X327397D02*
X326146D01*
G01X331334D02*
X330083D01*
G01X335271D02*
X334020D01*
G01X339208D02*
X337957D01*
G01X343145D02*
X341894D01*
G01X347082D02*
X345831D01*
G01X351019D02*
X349769D01*
G01X349788Y81229D02*
X351000D01*
G01X345851D02*
X347063D01*
G01X341914D02*
X343126D01*
G01X337977D02*
X339189D01*
G01X334040D02*
X335252D01*
G01X330103D02*
X331315D01*
G01X326166D02*
X327378D01*
G01X322229D02*
X323441D01*
G01X318292D02*
X319504D01*
G01X314355D02*
X315567D01*
G01X310418D02*
X311630D01*
G01X298607D02*
X299819D01*
G01X294670D02*
X295881D01*
G01X295891Y81004D02*
X294661D01*
G01X299828D02*
X298598D01*
G01X311639D02*
X310409D01*
G01X315576D02*
X314346D01*
G01X319513D02*
X318283D01*
G01X323450D02*
X322220D01*
G01X327387D02*
X326157D01*
G01X331324D02*
X330094D01*
G01X335261D02*
X334031D01*
G01X339198D02*
X337968D01*
G01X343135D02*
X341905D01*
G01X347072D02*
X345842D01*
G01X351009D02*
X349779D01*
G01X349766Y80389D02*
X351022D01*
G01X345829D02*
X347085D01*
G01X341892D02*
X343148D01*
G01X337955D02*
X339211D01*
G01X334018D02*
X335274D01*
G01X330081D02*
X331337D01*
G01X326144D02*
X327400D01*
G01X322207D02*
X323463D01*
G01X318270D02*
X319526D01*
G01X314333D02*
X315589D01*
G01X310396D02*
X311652D01*
G01X298585D02*
X299841D01*
G01X294648D02*
X295904D01*
G01X295880Y80301D02*
X294672D01*
G01X299817D02*
X298609D01*
G01X311628D02*
X310420D01*
G01X315565D02*
X314357D01*
G01X319502D02*
X318294D01*
G01X323439D02*
X322231D01*
G01X327376D02*
X326168D01*
G01X331313D02*
X330105D01*
G01X335250D02*
X334042D01*
G01X339187D02*
X337979D01*
G01X343124D02*
X341916D01*
G01X347061D02*
X345853D01*
G01X350998D02*
X349790D01*
G01X295891Y80019D02*
X294661D01*
G01X299828D02*
X298598D01*
G01X311639D02*
X310409D01*
G01X315576D02*
X314346D01*
G01X319513D02*
X318283D01*
G01X323450D02*
X322220D01*
G01X327387D02*
X326157D01*
G01X331324D02*
X330094D01*
G01X335261D02*
X334031D01*
G01X339198D02*
X337968D01*
G01X343135D02*
X341905D01*
G01X347072D02*
X345842D01*
G01X351009D02*
X349779D01*
G01Y76674D02*
X351009D01*
G01X345842D02*
X347072D01*
G01X341905D02*
X343135D01*
G01X337968D02*
X339198D01*
G01X334031D02*
X335261D01*
G01X330094D02*
X331324D01*
G01X326157D02*
X327387D01*
G01X322220D02*
X323450D01*
G01X318283D02*
X319513D01*
G01X314346D02*
X315576D01*
G01X310409D02*
X311639D01*
G01X298598D02*
X299828D01*
G01X294661D02*
X295891D01*
G01X349790Y76392D02*
X350998D01*
G01X345853D02*
X347061D01*
G01X341916D02*
X343124D01*
G01X337979D02*
X339187D01*
G01X334042D02*
X335250D01*
G01X330105D02*
X331313D01*
G01X326168D02*
X327376D01*
G01X322231D02*
X323439D01*
G01X318294D02*
X319502D01*
G01X314357D02*
X315565D01*
G01X310420D02*
X311628D01*
G01X298609D02*
X299817D01*
G01X294672D02*
X295880D01*
G01X295904Y76304D02*
X294648D01*
G01X299841D02*
X298585D01*
G01X311652D02*
X310396D01*
G01X315589D02*
X314333D01*
G01X319526D02*
X318270D01*
G01X323463D02*
X322207D01*
G01X327400D02*
X326144D01*
G01X331337D02*
X330081D01*
G01X335274D02*
X334018D01*
G01X339211D02*
X337955D01*
G01X343148D02*
X341892D01*
G01X347085D02*
X345829D01*
G01X351022D02*
X349766D01*
G01X349779Y75690D02*
X351009D01*
G01X345842D02*
X347072D01*
G01X341905D02*
X343135D01*
G01X337968D02*
X339198D01*
G01X334031D02*
X335261D01*
G01X330094D02*
X331324D01*
G01X326157D02*
X327387D01*
G01X322220D02*
X323450D01*
G01X318283D02*
X319513D01*
G01X314346D02*
X315576D01*
G01X310409D02*
X311639D01*
G01X298598D02*
X299828D01*
G01X294661D02*
X295891D01*
G01X295881Y75464D02*
X294670D01*
G01X299819D02*
X298607D01*
G01X311630D02*
X310418D01*
G01X315567D02*
X314355D01*
G01X319504D02*
X318292D01*
G01X323441D02*
X322229D01*
G01X327378D02*
X326166D01*
G01X331315D02*
X330103D01*
G01X335252D02*
X334040D01*
G01X339189D02*
X337977D01*
G01X343126D02*
X341914D01*
G01X347063D02*
X345851D01*
G01X351000D02*
X349788D01*
G01X349769Y75394D02*
X351019D01*
G01X345831D02*
X347082D01*
G01X341894D02*
X343145D01*
G01X337957D02*
X339208D01*
G01X334020D02*
X335271D01*
G01X330083D02*
X331334D01*
G01X326146D02*
X327397D01*
G01X322209D02*
X323460D01*
G01X318272D02*
X319523D01*
G01X314335D02*
X315586D01*
G01X310398D02*
X311649D01*
G01X298587D02*
X299838D01*
G01X294650D02*
X295901D01*
G01X349839Y73917D02*
X350949D01*
G01X341965D02*
X343075D01*
G01X334091D02*
X335201D01*
G01X326217D02*
X327327D01*
G01X318343D02*
X319453D01*
G01X310469D02*
X311579D01*
G01X294720D02*
X295831D01*
G01X308065Y73228D02*
X356102D01*
G01X349839Y72933D02*
X350949D01*
G01X341965D02*
X343075D01*
G01X334091D02*
X335201D01*
G01X326217D02*
X327327D01*
G01X318343D02*
X319453D01*
G01X310469D02*
X311579D01*
G01X294720D02*
X295831D01*
G01X349820Y72484D02*
X350968D01*
G01X341946D02*
X343094D01*
G01X334072D02*
X335220D01*
G01X326198D02*
X327346D01*
G01X318324D02*
X319472D01*
G01X310450D02*
X311598D01*
G01X294702D02*
X295850D01*
G01X295841Y72217D02*
X294711D01*
G01X311589D02*
X310459D01*
G01X319463D02*
X318333D01*
G01X327337D02*
X326207D01*
G01X335211D02*
X334081D01*
G01X343085D02*
X341955D01*
G01X350959D02*
X349829D01*
G01X295855Y70697D02*
X294697D01*
G01X311603D02*
X310445D01*
G01X319477D02*
X318319D01*
G01X327351D02*
X326193D01*
G01X335225D02*
X334067D01*
G01X343099D02*
X341941D01*
G01X350973D02*
X349815D01*
G01X349824Y70430D02*
X350964D01*
G01X341950D02*
X343090D01*
G01X334076D02*
X335216D01*
G01X326202D02*
X327342D01*
G01X318328D02*
X319468D01*
G01X310454D02*
X311594D01*
G01X294706D02*
X295846D01*
G01X349806Y69980D02*
X350982D01*
G01X345869D02*
X347045D01*
G01X341931D02*
X343108D01*
G01X337994D02*
X339171D01*
G01X334057D02*
X335234D01*
G01X330120D02*
X331297D01*
G01X326183D02*
X327360D01*
G01X322246D02*
X323423D01*
G01X318309D02*
X319486D01*
G01X314372D02*
X315549D01*
G01X310435D02*
X311612D01*
G01X298624D02*
X299801D01*
G01X294687D02*
X295864D01*
G01Y68996D02*
X294687D01*
G01X299801D02*
X298624D01*
G01X311612D02*
X310435D01*
G01X315549D02*
X314372D01*
G01X319486D02*
X318309D01*
G01X323423D02*
X322246D01*
G01X327360D02*
X326183D01*
G01X331297D02*
X330120D01*
G01X335234D02*
X334057D01*
G01X339171D02*
X337994D01*
G01X343108D02*
X341931D01*
G01X347045D02*
X345869D01*
G01X350982D02*
X349806D01*
G01X299783Y68547D02*
X298643D01*
G01X315531D02*
X314391D01*
G01X323405D02*
X322265D01*
G01X331279D02*
X330139D01*
G01X339153D02*
X338013D01*
G01X347027D02*
X345887D01*
G01X345878Y68280D02*
X347036D01*
G01X338004D02*
X339162D01*
G01X330130D02*
X331288D01*
G01X322256D02*
X323414D01*
G01X314382D02*
X315540D01*
G01X298634D02*
X299792D01*
G01X345892Y66760D02*
X347022D01*
G01X338018D02*
X339148D01*
G01X330144D02*
X331274D01*
G01X322270D02*
X323400D01*
G01X314396D02*
X315526D01*
G01X298648D02*
X299778D01*
G01X351378Y66535D02*
X351575D01*
G01X350263D02*
X350459D01*
G01X349606D02*
X349803D01*
G01X299787Y66493D02*
X298639D01*
G01X315535D02*
X314387D01*
G01X323409D02*
X322261D01*
G01X331283D02*
X330135D01*
G01X339157D02*
X338009D01*
G01X347031D02*
X345883D01*
G01X350591Y66133D02*
X351247D01*
G01X299768Y66043D02*
X298657D01*
G01X315516D02*
X314406D01*
G01X323390D02*
X322280D01*
G01X331264D02*
X330154D01*
G01X339138D02*
X338028D01*
G01X347012D02*
X345902D01*
G01X350624Y66000D02*
X351214D01*
G01X336122Y65354D02*
X345226D01*
G01X313976D02*
X323327D01*
G01X312008D02*
X302165D01*
G01X334154D02*
X325295D01*
G01X345902Y65059D02*
X347012D01*
G01X338028D02*
X339138D01*
G01X330154D02*
X331264D01*
G01X322280D02*
X323390D01*
G01X314406D02*
X315516D01*
G01X298657D02*
X299768D01*
G01X349803Y64961D02*
X349606D01*
G01X351050D02*
X350787D01*
G01X310827Y59449D02*
X322638D01*
G01X315551Y114567D02*
G03Y106693I0J-3937D01*
G01X352953Y219292D02*
X350984Y221260D01*
G01X322638Y274804D02*
G03X326575Y278741I0J3937D01*
G01X306890D02*
G03X310827Y274804I3937J0D01*
G01X296654D02*
G03X300591Y278741I0J3937D01*
G01X326575Y290552D02*
Y278741D01*
G01X306890D02*
Y290552D01*
G01X300591D02*
Y278741D01*
G01X322638Y274804D02*
X310827D01*
G01X308858Y264370D02*
G03X301378I-3740J0D01*
G01X350984Y235040D02*
X352953Y237008D01*
G01X308858D02*
Y264370D01*
G01X299409Y235040D02*
X301378Y237008D01*
G01D02*
Y264370D01*
G01X308858Y237008D02*
X310827Y235040D01*
G01X350984D02*
X310827D01*
G01Y294489D02*
G03X306890Y290552I0J-3937D01*
G01X326575D02*
G03X322638Y294489I-3937J0D01*
G01X300591Y290552D02*
G03X296654Y294489I-3937J0D01*
G01X310827D02*
X322638D01*
G01X315551Y349607D02*
G03Y341733I0J-3937D01*
G01X352953Y454331D02*
X350984Y456300D01*
G01X322638Y509843D02*
G03X326575Y513780I0J3937D01*
G01X306890D02*
G03X310827Y509843I3937J0D01*
G01Y529528D02*
G03X306890Y525591I0J-3937D01*
G01X326575D02*
G03X322638Y529528I-3937J0D01*
G01X300591Y525591D02*
G03X296654Y529528I-3937J0D01*
G01Y509843D02*
G03X300591Y513780I0J3937D01*
G01X326575Y525591D02*
Y513780D01*
G01X306890D02*
Y525591D01*
G01X300591D02*
Y513780D01*
G01X310827Y529528D02*
X322638D01*
G01Y509843D02*
X310827D01*
G01X308858Y499410D02*
G03X301378I-3740J0D01*
G01X350984Y470079D02*
X352953Y472048D01*
G01X308858D02*
Y499410D01*
G01X299409Y470079D02*
X301378Y472048D01*
G01D02*
Y499410D01*
G01X308858Y472048D02*
X310827Y470079D01*
G01X350984D02*
X310827D01*
G01X315551Y584646D02*
G03Y576772I0J-3937D01*
G01X352953Y689371D02*
X350984Y691339D01*
G01X359173Y-426126D02*
Y-443449D01*
G01X381890Y37795D02*
G03X385827Y33858I3937J0D01*
G01X402953Y29921D02*
G03X399016Y33858I-3937J0D01*
G01X385827D02*
X399016D01*
G01X681299Y0D02*
X404921D01*
G01X402953Y1969D02*
X404921Y0D01*
G01X402953Y1969D02*
Y29921D01*
G01X381890Y102756D02*
Y37795D01*
G01X392661Y38708D02*
G03Y42708I0J2000D01*
G01D02*
G03Y38708I0J-2000D01*
G01X398961Y36808D02*
X386361D01*
G01X398961Y44608D02*
Y36808D01*
G01X386361D02*
Y44608D01*
G01X400061Y35708D02*
X385261D01*
G01X400061Y45708D02*
Y35708D01*
G01X385261D02*
Y45708D01*
G01X352953Y1969D02*
Y59941D01*
G01D02*
Y33858D01*
G01X385827Y106693D02*
G03X381890Y102756I0J-3937D01*
G01X386361Y44608D02*
X398961D01*
G01X385261Y45708D02*
X400061D01*
G01X374016Y98524D02*
G03X381890I3937J0D01*
G01Y67815D02*
G03X374016I-3937J0D01*
G01X354528Y81890D02*
X356102Y83465D01*
G01X354528Y74803D02*
X356102Y73228D01*
G01X374016Y102756D02*
G03X370079Y106693I-3937J0D01*
G01Y63878D02*
G03X374016Y67815I0J3937D01*
G01X356890Y63878D02*
G03X352953Y59941I0J-3937D01*
G01X374016Y102756D02*
Y67815D01*
G01X362205Y98425D02*
Y63878D01*
G01X358661Y67028D02*
Y71358D01*
G01Y89665D02*
Y85335D01*
G01X356102Y73228D02*
Y83465D01*
G01X354724Y85335D02*
Y87697D01*
G01Y71358D02*
Y68996D01*
G01X354528Y81890D02*
Y74803D01*
G01X354331Y67815D02*
Y63878D01*
G01Y92835D02*
Y88878D01*
G01X353858Y71358D02*
Y67028D01*
G01Y89665D02*
Y85335D01*
G01X362205Y92835D02*
X354331D01*
G01X358661Y89665D02*
X353858D01*
G01X354331Y88878D02*
X362205D01*
G01X358661Y87697D02*
X354724D01*
G01X358661Y85335D02*
X353858D01*
G01Y71358D02*
X358661D01*
G01X354724Y68996D02*
X358661D01*
G01X362205Y67815D02*
X354331D01*
G01X358661Y67028D02*
X353858D01*
G01X370079Y63878D02*
X356890D01*
G01X381890Y118504D02*
G03X385827Y114567I3937J0D01*
G01Y157382D02*
G03X381890Y153445I0J-3937D01*
G01X399016Y157382D02*
G03X402953Y161319I0J3937D01*
G01X381890Y118504D02*
Y153445D01*
G01X402953Y219292D02*
Y161319D01*
G01D02*
Y187402D01*
G01X525591Y114567D02*
X385827D01*
G01Y157382D02*
X399016D01*
G01X370079Y114567D02*
G03X374016Y118504I0J3937D01*
G01D02*
Y183465D01*
G01X385827Y106693D02*
X525591D01*
G01X374016Y153445D02*
G03X381890I3937J0D01*
G01Y122737D02*
G03X374016I-3937J0D01*
G01X404921Y221260D02*
X402953Y219292D01*
G01X404921Y221260D02*
X445079D01*
G01X374016Y183465D02*
G03X370079Y187402I-3937J0D01*
G01X352953Y191339D02*
G03X356890Y187402I3937J0D01*
G01X370079D02*
X356890D01*
G01X352953Y219292D02*
Y191339D01*
G01X363245Y182552D02*
G03Y178552I0J-2000D01*
G01D02*
G03Y182552I0J2000D01*
G01X356945Y184452D02*
X369545D01*
G01X356945Y176652D02*
Y184452D01*
G01X369545Y176652D02*
X356945D01*
G01X369545Y184452D02*
Y176652D01*
G01X355845Y185552D02*
X370645D01*
G01X355845Y175552D02*
Y185552D01*
G01X370645Y175552D02*
X355845D01*
G01X370645Y185552D02*
Y175552D01*
G01X352953Y237008D02*
Y294981D01*
G01D02*
Y268898D01*
G01X381890Y272835D02*
G03X385827Y268898I3937J0D01*
G01X402953Y264961D02*
G03X399016Y268898I-3937J0D01*
G01X385827D02*
X399016D01*
G01X681299Y235040D02*
X404921D01*
G01X402953Y237008D02*
X404921Y235040D01*
G01X402953Y237008D02*
Y264961D01*
G01X381890Y337796D02*
Y272835D01*
G01X392660Y273748D02*
G03Y277748I0J2000D01*
G01D02*
G03Y273748I0J-2000D01*
G01X398960Y271848D02*
X386360D01*
G01X398960Y279648D02*
Y271848D01*
G01X386360Y279648D02*
X398960D01*
G01X386360Y271848D02*
Y279648D01*
G01X400060Y270748D02*
X385260D01*
G01X400060Y280748D02*
Y270748D01*
G01X385260Y280748D02*
X400060D01*
G01X385260Y270748D02*
Y280748D01*
G01X374016Y337796D02*
G03X370079Y341733I-3937J0D01*
G01Y298918D02*
G03X374016Y302855I0J3937D01*
G01X356890Y298918D02*
G03X352953Y294981I0J-3937D01*
G01X374016Y337796D02*
Y302855D01*
G01X370079Y298918D02*
X356890D01*
G01X385827Y341733D02*
G03X381890Y337796I0J-3937D01*
G01X385827Y341733D02*
X525591D01*
G01X374016Y333563D02*
G03X381890I3937J0D01*
G01Y302855D02*
G03X374016I-3937J0D01*
G01X370079Y349607D02*
G03X374016Y353544I0J3937D01*
G01D02*
Y418504D01*
G01X381890Y353544D02*
G03X385827Y349607I3937J0D01*
G01Y392422D02*
G03X381890Y388485I0J-3937D01*
G01X399016Y392422D02*
G03X402953Y396359I0J3937D01*
G01X381890Y353544D02*
Y388485D01*
G01X402953Y454331D02*
Y396359D01*
G01D02*
Y422441D01*
G01X525591Y349607D02*
X385827D01*
G01Y392422D02*
X399016D01*
G01X374016Y388485D02*
G03X381890I3937J0D01*
G01Y357776D02*
G03X374016I-3937J0D01*
G01Y418504D02*
G03X370079Y422441I-3937J0D01*
G01X352953Y426378D02*
G03X356890Y422441I3937J0D01*
G01X370079D02*
X356890D01*
G01X352953Y454331D02*
Y426378D01*
G01X404921Y456300D02*
X402953Y454331D01*
G01X404921Y456300D02*
X445079D01*
G01X363245Y417591D02*
G03Y413591I0J-2000D01*
G01D02*
G03Y417591I0J2000D01*
G01X356945Y419491D02*
X369545D01*
G01X356945Y411691D02*
Y419491D01*
G01X369545Y411691D02*
X356945D01*
G01X369545Y419491D02*
Y411691D01*
G01X355845Y420591D02*
X370645D01*
G01X355845Y410591D02*
Y420591D01*
G01X370645Y410591D02*
X355845D01*
G01X370645Y420591D02*
Y410591D01*
G01X352953Y472048D02*
Y530020D01*
G01D02*
Y503937D01*
G01X381890Y507874D02*
G03X385827Y503937I3937J0D01*
G01X402953Y500000D02*
G03X399016Y503937I-3937J0D01*
G01X385827D02*
X399016D01*
G01X681299Y470079D02*
X404921D01*
G01X402953Y472048D02*
X404921Y470079D01*
G01X402953Y472048D02*
Y500000D01*
G01X381890Y572835D02*
Y507874D01*
G01X392660Y508787D02*
G03Y512787I0J2000D01*
G01D02*
G03Y508787I0J-2000D01*
G01X398960Y506887D02*
X386360D01*
G01X398960Y514687D02*
Y506887D01*
G01X386360Y514687D02*
X398960D01*
G01X386360Y506887D02*
Y514687D01*
G01X400060Y505787D02*
X385260D01*
G01X400060Y515787D02*
Y505787D01*
G01X385260Y515787D02*
X400060D01*
G01X385260Y505787D02*
Y515787D01*
G01X374016Y572835D02*
G03X370079Y576772I-3937J0D01*
G01Y533957D02*
G03X374016Y537894I0J3937D01*
G01X356890Y533957D02*
G03X352953Y530020I0J-3937D01*
G01X374016Y572835D02*
Y537894D01*
G01X370079Y533957D02*
X356890D01*
G01X381890Y588583D02*
G03X385827Y584646I3937J0D01*
G01X381890Y588583D02*
Y623524D01*
G01X525591Y584646D02*
X385827D01*
G01Y576772D02*
G03X381890Y572835I0J-3937D01*
G01X385827Y576772D02*
X525591D01*
G01X374016Y568603D02*
G03X381890I3937J0D01*
G01Y537894D02*
G03X374016I-3937J0D01*
G01X370079Y584646D02*
G03X374016Y588583I0J3937D01*
G01D02*
Y653544D01*
G01X385827Y627461D02*
G03X381890Y623524I0J-3937D01*
G01X399016Y627461D02*
G03X402953Y631398I0J3937D01*
G01Y689371D02*
Y631398D01*
G01D02*
Y657481D01*
G01X385827Y627461D02*
X399016D01*
G01X363245Y652631D02*
G03Y648631I0J-2000D01*
G01D02*
G03Y652631I0J2000D01*
G01X356945Y646731D02*
Y654531D01*
G01X369545Y646731D02*
X356945D01*
G01X369545Y654531D02*
Y646731D01*
G01X355845Y645631D02*
Y655631D01*
G01X370645Y645631D02*
X355845D01*
G01X370645Y655631D02*
Y645631D01*
G01X381890Y631398D02*
Y730582D01*
G01X374016Y623524D02*
G03X381890I3937J0D01*
G01Y592816D02*
G03X374016I-3937J0D01*
G01X404921Y691339D02*
X402953Y689371D01*
G01X404921Y691339D02*
X445079D01*
G01X356945Y654531D02*
X369545D01*
G01X355845Y655631D02*
X370645D01*
G01X374016Y661418D02*
Y730594D01*
G01Y653544D02*
G03X370079Y657481I-3937J0D01*
G01X352953Y661418D02*
G03X356890Y657481I3937J0D01*
G01X370079D02*
X356890D01*
G01X352953Y689371D02*
Y661418D01*
G01X359173Y934504D02*
Y917181D01*
G01X445079Y161811D02*
G03X449016Y165748I0J3937D01*
G01X429331D02*
G03X433268Y161811I3937J0D01*
G01X455315Y165748D02*
G03X459252Y161811I3937J0D01*
G01X471063D02*
G03X475000Y165748I0J3937D01*
G01X445079Y161811D02*
X433268D01*
G01X471063D02*
X459252D01*
G01X471063Y114567D02*
G03Y106693I0J-3937D01*
G01X440354D02*
G03Y114567I0J3937D01*
G01X433268Y181496D02*
G03X429331Y177559I0J-3937D01*
G01X449016D02*
G03X445079Y181496I-3937J0D01*
G01X459252D02*
G03X455315Y177559I0J-3937D01*
G01X475000D02*
G03X471063Y181496I-3937J0D01*
G01X429331Y165748D02*
Y177559D01*
G01X449016D02*
Y165748D01*
G01X455315D02*
Y177559D01*
G01X459252Y181496D02*
X471063D01*
G01X433268D02*
X445079D01*
G01X447047Y191930D02*
G03X454528I3740J0D01*
G01X447047Y219292D02*
Y191930D01*
G01X456496Y221260D02*
X454528Y219292D01*
G01D02*
Y191930D01*
G01X447047Y219292D02*
X445079Y221260D01*
G01X456496D02*
X732874D01*
G01X471063Y349607D02*
G03Y341733I0J-3937D01*
G01X440354D02*
G03Y349607I0J3937D01*
G01X445079Y396851D02*
G03X449016Y400788I0J3937D01*
G01X429331D02*
G03X433268Y396851I3937J0D01*
G01X455315Y400788D02*
G03X459252Y396851I3937J0D01*
G01X471063D02*
G03X475000Y400788I0J3937D01*
G01X429331D02*
Y412599D01*
G01X449016D02*
Y400788D01*
G01X455315D02*
Y412599D01*
G01X445079Y396851D02*
X433268D01*
G01X471063D02*
X459252D01*
G01X433268Y416536D02*
G03X429331Y412599I0J-3937D01*
G01X449016D02*
G03X445079Y416536I-3937J0D01*
G01X459252D02*
G03X455315Y412599I0J-3937D01*
G01X475000D02*
G03X471063Y416536I-3937J0D01*
G01X459252D02*
X471063D01*
G01X433268D02*
X445079D01*
G01X447047Y426969D02*
G03X454528I3740J0D01*
G01X447047Y454331D02*
Y426969D01*
G01X456496Y456300D02*
X454528Y454331D01*
G01D02*
Y426969D01*
G01X447047Y454331D02*
X445079Y456300D01*
G01X456496D02*
X732874D01*
G01X471063Y584646D02*
G03Y576772I0J-3937D01*
G01X440354D02*
G03Y584646I0J3937D01*
G01X433268Y651576D02*
G03X429331Y647639I0J-3937D01*
G01X449016D02*
G03X445079Y651576I-3937J0D01*
G01Y631891D02*
G03X449016Y635828I0J3937D01*
G01X429331D02*
G03X433268Y631891I3937J0D01*
G01X455315Y635828D02*
G03X459252Y631891I3937J0D01*
G01Y651576D02*
G03X455315Y647639I0J-3937D01*
G01X475000D02*
G03X471063Y651576I-3937J0D01*
G01Y631891D02*
G03X475000Y635828I0J3937D01*
G01X429331D02*
Y647639D01*
G01X449016D02*
Y635828D01*
G01X455315D02*
Y647639D01*
G01X445079Y631891D02*
X433268D01*
G01X471063D02*
X459252D01*
G01Y651576D02*
X471063D01*
G01X433268D02*
X445079D01*
G01X447047Y662009D02*
G03X454528I3740J0D01*
G01X447047Y689371D02*
Y662009D01*
G01X456496Y691339D02*
X454528Y689371D01*
G01D02*
Y662009D01*
G01X447047Y689371D02*
X445079Y691339D01*
G01X456496D02*
X732874D01*
G01X532401Y-426126D02*
Y-443449D01*
G01X529528Y102756D02*
G03X533465Y98819I3937J0D01*
G01X529528Y102756D02*
G03X525591Y106693I-3937J0D01*
G01X529528Y102756D02*
G03X533465Y98819I3937J0D01*
G01X529528Y102756D02*
G03X525591Y106693I-3937J0D01*
G01X529528Y102756D02*
G03X533465Y98819I3937J0D01*
G01X529528Y102756D02*
G03X525591Y106693I-3937J0D01*
G01X533465Y98819D02*
X604331D01*
G01X497047Y161811D02*
G03X500984Y165748I0J3937D01*
G01X481299D02*
G03X485236Y161811I3937J0D01*
G01X497047D02*
X485236D01*
G01X533465Y122441D02*
G03X529528Y118504I0J-3937D01*
G01X525591Y114567D02*
G03X529528Y118504I0J3937D01*
G01X525591Y114567D02*
X494094D01*
G01X525591D02*
G03X529528Y118504I0J3937D01*
G01X533465Y122441D02*
G03X529528Y118504I0J-3937D01*
G01X533465Y122441D02*
G03X529528Y118504I0J-3937D01*
G01X525591Y114567D02*
G03X529528Y118504I0J3937D01*
G01X604331Y122441D02*
X533465D01*
G01X525591Y106693D02*
X494094D01*
G01X485236Y181496D02*
G03X481299Y177559I0J-3937D01*
G01X500984D02*
G03X497047Y181496I-3937J0D01*
G01X475000Y177559D02*
Y165748D01*
G01X481299D02*
Y177559D01*
G01X500984D02*
Y165748D01*
G01X485236Y181496D02*
X497047D01*
G01X529528Y337796D02*
G03X533465Y333859I3937J0D01*
G01X529528Y337796D02*
G03X525591Y341733I-3937J0D01*
G01D02*
X494094D01*
G01X529528Y337796D02*
G03X533465Y333859I3937J0D01*
G01X529528Y337796D02*
G03X525591Y341733I-3937J0D01*
G01X529528Y337796D02*
G03X533465Y333859I3937J0D01*
G01X529528Y337796D02*
G03X525591Y341733I-3937J0D01*
G01X533465Y333859D02*
X604331D01*
G01X497047Y396851D02*
G03X500984Y400788I0J3937D01*
G01X481299D02*
G03X485236Y396851I3937J0D01*
G01X475000Y412599D02*
Y400788D01*
G01X481299D02*
Y412599D01*
G01X500984D02*
Y400788D01*
G01X497047Y396851D02*
X485236D01*
G01X533465Y357481D02*
G03X529528Y353544I0J-3937D01*
G01X525591Y349607D02*
G03X529528Y353544I0J3937D01*
G01X525591Y349607D02*
X494094D01*
G01X525591D02*
G03X529528Y353544I0J3937D01*
G01X533465Y357481D02*
G03X529528Y353544I0J-3937D01*
G01X533465Y357481D02*
G03X529528Y353544I0J-3937D01*
G01X525591Y349607D02*
G03X529528Y353544I0J3937D01*
G01X604331Y357481D02*
X533465D01*
G01X485236Y416536D02*
G03X481299Y412599I0J-3937D01*
G01X500984D02*
G03X497047Y416536I-3937J0D01*
G01X485236D02*
X497047D01*
G01X533465Y592520D02*
G03X529528Y588583I0J-3937D01*
G01X525591Y584646D02*
G03X529528Y588583I0J3937D01*
G01X525591Y584646D02*
X494094D01*
G01X525591D02*
G03X529528Y588583I0J3937D01*
G01X533465Y592520D02*
G03X529528Y588583I0J-3937D01*
G01X533465Y592520D02*
G03X529528Y588583I0J-3937D01*
G01X525591Y584646D02*
G03X529528Y588583I0J3937D01*
G01Y572835D02*
G03X533465Y568898I3937J0D01*
G01X529528Y572835D02*
G03X525591Y576772I-3937J0D01*
G01D02*
X494094D01*
G01X529528Y572835D02*
G03X533465Y568898I3937J0D01*
G01X529528Y572835D02*
G03X525591Y576772I-3937J0D01*
G01X529528Y572835D02*
G03X533465Y568898I3937J0D01*
G01X529528Y572835D02*
G03X525591Y576772I-3937J0D01*
G01X533465Y568898D02*
X604331D01*
G01X485236Y651576D02*
G03X481299Y647639I0J-3937D01*
G01X500984D02*
G03X497047Y651576I-3937J0D01*
G01Y631891D02*
G03X500984Y635828I0J3937D01*
G01X481299D02*
G03X485236Y631891I3937J0D01*
G01X475000Y647639D02*
Y635828D01*
G01X481299D02*
Y647639D01*
G01X500984D02*
Y635828D01*
G01X497047Y631891D02*
X485236D01*
G01Y651576D02*
X497047D01*
G01X604331Y592520D02*
X533465D01*
G01X532401Y934504D02*
Y917181D01*
G01X652559Y39764D02*
G03X656496Y43701I0J3937D01*
G01X636811D02*
G03X640748Y39764I3937J0D01*
G01X652559D02*
X640748D01*
G01Y59449D02*
G03X636811Y55512I0J-3937D01*
G01X656496D02*
G03X652559Y59449I-3937J0D01*
G01X656496Y55512D02*
Y43701D01*
G01X636811D02*
Y55512D01*
G01X640748Y59449D02*
X652559D01*
G01X604331Y98819D02*
G03X608268Y102756I0J3937D01*
G01X612205Y106693D02*
G03X608268Y102756I0J-3937D01*
G01X612205Y106693D02*
G03X608268Y102756I0J-3937D01*
G01X604331Y98819D02*
G03X608268Y102756I0J3937D01*
G01X604331Y98819D02*
G03X608268Y102756I0J3937D01*
G01X612205Y106693D02*
G03X608268Y102756I0J-3937D01*
G01Y118504D02*
G03X604331Y122441I-3937J0D01*
G01X608268Y118504D02*
G03X612205Y114567I3937J0D01*
G01D02*
X643701D01*
G01X608268Y118504D02*
G03X604331Y122441I-3937J0D01*
G01X608268Y118504D02*
G03X612205Y114567I3937J0D01*
G01X608268Y118504D02*
G03X604331Y122441I-3937J0D01*
G01X608268Y118504D02*
G03X612205Y114567I3937J0D01*
G01X751969D02*
X612205D01*
G01Y106693D02*
X643701D01*
G01X612205D02*
X751969D01*
G01X652559Y274804D02*
G03X656496Y278741I0J3937D01*
G01X636811D02*
G03X640748Y274804I3937J0D01*
G01X656496Y290552D02*
Y278741D01*
G01X636811D02*
Y290552D01*
G01X652559Y274804D02*
X640748D01*
G01Y294489D02*
G03X636811Y290552I0J-3937D01*
G01X656496D02*
G03X652559Y294489I-3937J0D01*
G01X640748D02*
X652559D01*
G01X604331Y333859D02*
G03X608268Y337796I0J3937D01*
G01X612205Y341733D02*
G03X608268Y337796I0J-3937D01*
G01X612205Y341733D02*
X643701D01*
G01X612205D02*
G03X608268Y337796I0J-3937D01*
G01X604331Y333859D02*
G03X608268Y337796I0J3937D01*
G01X604331Y333859D02*
G03X608268Y337796I0J3937D01*
G01X612205Y341733D02*
G03X608268Y337796I0J-3937D01*
G01X612205Y341733D02*
X751969D01*
G01X608268Y353544D02*
G03X604331Y357481I-3937J0D01*
G01X608268Y353544D02*
G03X612205Y349607I3937J0D01*
G01D02*
X643701D01*
G01X608268Y353544D02*
G03X604331Y357481I-3937J0D01*
G01X608268Y353544D02*
G03X612205Y349607I3937J0D01*
G01X608268Y353544D02*
G03X604331Y357481I-3937J0D01*
G01X608268Y353544D02*
G03X612205Y349607I3937J0D01*
G01X751969D02*
X612205D01*
G01X652559Y509843D02*
G03X656496Y513780I0J3937D01*
G01X636811D02*
G03X640748Y509843I3937J0D01*
G01Y529528D02*
G03X636811Y525591I0J-3937D01*
G01X656496D02*
G03X652559Y529528I-3937J0D01*
G01X656496Y525591D02*
Y513780D01*
G01X636811D02*
Y525591D01*
G01X640748Y529528D02*
X652559D01*
G01Y509843D02*
X640748D01*
G01X608268Y588583D02*
G03X604331Y592520I-3937J0D01*
G01X608268Y588583D02*
G03X612205Y584646I3937J0D01*
G01D02*
X643701D01*
G01X608268Y588583D02*
G03X604331Y592520I-3937J0D01*
G01X608268Y588583D02*
G03X612205Y584646I3937J0D01*
G01X608268Y588583D02*
G03X604331Y592520I-3937J0D01*
G01X608268Y588583D02*
G03X612205Y584646I3937J0D01*
G01X751969D02*
X612205D01*
G01X604331Y568898D02*
G03X608268Y572835I0J3937D01*
G01X612205Y576772D02*
G03X608268Y572835I0J-3937D01*
G01X612205Y576772D02*
X643701D01*
G01X612205D02*
G03X608268Y572835I0J-3937D01*
G01X604331Y568898D02*
G03X608268Y572835I0J3937D01*
G01X604331Y568898D02*
G03X608268Y572835I0J3937D01*
G01X612205Y576772D02*
G03X608268Y572835I0J-3937D01*
G01X612205Y576772D02*
X751969D01*
G01X705630Y-426126D02*
Y-443449D01*
G01X704528Y39764D02*
G03X708465Y43701I0J3937D01*
G01X688780D02*
G03X692717Y39764I3937J0D01*
G01X678543D02*
G03X682480Y43701I0J3937D01*
G01X662795D02*
G03X666732Y39764I3937J0D01*
G01X678543D02*
X666732D01*
G01X704528D02*
X692717D01*
G01X690748Y29331D02*
G03X683268I-3740J0D01*
G01X690748Y1969D02*
Y29331D01*
G01X681299Y0D02*
X683268Y1969D01*
G01D02*
Y29331D01*
G01X690748Y1969D02*
X692717Y0D01*
G01X732874D02*
X692717D01*
G01Y59449D02*
G03X688780Y55512I0J-3937D01*
G01X708465D02*
G03X704528Y59449I-3937J0D01*
G01X682480Y55512D02*
G03X678543Y59449I-3937J0D01*
G01X666732D02*
G03X662795Y55512I0J-3937D01*
G01X708465D02*
Y43701D01*
G01X688780D02*
Y55512D01*
G01X682480D02*
Y43701D01*
G01X662795D02*
Y55512D01*
G01X692717Y59449D02*
X704528D01*
G01X666732D02*
X678543D01*
G01X697441Y114567D02*
G03Y106693I0J-3937D01*
G01X666732D02*
G03Y114567I0J3937D01*
G01X704528Y274804D02*
G03X708465Y278741I0J3937D01*
G01X688780D02*
G03X692717Y274804I3937J0D01*
G01X678543D02*
G03X682480Y278741I0J3937D01*
G01X662795D02*
G03X666732Y274804I3937J0D01*
G01X708465Y290552D02*
Y278741D01*
G01X688780D02*
Y290552D01*
G01X682480D02*
Y278741D01*
G01X662795D02*
Y290552D01*
G01X678543Y274804D02*
X666732D01*
G01X704528D02*
X692717D01*
G01X690748Y264370D02*
G03X683268I-3740J0D01*
G01X690748Y237008D02*
Y264370D01*
G01X681299Y235040D02*
X683268Y237008D01*
G01D02*
Y264370D01*
G01X690748Y237008D02*
X692717Y235040D01*
G01X732874D02*
X692717D01*
G01Y294489D02*
G03X688780Y290552I0J-3937D01*
G01X708465D02*
G03X704528Y294489I-3937J0D01*
G01X682480Y290552D02*
G03X678543Y294489I-3937J0D01*
G01X666732D02*
G03X662795Y290552I0J-3937D01*
G01X692717Y294489D02*
X704528D01*
G01X666732D02*
X678543D01*
G01X697441Y349607D02*
G03Y341733I0J-3937D01*
G01X666732D02*
G03Y349607I0J3937D01*
G01X704528Y509843D02*
G03X708465Y513780I0J3937D01*
G01X688780D02*
G03X692717Y509843I3937J0D01*
G01Y529528D02*
G03X688780Y525591I0J-3937D01*
G01X708465D02*
G03X704528Y529528I-3937J0D01*
G01X682480Y525591D02*
G03X678543Y529528I-3937J0D01*
G01Y509843D02*
G03X682480Y513780I0J3937D01*
G01X662795D02*
G03X666732Y509843I3937J0D01*
G01Y529528D02*
G03X662795Y525591I0J-3937D01*
G01X708465D02*
Y513780D01*
G01X688780D02*
Y525591D01*
G01X682480D02*
Y513780D01*
G01X662795D02*
Y525591D01*
G01X692717Y529528D02*
X704528D01*
G01X666732D02*
X678543D01*
G01Y509843D02*
X666732D01*
G01X704528D02*
X692717D01*
G01X690748Y499410D02*
G03X683268I-3740J0D01*
G01X690748Y472048D02*
Y499410D01*
G01X681299Y470079D02*
X683268Y472048D01*
G01D02*
Y499410D01*
G01X690748Y472048D02*
X692717Y470079D01*
G01X732874D02*
X692717D01*
G01X697441Y584646D02*
G03Y576772I0J-3937D01*
G01X666732D02*
G03Y584646I0J3937D01*
G01X705630Y934504D02*
Y917181D01*
G01X734843Y1969D02*
Y59941D01*
G01D02*
Y33858D01*
G01X732874Y0D02*
X734843Y1969D01*
G01X757590Y42711D02*
G03I-4000J0D01*
G01X755590D02*
G03I-2000J0D01*
G01X762744Y17317D02*
G03I-4292J0D01*
G01X775591Y553149D02*
Y15000D01*
G01X760591Y0D02*
G03X775591Y15000I0J15000D01*
G01X742717Y0D02*
Y56004D01*
G01Y0D02*
X760591D01*
G01X755906Y102756D02*
G03X751969Y106693I-3937J0D01*
G01Y63878D02*
G03X755906Y67815I0J3937D01*
G01X738780Y63878D02*
G03X734843Y59941I0J-3937D01*
G01X755906Y102756D02*
Y67815D01*
G01X751969Y63878D02*
X738780D01*
G01X763780Y152761D02*
Y98517D01*
G01Y67822D02*
Y67803D01*
G01X751969Y56004D02*
X742717D01*
G01X751969D02*
G03X763780Y67815I0J11811D01*
G01D02*
G03X755906I-3937J0D01*
G01Y98524D02*
G03X763780I3937J0D01*
G01X751969Y114567D02*
G03X755906Y118504I0J3937D01*
G01D02*
Y183465D01*
G01X763780Y152756D02*
G03X755906I-3937J0D01*
G01Y183465D02*
G03X751969Y187402I-3937J0D01*
G01X734843Y191339D02*
G03X738780Y187402I3937J0D01*
G01X751969D02*
X738780D01*
G01X734843Y219292D02*
X732874Y221260D01*
G01X734843Y219292D02*
Y191339D01*
G01X745135Y182552D02*
G03Y178552I0J-2000D01*
G01D02*
G03Y182552I0J2000D01*
G01X738835Y184452D02*
X751435D01*
G01X738835Y176652D02*
Y184452D01*
G01X751435Y176652D02*
X738835D01*
G01X751435Y184452D02*
Y176652D01*
G01X737735Y185552D02*
X752535D01*
G01X737735Y175552D02*
Y185552D01*
G01X752535Y175552D02*
X737735D01*
G01X752535Y185552D02*
Y175552D01*
G01X755906Y183465D02*
G03X763780I3937J0D01*
G01Y302855D02*
Y183460D01*
G01X734843Y237008D02*
Y294981D01*
G01D02*
Y268898D01*
G01X732874Y235040D02*
X734843Y237008D01*
G01X755906Y337796D02*
G03X751969Y341733I-3937J0D01*
G01Y298918D02*
G03X755906Y302855I0J3937D01*
G01X738780Y298918D02*
G03X734843Y294981I0J-3937D01*
G01X755906Y337796D02*
Y302855D01*
G01X751969Y298918D02*
X738780D01*
G01X763780Y387796D02*
Y333559D01*
G01Y302855D02*
G03X755906I-3937J0D01*
G01Y333563D02*
G03X763780I3937J0D01*
G01X751969Y349607D02*
G03X755906Y353544I0J3937D01*
G01D02*
Y418504D01*
G01X774191Y368115D02*
X776991D01*
G01X774191Y399610D02*
X776991D01*
G01X763780Y387796D02*
G03X755906I-3937J0D01*
G01Y418504D02*
G03X751969Y422441I-3937J0D01*
G01X734843Y426378D02*
G03X738780Y422441I3937J0D01*
G01X751969D02*
X738780D01*
G01X734843Y454331D02*
X732874Y456300D01*
G01X734843Y454331D02*
Y426378D01*
G01X745135Y417591D02*
G03Y413591I0J-2000D01*
G01D02*
G03Y417591I0J2000D01*
G01X738835Y419491D02*
X751435D01*
G01X738835Y411691D02*
Y419491D01*
G01X751435Y411691D02*
X738835D01*
G01X751435Y419491D02*
Y411691D01*
G01X737735Y420591D02*
X752535D01*
G01X737735Y410591D02*
Y420591D01*
G01X752535Y410591D02*
X737735D01*
G01X752535Y420591D02*
Y410591D01*
G01X774191Y431105D02*
X776991D01*
G01X774191Y462600D02*
X776991D01*
G01X763780Y537894D02*
Y418504D01*
G01X755906Y418505D02*
G03X763780I3937J0D01*
G01X734843Y472048D02*
Y530020D01*
G01D02*
Y503937D01*
G01X732874Y470079D02*
X734843Y472048D01*
G01X774191Y494096D02*
X776991D01*
G01X774191Y525591D02*
X776991D01*
G01X751969Y584646D02*
G03X755906Y588583I0J3937D01*
G01D02*
Y653544D01*
G01Y572835D02*
G03X751969Y576772I-3937J0D01*
G01Y533957D02*
G03X755906Y537894I0J3937D01*
G01X738780Y533957D02*
G03X734843Y530020I0J-3937D01*
G01X755906Y572835D02*
Y537894D01*
G01X751969Y533957D02*
X738780D01*
G01X775591Y557086D02*
Y556692D01*
G01Y557086D02*
Y557480D01*
G01X775098Y557086D02*
X776083D01*
G01X775591Y561023D02*
G03Y553149I0J-3937D01*
G01X763780Y537894D02*
G03X755906I-3937J0D01*
G01Y568603D02*
G03X763780I3937J0D01*
G01X775591Y676339D02*
Y561023D01*
G01X763780Y622835D02*
Y568603D01*
G01X745135Y652631D02*
G03Y648631I0J-2000D01*
G01D02*
G03Y652631I0J2000D01*
G01X738835Y646731D02*
Y654531D01*
G01X751435Y646731D02*
X738835D01*
G01X751435Y654531D02*
Y646731D01*
G01X737735Y645631D02*
Y655631D01*
G01X752535Y645631D02*
X737735D01*
G01X752535Y655631D02*
Y645631D01*
G01X767750Y630416D02*
X803950D01*
G01X752535Y645631D02*
X767750Y630416D01*
G01X759605Y642096D02*
X752535Y645631D01*
G01D02*
X756070Y638561D01*
G01D02*
X759605Y642096D01*
G01X763780Y622835D02*
G03X755906I-3937J0D01*
G01Y653544D02*
G03X763780I3937J0D01*
G01X755906D02*
G03X751969Y657481I-3937J0D01*
G01X734843Y661418D02*
G03X738780Y657481I3937J0D01*
G01X751969D02*
X738780D01*
G01X734843Y689371D02*
X732874Y691339D01*
G01X734843Y689371D02*
Y661418D01*
G01X738835Y654531D02*
X751435D01*
G01X737735Y655631D02*
X752535D01*
G01X755906Y661418D02*
Y720476D01*
G01X775591Y684213D02*
Y720073D01*
G01X760014Y677788D02*
G03I-4292J0D01*
G01X775591Y676339D02*
G03X760591Y691339I-15000J0D01*
G01X751969Y665355D02*
X742717D01*
G01X763780Y653544D02*
G03X751969Y665355I-11811J0D01*
G01X742717Y691339D02*
X760591D01*
G01X742717Y665355D02*
Y691339D01*
G01X807293Y-350210D02*
Y-410378D01*
G01D02*
X1559393D01*
G01X807293Y-350210D02*
Y-305084D01*
G01X1596998Y-350210D02*
X807293D01*
G01Y-305084D02*
Y-259958D01*
G01Y-305084D02*
X1183343D01*
G01X807293Y-214832D02*
X1596998D01*
G01X807293Y-259958D02*
Y-154689D01*
G01Y-259958D02*
X1596998D01*
G01X807293Y-154689D02*
X1596998D01*
G01X878858Y-426126D02*
Y-443449D01*
G01Y934504D02*
Y917181D01*
G01X927596Y238393D02*
X1009898D01*
G01X1006748D02*
X927596D01*
G01X974268Y365519D02*
X962851Y359909D01*
G01X995319Y-350210D02*
Y-154689D01*
G01X1032733Y238393D02*
X1009898D01*
G01X1013048D02*
X1032733D01*
G01X1013048Y268669D02*
Y234456D01*
G01X1006748Y268669D02*
Y234456D01*
G01X1009385Y265363D02*
X1035163Y194538D01*
G01X1016985Y272606D02*
X1048340D01*
G01X1014978Y267094D02*
X1048340D01*
G01X1011041D02*
X1013048Y272606D01*
G01Y267094D02*
Y277960D01*
G01Y277330D02*
Y269850D01*
G01Y373787D02*
Y272606D01*
G01X1006748D02*
Y373787D01*
G01Y289141D02*
Y272606D01*
G01X1008754Y267094D02*
X1006748Y272606D01*
G01X1008038Y269062D02*
X1011758D01*
G01X1008754Y267094D02*
X1011041D01*
G01X1006748Y330972D02*
Y355683D01*
G01X964234Y341885D02*
X964331Y341894D01*
G01X964137Y341870D02*
X964234Y341885D01*
G01X964038Y341848D02*
X964137Y341870D01*
G01X963939Y341820D02*
X964038Y341848D01*
G01X963842Y341785D02*
X963939Y341820D01*
G01X963745Y341742D02*
X963842Y341785D01*
G01X963649Y341692D02*
X963745Y341742D01*
G01X963556Y341635D02*
X963649Y341692D01*
G01X963467Y341571D02*
X963556Y341635D01*
G01X963380Y341500D02*
X963467Y341571D01*
G01X963220Y341336D02*
X963298Y341421D01*
G01X963149Y341244D02*
X963220Y341336D01*
G01X963083Y341146D02*
X963149Y341244D01*
G01X963025Y341042D02*
X963083Y341146D01*
G01X962974Y340932D02*
X963025Y341042D01*
G01X962931Y340818D02*
X962974Y340932D01*
G01X962896Y340699D02*
X962931Y340818D01*
G01X962871Y340576D02*
X962896Y340699D01*
G01X962856Y340450D02*
X962871Y340576D01*
G01X962851Y340322D02*
X962856Y340450D01*
G01X964322Y341893D02*
X964426Y341897D01*
G01X964216Y341883D02*
X964322Y341893D01*
G01X964109Y341865D02*
X964216Y341883D01*
G01X964001Y341839D02*
X964109Y341865D01*
G01X963893Y341804D02*
X964001Y341839D01*
G01X963786Y341761D02*
X963893Y341804D01*
G01X963681Y341709D02*
X963786Y341761D01*
G01X963578Y341649D02*
X963681Y341709D01*
G01X963479Y341580D02*
X963578Y341649D01*
G01X963383Y341502D02*
X963479Y341580D01*
G01X963293Y341416D02*
X963383Y341502D01*
G01X963209Y341322D02*
X963293Y341416D01*
G01X963131Y341219D02*
X963209Y341322D01*
G01X963061Y341109D02*
X963131Y341219D01*
G01X963000Y340992D02*
X963061Y341109D01*
G01X962948Y340868D02*
X963000Y340992D01*
G01X962907Y340738D02*
X962948Y340868D01*
G01X962876Y340603D02*
X962907Y340738D01*
G01X962857Y340464D02*
X962876Y340603D01*
G01X962851Y340322D02*
X962857Y340464D01*
G01X1012161Y341825D02*
G03X1012457Y342194I-19247J15743D01*
G01X1006158Y340027D02*
G03X1005211Y339310I0J-984D01*
G01X1006158Y341011D02*
G03X1004263Y339578I0J-1969D01*
G01X1002811Y337074D02*
G03X1003759Y337791I1J984D01*
G01X1002811Y336090D02*
G03X1004706Y337523I1J1968D01*
G01X1005211Y333854D02*
G03X1006158Y333137I947J267D01*
G01X1004263Y333586D02*
G03X1006158Y332153I1894J536D01*
G01X1003759Y335373D02*
G03X1002811Y336090I-948J-268D01*
G01X1004706Y335641D02*
G03X1002811Y337074I-1894J-535D01*
G01X977615Y342488D02*
G03X974804Y342558I-1497J-3641D01*
G01X977989Y343398D02*
G03X974476Y343485I-1870J-4552D01*
G01X964426Y341897D02*
G03X962851Y340322I0J-1575D01*
G01X1022103Y341306D02*
Y349574D01*
G01X1018953Y341011D02*
Y340027D01*
G01Y333137D02*
Y332153D01*
G01X1022103Y343680D02*
X1002811D01*
G01X1012162Y343068D02*
X1002811D01*
G01X1012457Y342194D02*
X1022103D01*
G01X993363Y341897D02*
X962851D01*
G01X1002811Y341825D02*
X1012162D01*
G01X1018520Y333137D02*
Y332153D01*
G01Y341011D02*
Y340027D01*
G01X1012457Y341306D02*
X1022103D01*
G01X1018953Y341011D02*
X1002811D01*
G01X1018953Y340027D02*
X1006158D01*
G01X1002811Y338452D02*
X962851D01*
G01X1013048Y327035D02*
Y369850D01*
G01Y296424D02*
Y300165D01*
G01Y300952D02*
Y297015D01*
G01Y326543D02*
Y306857D01*
G01X1012457Y343680D02*
Y341306D01*
G01X1012162Y343068D02*
Y341011D01*
G01X1004706Y335641D02*
X1005211Y333854D01*
G01X1003759Y335373D02*
X1004263Y333586D01*
G01X981641Y341897D02*
X977989Y343398D01*
G01X979052Y341897D02*
X977615Y342488D01*
G01X1002811Y336090D02*
X989032D01*
G01X1006748Y334909D02*
X1002811D01*
G01X1013048D02*
X1006748D01*
G01X989032Y334121D02*
X962851D01*
G01X963048Y333629D02*
X962851D01*
G01X1006748Y327035D02*
Y369850D01*
G01Y296424D02*
Y300165D01*
G01Y300952D02*
Y297015D01*
G01Y326543D02*
Y306857D01*
G01Y334909D02*
Y330972D01*
G01X1006370D02*
Y300952D01*
G01X963048Y333227D02*
X962851D01*
G01X1018953Y333137D02*
X1006158D01*
G01X963048Y333093D02*
X962851D01*
G01X1002811Y332645D02*
X977418D01*
G01X963048Y332557D02*
X962851D01*
G01X996906Y332448D02*
X985095D01*
G01X963048Y332322D02*
X962851D01*
G01X963048Y332289D02*
X962851D01*
G01Y332189D02*
X963048D01*
G01X1018953Y332153D02*
X1006158D01*
G01X963048Y332054D02*
X962851D01*
G01X1006748Y330972D02*
X962851D01*
G01X1013048D02*
X1006748D01*
G01X1002811Y358235D02*
Y332645D01*
G01X1006748Y327035D02*
X1013048D01*
G01X1006748Y326543D02*
X1013048D01*
G01X1005211Y339310D02*
X1004706Y337523D01*
G01X1004263Y339578D02*
X1003759Y337791D01*
G01X1013048Y322606D02*
X1006748D01*
G01X996906Y332448D02*
Y332645D01*
G01X996654Y332448D02*
Y332645D01*
G01X996152Y332448D02*
Y332645D01*
G01X995901Y332448D02*
Y332645D01*
G01X995398D02*
Y332448D01*
G01X995147Y332645D02*
Y332448D01*
G01X994644Y332645D02*
Y332448D01*
G01X994393D02*
Y332645D01*
G01X994142Y332448D02*
Y332645D01*
G01X1024071Y342487D02*
X1022103Y341306D01*
G01X1012457D02*
X1012162Y341011D01*
G01X993890Y332645D02*
Y332448D01*
G01X993639D02*
Y332645D01*
G01X993363Y348983D02*
Y341897D01*
G01X993136Y332448D02*
Y332645D01*
G01X992885D02*
Y332448D01*
G01X992382D02*
Y332645D01*
G01X991880Y332448D02*
Y332645D01*
G01X991629Y332448D02*
Y332645D01*
G01X991377Y332448D02*
Y332645D01*
G01X990875Y332448D02*
Y332645D01*
G01X990372Y332448D02*
Y332645D01*
G01X990121Y332448D02*
Y332645D01*
G01X989869Y332448D02*
Y332645D01*
G01X989367Y332448D02*
Y332645D01*
G01X989116D02*
Y332448D01*
G01X989032Y334121D02*
Y338452D01*
G01X988864Y332448D02*
Y332645D01*
G01X988613Y332448D02*
Y332645D01*
G01X988110D02*
Y332448D01*
G01X987859Y332645D02*
Y332448D01*
G01X987356Y332645D02*
Y332448D01*
G01X987105D02*
Y332645D01*
G01X986854D02*
Y332448D01*
G01X986603Y332645D02*
Y332448D01*
G01X986351D02*
Y332645D01*
G01X986100Y332448D02*
Y332645D01*
G01X985849Y332448D02*
Y332645D01*
G01X1013048Y310794D02*
X1006748D01*
G01X985346Y332448D02*
Y332645D01*
G01X985095D02*
Y332448D01*
G01X1006748Y306857D02*
X1013048D01*
G01X1006748Y304889D02*
X1013048D01*
G01X1006748Y300952D02*
X1013048D01*
G01D02*
X1006748D01*
G01X977418Y332645D02*
Y330972D01*
G01X1006748Y300165D02*
X1013048D01*
G01Y297015D02*
X1006748D01*
G01X1013048Y296424D02*
X1006748D01*
G01X974804Y342558D02*
X972938Y341897D01*
G01X974476Y343485D02*
X969988Y341897D01*
G01X966394Y348983D02*
Y341897D01*
G01X964426Y348983D02*
Y341897D01*
G01X963048Y333629D02*
Y332054D01*
G01X962851Y359909D02*
Y330972D01*
G01X1052115Y337452D02*
G03X1006748Y351746I-45367J-64847D01*
G01X962877Y350270D02*
X962857Y350412D01*
G01X962909Y350132D02*
X962877Y350270D01*
G01X962953Y350001D02*
X962909Y350132D01*
G01X963007Y349876D02*
X962953Y350001D01*
G01X963070Y349757D02*
X963007Y349876D01*
G01X963141Y349647D02*
X963070Y349757D01*
G01X963220Y349545D02*
X963141Y349647D01*
G01X963306Y349451D02*
X963220Y349545D01*
G01X963398Y349366D02*
X963306Y349451D01*
G01X963494Y349289D02*
X963398Y349366D01*
G01X963593Y349221D02*
X963494Y349289D01*
G01X963696Y349163D02*
X963593Y349221D01*
G01X963801Y349113D02*
X963696Y349163D01*
G01X963907Y349071D02*
X963801Y349113D01*
G01X964014Y349038D02*
X963907Y349071D01*
G01X964119Y349014D02*
X964014Y349038D01*
G01X964220Y348997D02*
X964119Y349014D01*
G01X962858Y350405D02*
X962851Y350558D01*
G01X962880Y350256D02*
X962858Y350405D01*
G01X962915Y350113D02*
X962880Y350256D01*
G01X962963Y349975D02*
X962915Y350113D01*
G01X963021Y349845D02*
X962963Y349975D01*
G01X963090Y349724D02*
X963021Y349845D01*
G01X963168Y349611D02*
X963090Y349724D01*
G01X963254Y349506D02*
X963168Y349611D01*
G01X963346Y349412D02*
X963254Y349506D01*
G01X963445Y349326D02*
X963346Y349412D01*
G01X963548Y349251D02*
X963445Y349326D01*
G01X963656Y349185D02*
X963548Y349251D01*
G01X963766Y349128D02*
X963656Y349185D01*
G01X963878Y349082D02*
X963766Y349128D01*
G01X963991Y349045D02*
X963878Y349082D01*
G01X964104Y349017D02*
X963991Y349045D01*
G01X964213Y348998D02*
X964104Y349017D01*
G01X964322Y348987D02*
X964213Y348998D01*
G01X1006158Y357743D02*
G03X1005211Y357027I0J-984D01*
G01X1006158Y358728D02*
G03X1004263Y357294I0J-1969D01*
G01X1002811Y354791D02*
G03X1003759Y355507I1J984D01*
G01X1002811Y353806D02*
G03X1004706Y355240I1J1968D01*
G01X1005211Y351570D02*
G03X1006158Y350854I947J268D01*
G01X1004263Y351303D02*
G03X1006158Y349869I1895J535D01*
G01X1003759Y353090D02*
G03X1002811Y353806I-947J-268D01*
G01X1004706Y353357D02*
G03X1002811Y354791I-1895J-535D01*
G01X1012457Y348687D02*
G03X1012162Y349056I-20025J-15707D01*
G01X974804Y348323D02*
G03X977615Y348393I1314J3711D01*
G01X974476Y347395D02*
G03X977989Y347482I1643J4639D01*
G01X962851Y350558D02*
G03X964426Y348983I1575J0D01*
G01X1013048Y373787D02*
X1006748D01*
G01X1013048Y369850D02*
X1006748D01*
G01Y365913D02*
X1013048D01*
G01X977418Y365519D02*
X974268D01*
G01X1024071Y348393D02*
X1022103Y349574D01*
G01X1006748Y359928D02*
X977418D01*
G01Y359909D02*
X962851D01*
G01X1018953Y358728D02*
X1006158D01*
G01X1002811Y358235D02*
X977418D01*
G01X996906Y358039D02*
X985095D01*
G01X1012457Y349574D02*
X1012162Y349869D01*
G01X1018953Y357743D02*
X1006158D01*
G01X989032Y356759D02*
X962851D01*
G01X1006748Y355972D02*
X1002811D01*
G01Y354791D02*
X989032D01*
G01X1002811Y352428D02*
X962851D01*
G01X1018953Y350854D02*
X1006158D01*
G01X1002811Y349869D02*
X1018953D01*
G01X964426Y348983D02*
X964319Y348987D01*
G01X1012457Y349574D02*
X1022103D01*
G01X1012162Y349055D02*
X1002811D01*
G01X993363Y348983D02*
X962851D01*
G01X1022103Y348687D02*
X1012457D01*
G01X1012162Y347813D02*
X1002811D01*
G01Y347201D02*
X1022103D01*
G01X1018953Y357743D02*
Y358728D01*
G01Y349869D02*
Y350854D01*
G01X1018520Y358728D02*
Y357743D01*
G01Y350854D02*
Y349869D01*
G01X1004706Y353357D02*
X1005211Y351570D01*
G01X1003759Y353090D02*
X1004263Y351303D01*
G01X974804Y348323D02*
X972938Y348983D01*
G01X974476Y347395D02*
X969988Y348983D01*
G01X1012457Y349574D02*
Y347201D01*
G01X1012162Y349869D02*
Y347813D01*
G01X1006748Y359928D02*
Y355972D01*
G01X1006370Y371543D02*
Y363669D01*
G01X1005211Y357027D02*
X1004706Y355240D01*
G01X996906Y358039D02*
Y358235D01*
G01X996654Y358039D02*
Y358235D01*
G01X996152Y358039D02*
Y358235D01*
G01X995901Y358039D02*
Y358235D01*
G01X995398D02*
Y358039D01*
G01X995147Y358235D02*
Y358039D01*
G01X994644Y358235D02*
Y358039D01*
G01X994393D02*
Y358235D01*
G01X994142Y358039D02*
Y358235D01*
G01X1004263Y357294D02*
X1003759Y355507D01*
G01X993890Y358235D02*
Y358039D01*
G01X993639D02*
Y358235D01*
G01X993136Y358039D02*
Y358235D01*
G01X992885D02*
Y358039D01*
G01X992382D02*
Y358235D01*
G01X991880Y358039D02*
Y358235D01*
G01X991629Y358039D02*
Y358235D01*
G01X991377Y358039D02*
Y358235D01*
G01X990875Y358039D02*
Y358235D01*
G01X990372Y358039D02*
Y358235D01*
G01X990121Y358039D02*
Y358235D01*
G01X989869Y358039D02*
Y358235D01*
G01X989367Y358039D02*
Y358235D01*
G01X989116D02*
Y358039D01*
G01X989032Y352428D02*
Y356759D01*
G01X988864Y358039D02*
Y358235D01*
G01X988613Y358039D02*
Y358235D01*
G01X988110D02*
Y358039D01*
G01X987859Y358235D02*
Y358039D01*
G01X987356Y358235D02*
Y358039D01*
G01X987105D02*
Y358235D01*
G01X986854D02*
Y358039D01*
G01X986603Y358235D02*
Y358039D01*
G01X986351D02*
Y358235D01*
G01X986100Y358039D02*
Y358235D01*
G01X985849Y358039D02*
Y358235D01*
G01X985346Y358039D02*
Y358235D01*
G01X985095D02*
Y358039D01*
G01X977418Y358235D02*
Y365519D01*
G01X981641Y348983D02*
X977989Y347482D01*
G01X979052Y348983D02*
X977615Y348393D01*
G01X1052086Y-426126D02*
Y-443449D01*
G01X1033816Y198237D02*
G03X1051291Y207189I-27067J74369D01*
G01X1044403Y364657D02*
Y269850D01*
G01Y272606D02*
Y364657D01*
G01Y247409D02*
Y269850D01*
G01Y267094D02*
Y247409D01*
G01X1099719Y285637D02*
X1064581Y250182D01*
G01X1024071Y348393D02*
Y342487D01*
G01X1099561Y356025D02*
X1060158Y391412D01*
G01X1081860Y584346D02*
X1070443D01*
G01X1085797Y618205D02*
X1070443D01*
G01X1085797Y691039D02*
X1070443D01*
G01X1233435Y683165D02*
X1070443D01*
G01X1052086Y934504D02*
Y917181D01*
G01X1118154Y283622D02*
X1153032Y326776D01*
G01X1098554Y288434D02*
G03X1102491Y284497I3937J0D01*
G01X1119617Y280560D02*
G03X1115680Y284497I-3937J0D01*
G01X1121865Y267395D02*
X1122030Y267437D01*
G01X1122357Y266809D02*
X1122193Y266767D01*
G01X1121865Y266557D02*
X1122030Y266600D01*
G01X1122357Y265930D02*
X1122193Y265887D01*
G01X1120184Y267646D02*
X1119938Y267605D01*
G01X1120020Y267395D02*
X1120225Y267437D01*
G01X1121824Y267605D02*
X1122030Y267646D01*
G01X1123711D02*
X1123506Y267605D01*
G01X1122439Y265720D02*
X1122235Y265678D01*
G01X1102491Y284497D02*
X1115680D01*
G01X1123670Y266557D02*
X1123547Y266516D01*
G01Y267354D02*
X1123670Y267395D01*
G01X1144420Y272686D02*
X1147176D01*
G01X1140483D02*
X1143239D01*
G01X1136546D02*
X1139302D01*
G01X1132609D02*
X1135365D01*
G01X1128672D02*
X1131428D01*
G01X1120798D02*
X1123554D01*
G01X1127491D02*
X1124735D01*
G01X1122030Y267646D02*
X1122193D01*
G01X1120348D02*
X1120184D01*
G01X1124695D02*
X1123711D01*
G01X1122030Y267437D02*
X1122193D01*
G01X1120225D02*
X1120389D01*
G01X1123670Y267395D02*
X1124449D01*
G01X1120799Y267186D02*
X1121004D01*
G01X1124449Y266809D02*
X1123670D01*
G01X1122193Y266767D02*
X1122030D01*
G01Y266600D02*
X1122193D01*
G01X1124449Y266557D02*
X1123670D01*
G01Y265930D02*
X1124449D01*
G01X1120717Y265887D02*
X1119569D01*
G01X1122193D02*
X1122030D01*
G01X1123711Y265678D02*
X1124695D01*
G01X1119569D02*
X1121045D01*
G01X1122235D02*
X1121989D01*
G01X1124735Y260087D02*
X1127491D01*
G01X1119617Y256150D02*
X1399931D01*
G01X1123554D02*
X1120798D01*
G01X1131428D02*
X1128672D01*
G01X1135365D02*
X1132609D01*
G01X1139302D02*
X1136546D01*
G01X1143239D02*
X1140483D01*
G01X1147176D02*
X1144420D01*
G01X1122522Y266013D02*
X1122357Y265930D01*
G01X1123424Y266683D02*
X1123342Y266641D01*
G01X1122604Y266725D02*
X1122522Y266683D01*
G01X1121701Y266474D02*
X1121865Y266557D01*
G01X1121619Y266641D02*
X1121701Y266683D01*
G01X1119938Y267605D02*
X1119774Y267521D01*
G01X1120635Y267605D02*
X1120348Y267646D01*
G01X1098554Y250639D02*
X1109420D01*
G01X1397963D02*
X1121585D01*
G01X1122644Y265846D02*
X1122439Y265720D01*
G01X1121619Y267479D02*
X1121824Y267605D01*
G01X1119897Y267311D02*
X1120020Y267395D01*
G01X1122193Y267437D02*
X1122357Y267395D01*
G01X1122193Y267646D02*
X1122398Y267605D01*
G01X1120389Y267437D02*
X1120594Y267395D01*
G01X1123506Y265720D02*
X1123711Y265678D01*
G01X1121989D02*
X1121783Y265720D01*
G01X1123506Y267605D02*
X1123342Y267479D01*
G01X1122522Y266935D02*
X1122357Y266809D01*
G01X1121455Y266516D02*
X1121619Y266641D01*
G01X1121701Y267270D02*
X1121865Y267395D01*
G01X1123670Y266809D02*
X1123547Y266851D01*
G01Y265971D02*
X1123670Y265930D01*
G01X1122030Y266767D02*
X1121865Y266809D01*
G01X1122193Y266600D02*
X1122357Y266557D01*
G01X1122030Y265887D02*
X1121865Y265930D01*
G01X1123547Y266516D02*
X1123465Y266432D01*
G01X1122768Y265971D02*
X1122644Y265846D01*
G01X1123465Y267270D02*
X1123547Y267354D01*
G01X1122727Y266851D02*
X1122604Y266725D01*
G01X1121496Y267354D02*
X1121619Y267479D01*
G01X1119774Y267521D02*
X1119610Y267354D01*
G01X1123342Y266725D02*
X1123424Y266683D01*
G01X1122522D02*
X1122604Y266641D01*
G01X1120799Y267521D02*
X1120635Y267605D01*
G01X1122357Y266557D02*
X1122522Y266474D01*
G01X1121701Y266683D02*
X1121619Y266725D01*
G01X1121865Y265930D02*
X1121701Y266013D01*
G01X1123342Y266641D02*
X1123219Y266474D01*
G01X1122644Y266181D02*
X1122522Y266013D01*
G01X1123342Y267479D02*
X1123219Y267311D01*
G01X1121578Y266306D02*
X1121701Y266474D01*
G01X1120594Y267395D02*
X1120717Y267311D01*
G01X1122398Y267605D02*
X1122604Y267479D01*
G01X1121783Y265720D02*
X1121578Y265846D01*
G01X1122604Y267060D02*
X1122522Y266935D01*
G01X1121619Y267144D02*
X1121701Y267270D01*
G01X1119815Y267186D02*
X1119897Y267311D01*
G01X1121045Y265887D02*
X1119897Y266935D01*
G01X1119692Y266809D02*
X1120717Y265887D01*
G01X1122357Y267395D02*
X1122522Y267270D01*
G01X1122604Y266641D02*
X1122768Y266516D01*
G01X1123342Y265846D02*
X1123506Y265720D01*
G01X1121865Y266809D02*
X1121701Y266935D01*
G01X1122809Y267018D02*
X1122727Y266851D01*
G01X1122850Y266181D02*
X1122768Y265971D01*
G01X1121373Y266306D02*
X1121455Y266516D01*
G01X1121414Y267144D02*
X1121496Y267354D01*
G01X1123219Y266893D02*
X1123342Y266725D01*
G01X1123219Y266013D02*
X1123342Y265846D01*
G01X1122522Y266474D02*
X1122644Y266306D01*
G01X1123547Y266851D02*
X1123465Y266935D01*
G01X1122604Y267479D02*
X1122727Y267354D01*
G01X1123465Y266055D02*
X1123547Y265971D01*
G01X1121619Y266725D02*
X1121496Y266851D01*
G01X1120963Y267354D02*
X1120799Y267521D01*
G01X1121578Y265846D02*
X1121455Y265971D01*
G01X1119617Y252607D02*
X1121585Y250639D01*
G01X1123465Y266432D02*
X1123424Y266306D01*
G01X1123219Y266474D02*
X1123178Y266348D01*
G01X1123424Y267144D02*
X1123465Y267270D01*
G01X1123219Y267311D02*
X1123178Y267186D01*
G01X1119610Y267354D02*
X1119569Y267186D01*
G01X1144420Y256150D02*
Y272686D01*
G01X1143239D02*
Y256150D01*
G01X1140483D02*
Y272686D01*
G01X1139302D02*
Y256150D01*
G01X1136546D02*
Y272686D01*
G01X1135365D02*
Y256150D01*
G01X1132609D02*
Y272686D01*
G01X1123465Y266935D02*
X1123424Y267060D01*
G01X1123178Y267018D02*
X1123219Y266893D01*
G01X1123424Y266181D02*
X1123465Y266055D01*
G01X1123178Y266139D02*
X1123219Y266013D01*
G01X1122727Y267354D02*
X1122809Y267144D01*
G01X1122768Y266516D02*
X1122850Y266306D01*
G01X1121455Y265971D02*
X1121373Y266181D01*
G01X1121496Y266851D02*
X1121414Y267018D01*
G01X1119897Y266935D02*
X1119815Y267102D01*
G01X1122522Y267270D02*
X1122604Y267144D01*
G01X1121701Y266935D02*
X1121619Y267060D01*
G01X1120717Y267311D02*
X1120799Y267186D01*
G01X1119610Y266935D02*
X1119692Y266809D01*
G01X1121701Y266013D02*
X1121578Y266181D01*
G01X1131428Y272686D02*
Y256150D01*
G01X1128672D02*
Y272686D01*
G01X1127491Y260087D02*
Y272686D01*
G01X1124735D02*
Y260087D01*
G01X1124695Y265678D02*
Y267646D01*
G01X1124449Y265930D02*
Y266557D01*
G01Y267395D02*
Y266809D01*
G01X1123554Y272686D02*
Y256150D01*
G01X1123424Y267060D02*
Y267144D01*
G01Y266306D02*
Y266181D01*
G01X1123178Y266348D02*
Y266139D01*
G01Y267186D02*
Y267018D01*
G01X1122850Y266306D02*
Y266181D01*
G01X1122809Y267144D02*
Y267018D01*
G01X1122644Y266306D02*
Y266181D01*
G01X1122604Y267144D02*
Y267060D01*
G01X1121619D02*
Y267144D01*
G01X1121578Y266181D02*
Y266306D01*
G01X1121414Y267018D02*
Y267144D01*
G01X1121373Y266181D02*
Y266306D01*
G01X1121045Y265678D02*
Y265887D01*
G01X1120798Y256150D02*
Y272686D01*
G01X1119815Y267102D02*
Y267186D01*
G01X1119617Y252607D02*
Y280560D01*
G01X1119569Y265887D02*
Y265678D01*
G01Y267186D02*
Y267102D01*
G01X1121004Y267186D02*
X1120963Y267354D01*
G01X1119569Y267102D02*
X1119610Y266935D01*
G01X1098554Y250639D02*
Y261505D01*
G01Y353394D02*
Y288434D01*
G01X1102491Y357331D02*
G03X1098554Y353394I0J-3937D01*
G01X1102491Y357331D02*
X1242254D01*
G01X1106860Y582378D02*
Y568992D01*
G01X1085797Y580409D02*
Y568992D01*
G01X1106860Y589858D02*
X1387175D01*
G01X1110797D02*
X1108041D01*
G01X1114734D02*
X1111978D01*
G01X1118671D02*
X1115915D01*
G01X1122608D02*
X1119852D01*
G01X1126545D02*
X1123789D01*
G01X1130482D02*
X1127726D01*
G01X1134419D02*
X1131663D01*
G01X1138356D02*
X1135600D01*
G01X1142293D02*
X1139537D01*
G01X1146230D02*
X1143474D01*
G01X1085797Y584346D02*
X1096663D01*
G01X1385206D02*
X1108828D01*
G01X1143474Y589858D02*
Y606394D01*
G01X1142293D02*
Y589858D01*
G01X1139537D02*
Y606394D01*
G01X1138356D02*
Y589858D01*
G01X1135600D02*
Y606394D01*
G01X1134419D02*
Y589858D01*
G01X1106860Y586315D02*
X1108828Y584346D01*
G01X1131663Y589858D02*
Y606394D01*
G01X1130482D02*
Y589858D01*
G01X1127726D02*
Y606394D01*
G01X1126545D02*
Y589858D01*
G01X1123789D02*
Y606394D01*
G01X1122608D02*
Y589858D01*
G01X1119852D02*
Y606394D01*
G01X1118671D02*
Y589858D01*
G01X1115915D02*
Y606394D01*
G01X1114734D02*
Y589858D01*
G01X1111978D02*
Y606394D01*
G01X1110797D02*
Y589858D01*
G01X1108041D02*
Y606394D01*
G01X1106860Y586315D02*
Y614268D01*
G01X1085797Y584346D02*
Y595213D01*
G01Y622142D02*
G03X1089734Y618205I3937J0D01*
G01X1106860Y614268D02*
G03X1102923Y618205I-3937J0D01*
G01X1105954Y651374D02*
X1101151D01*
G01X1140350Y651106D02*
X1141480D01*
G01X1132476D02*
X1133606D01*
G01X1124602D02*
X1125731D01*
G01X1116728D02*
X1117857D01*
G01X1108854D02*
X1109983D01*
G01X1109993Y650839D02*
X1108845D01*
G01X1117867D02*
X1116719D01*
G01X1125741D02*
X1124593D01*
G01X1133615D02*
X1132467D01*
G01X1141489D02*
X1140341D01*
G01X1140359Y650390D02*
X1141470D01*
G01X1132485D02*
X1133596D01*
G01X1124611D02*
X1125722D01*
G01X1116737D02*
X1117848D01*
G01X1108863D02*
X1109974D01*
G01X1440128Y649898D02*
X1105482D01*
G01X1140359Y649406D02*
X1141470D01*
G01X1132485D02*
X1133596D01*
G01X1124611D02*
X1125722D01*
G01X1116737D02*
X1117848D01*
G01X1108863D02*
X1109974D01*
G01X1097608Y648224D02*
X1448002D01*
G01X1108806Y604046D02*
X1108970Y604088D01*
G01X1109298Y603459D02*
X1109134Y603418D01*
G01X1108806Y603208D02*
X1108970Y603250D01*
G01X1109298Y602580D02*
X1109134Y602538D01*
G01X1107124Y604297D02*
X1106878Y604255D01*
G01X1106960Y604046D02*
X1107165Y604088D01*
G01X1108765Y604255D02*
X1108970Y604297D01*
G01X1109380Y602370D02*
X1109175Y602329D01*
G01X1089734Y618205D02*
X1102923D01*
G01X1438750D02*
X1097608D01*
G01X1143474Y606394D02*
X1146230D01*
G01X1139537D02*
X1142293D01*
G01X1135600D02*
X1138356D01*
G01X1131663D02*
X1134419D01*
G01X1127726D02*
X1130482D01*
G01X1123789D02*
X1126545D01*
G01X1119852D02*
X1122608D01*
G01X1115915D02*
X1118671D01*
G01X1111978D02*
X1114734D01*
G01X1108041D02*
X1110797D01*
G01X1108970Y604297D02*
X1109134D01*
G01X1107289D02*
X1107124D01*
G01X1111102D02*
X1110774D01*
G01X1108970Y604088D02*
X1109134D01*
G01X1107165D02*
X1107330D01*
G01X1107740Y603836D02*
X1107944D01*
G01X1109134Y603418D02*
X1108970D01*
G01Y603250D02*
X1109134D01*
G01X1110569Y602999D02*
X1111307D01*
G01X1110528Y602831D02*
X1111348D01*
G01X1107657Y602538D02*
X1106509D01*
G01X1109134D02*
X1108970D01*
G01X1111513Y602329D02*
X1111759D01*
G01X1110118D02*
X1110364D01*
G01X1106509D02*
X1107986D01*
G01X1109175D02*
X1108929D01*
G01X1109462Y602664D02*
X1109298Y602580D01*
G01X1109544Y603376D02*
X1109462Y603334D01*
G01X1108642Y603124D02*
X1108806Y603208D01*
G01X1108560Y603292D02*
X1108642Y603334D01*
G01X1106878Y604255D02*
X1106714Y604172D01*
G01X1107576Y604255D02*
X1107289Y604297D01*
G01X1109585Y602496D02*
X1109380Y602370D01*
G01X1108560Y604130D02*
X1108765Y604255D01*
G01X1109134Y604088D02*
X1109298Y604046D01*
G01X1108970Y603418D02*
X1108806Y603459D01*
G01X1109134Y603250D02*
X1109298Y603208D01*
G01X1108970Y602538D02*
X1108806Y602580D01*
G01X1109134Y604297D02*
X1109339Y604255D01*
G01X1107330Y604088D02*
X1107535Y604046D01*
G01X1108929Y602329D02*
X1108724Y602370D01*
G01X1106837Y603962D02*
X1106960Y604046D01*
G01X1109462Y603585D02*
X1109298Y603459D01*
G01X1108396Y603166D02*
X1108560Y603292D01*
G01X1108642Y603920D02*
X1108806Y604046D01*
G01X1109708Y602622D02*
X1109585Y602496D01*
G01X1109667Y603501D02*
X1109544Y603376D01*
G01X1108437Y604004D02*
X1108560Y604130D01*
G01X1106714Y604172D02*
X1106550Y604004D01*
G01X1109339Y604255D02*
X1109544Y604130D01*
G01X1109462Y603334D02*
X1109544Y603292D01*
G01X1107740Y604172D02*
X1107576Y604255D01*
G01X1109298Y603208D02*
X1109462Y603124D01*
G01X1108642Y603334D02*
X1108560Y603376D01*
G01X1108806Y602580D02*
X1108642Y602664D01*
G01X1109585Y602831D02*
X1109462Y602664D01*
G01X1108519Y602957D02*
X1108642Y603124D01*
G01X1109298Y604046D02*
X1109462Y603920D01*
G01X1109544Y603292D02*
X1109708Y603166D01*
G01X1108806Y603459D02*
X1108642Y603585D01*
G01X1107535Y604046D02*
X1107657Y603962D01*
G01X1108724Y602370D02*
X1108519Y602496D01*
G01X1109544Y603711D02*
X1109462Y603585D01*
G01X1108560Y603794D02*
X1108642Y603920D01*
G01X1106756Y603836D02*
X1106837Y603962D01*
G01X1109544Y604130D02*
X1109667Y604004D01*
G01X1107986Y602538D02*
X1106837Y603585D01*
G01X1106632Y603459D02*
X1107657Y602538D01*
G01X1109749Y603669D02*
X1109667Y603501D01*
G01X1109790Y602831D02*
X1109708Y602622D01*
G01X1108314Y602957D02*
X1108396Y603166D01*
G01X1108355Y603794D02*
X1108437Y604004D01*
G01X1141494Y652626D02*
X1141489Y650839D01*
G01X1141480Y651106D02*
X1141485Y652893D01*
G01X1133620Y652626D02*
X1133615Y650839D01*
G01X1133606Y651106D02*
X1133611Y652893D01*
G01X1141348Y650390D02*
Y649406D01*
G01X1140482Y650390D02*
Y649406D01*
G01X1133474Y650390D02*
Y649406D01*
G01X1132608Y650390D02*
Y649406D01*
G01X1140345Y652893D02*
X1140350Y651106D01*
G01X1140341Y650839D02*
X1140336Y652626D01*
G01X1132471Y652893D02*
X1132476Y651106D01*
G01X1132467Y650839D02*
X1132462Y652626D01*
G01X1109462Y603124D02*
X1109585Y602957D01*
G01X1108642Y602664D02*
X1108519Y602831D01*
G01X1108560Y603376D02*
X1108437Y603501D01*
G01X1107904Y604004D02*
X1107740Y604172D01*
G01X1108519Y602496D02*
X1108396Y602622D01*
G01X1110774Y604297D02*
X1110118Y602329D01*
G01X1110364D02*
X1110528Y602831D01*
G01X1110939Y604130D02*
X1110569Y602999D01*
G01X1106550Y604004D02*
X1106509Y603836D01*
G01X1125746Y652626D02*
X1125741Y650839D01*
G01X1125731Y651106D02*
X1125737Y652893D01*
G01X1125600Y650390D02*
Y649406D01*
G01X1124734Y650390D02*
Y649406D01*
G01X1124597Y652893D02*
X1124602Y651106D01*
G01X1124593Y650839D02*
X1124588Y652626D01*
G01X1111307Y602999D02*
X1110939Y604130D01*
G01X1111348Y602831D02*
X1111513Y602329D01*
G01X1111759D02*
X1111102Y604297D01*
G01X1109667Y604004D02*
X1109749Y603794D01*
G01X1109708Y603166D02*
X1109790Y602957D01*
G01X1108396Y602622D02*
X1108314Y602831D01*
G01X1108437Y603501D02*
X1108355Y603669D01*
G01X1106837Y603585D02*
X1106756Y603753D01*
G01X1109462Y603920D02*
X1109544Y603794D01*
G01X1108642Y603585D02*
X1108560Y603711D01*
G01X1107657Y603962D02*
X1107740Y603836D01*
G01X1106550Y603585D02*
X1106632Y603459D01*
G01X1117872Y652626D02*
X1117867Y650839D01*
G01X1117857Y651106D02*
X1117863Y652893D01*
G01X1109998Y652626D02*
X1109993Y650839D01*
G01X1109983Y651106D02*
X1109989Y652893D01*
G01X1117726Y650390D02*
Y649406D01*
G01X1116860Y650390D02*
Y649406D01*
G01X1109852Y650390D02*
Y649406D01*
G01X1109790Y602957D02*
Y602831D01*
G01X1109749Y603794D02*
Y603669D01*
G01X1109585Y602957D02*
Y602831D01*
G01X1109544Y603794D02*
Y603711D01*
G01X1108986Y650390D02*
Y649406D01*
G01X1108560Y603711D02*
Y603794D01*
G01X1108519Y602831D02*
Y602957D01*
G01X1108355Y603669D02*
Y603794D01*
G01X1108314Y602831D02*
Y602957D01*
G01X1107986Y602329D02*
Y602538D01*
G01X1106756Y603753D02*
Y603836D01*
G01X1106509Y602538D02*
Y602329D01*
G01Y603836D02*
Y603753D01*
G01X1116723Y652893D02*
X1116728Y651106D01*
G01X1116719Y650839D02*
X1116714Y652626D01*
G01X1108849Y652893D02*
X1108854Y651106D01*
G01X1108845Y650839D02*
X1108840Y652626D01*
G01X1107944Y603836D02*
X1107904Y604004D01*
G01X1106509Y603753D02*
X1106550Y603585D01*
G01X1105954Y651374D02*
Y655705D01*
G01X1105482Y652161D02*
Y648224D01*
G01X1101151Y655705D02*
Y651374D01*
G01X1097608Y648224D02*
Y682772D01*
G01X1085797Y687102D02*
Y622142D01*
G01X1105285Y666236D02*
X1103710Y667811D01*
G01Y657575D02*
X1105285Y659150D01*
G01Y662693D02*
G03I-2953J0D01*
G01X1089734Y691039D02*
G03X1085797Y687102I0J-3937D01*
G01X1106072Y664454D02*
G03Y660932I-3740J-1761D01*
G01X1098592Y660320D02*
G03X1106072I3740J2373D01*
G01Y665065D02*
G03X1098592I-3740J-2372D01*
G01X1089734Y691039D02*
X1229498D01*
G01X1114065Y682772D02*
X1097608D01*
G01X1134970D02*
X1119065D01*
G01X1155876D02*
X1139970D01*
G01X1105482Y677181D02*
X1097608D01*
G01X1448002Y677161D02*
X1097608D01*
G01X1109974Y675980D02*
X1108863D01*
G01X1117848D02*
X1116737D01*
G01X1125722D02*
X1124611D01*
G01X1133596D02*
X1132485D01*
G01X1141470D02*
X1140359D01*
G01X1105482Y675488D02*
X1440128D01*
G01X1109974Y674996D02*
X1108863D01*
G01X1117848D02*
X1116737D01*
G01X1125722D02*
X1124611D01*
G01X1133596D02*
X1132485D01*
G01X1141470D02*
X1140359D01*
G01X1140341Y674547D02*
X1141489D01*
G01X1132467D02*
X1133615D01*
G01X1124593D02*
X1125741D01*
G01X1116719D02*
X1117867D01*
G01X1108844D02*
X1109993D01*
G01X1109983Y674279D02*
X1108854D01*
G01X1117857D02*
X1116728D01*
G01X1125731D02*
X1124602D01*
G01X1133606D02*
X1132476D01*
G01X1141480D02*
X1140350D01*
G01X1105954Y674012D02*
X1101151D01*
G01X1097608Y673224D02*
X1105482D01*
G01X1109998Y672760D02*
X1108840D01*
G01X1117872D02*
X1116714D01*
G01X1125746D02*
X1124588D01*
G01X1133620D02*
X1132462D01*
G01X1141494D02*
X1140336D01*
G01X1140345Y672492D02*
X1141485D01*
G01X1132471D02*
X1133611D01*
G01X1124597D02*
X1125737D01*
G01X1116723D02*
X1117863D01*
G01X1108849D02*
X1109989D01*
G01X1105088Y672043D02*
X1101151D01*
G01X1110007D02*
X1108830D01*
G01X1113944D02*
X1112767D01*
G01X1117881D02*
X1116704D01*
G01X1121818D02*
X1120641D01*
G01X1125755D02*
X1124578D01*
G01X1129692D02*
X1128515D01*
G01X1133629D02*
X1132452D01*
G01X1137566D02*
X1136389D01*
G01X1141503D02*
X1140326D01*
G01X1145440D02*
X1144263D01*
G01X1110007Y671059D02*
X1108830D01*
G01X1113944D02*
X1112767D01*
G01X1117881D02*
X1116704D01*
G01X1121818D02*
X1120641D01*
G01X1125755D02*
X1124578D01*
G01X1129692D02*
X1128515D01*
G01X1133629D02*
X1132452D01*
G01X1137566D02*
X1136389D01*
G01X1141503D02*
X1140326D01*
G01X1145440D02*
X1144263D01*
G01X1113926Y670610D02*
X1112786D01*
G01X1121800D02*
X1120660D01*
G01X1129674D02*
X1128534D01*
G01X1137548D02*
X1136408D01*
G01X1145422D02*
X1144282D01*
G01X1144273Y670342D02*
X1145431D01*
G01X1136399D02*
X1137557D01*
G01X1128525D02*
X1129683D01*
G01X1120651D02*
X1121809D01*
G01X1112777D02*
X1113935D01*
G01X1105954Y669681D02*
X1101151D01*
G01X1144287Y668823D02*
X1145417D01*
G01X1136413D02*
X1137543D01*
G01X1128539D02*
X1129669D01*
G01X1120665D02*
X1121794D01*
G01X1112791D02*
X1113920D01*
G01X1113930Y668555D02*
X1112781D01*
G01X1121804D02*
X1120656D01*
G01X1129678D02*
X1128530D01*
G01X1137552D02*
X1136404D01*
G01X1145426D02*
X1144278D01*
G01X1113911Y668106D02*
X1112800D01*
G01X1121785D02*
X1120674D01*
G01X1129659D02*
X1128548D01*
G01X1137533D02*
X1136422D01*
G01X1145407D02*
X1144296D01*
G01X1387969Y667811D02*
X1103710D01*
G01X1113911Y667122D02*
X1112800D01*
G01X1121785D02*
X1120674D01*
G01X1129659D02*
X1128548D01*
G01X1137533D02*
X1136422D01*
G01X1145407D02*
X1144296D01*
G01X1105285Y666236D02*
X1440324D01*
G01X1110044Y665645D02*
X1108794D01*
G01X1113981D02*
X1112731D01*
G01X1117918D02*
X1116668D01*
G01X1121855D02*
X1120605D01*
G01X1125792D02*
X1124542D01*
G01X1129729D02*
X1128479D01*
G01X1133666D02*
X1132416D01*
G01X1137603D02*
X1136353D01*
G01X1141540D02*
X1140290D01*
G01X1145477D02*
X1144227D01*
G01X1144246Y665575D02*
X1145458D01*
G01X1140309D02*
X1141521D01*
G01X1136372D02*
X1137584D01*
G01X1132435D02*
X1133647D01*
G01X1128498D02*
X1129710D01*
G01X1124561D02*
X1125773D01*
G01X1120624D02*
X1121836D01*
G01X1116687D02*
X1117899D01*
G01X1112750D02*
X1113962D01*
G01X1108813D02*
X1110025D01*
G01X1110034Y665350D02*
X1108804D01*
G01X1113971D02*
X1112741D01*
G01X1117908D02*
X1116678D01*
G01X1121845D02*
X1120615D01*
G01X1125782D02*
X1124552D01*
G01X1129719D02*
X1128489D01*
G01X1133656D02*
X1132426D01*
G01X1137593D02*
X1136363D01*
G01X1141530D02*
X1140300D01*
G01X1145467D02*
X1144237D01*
G01X1144224Y664735D02*
X1145480D01*
G01X1140287D02*
X1141543D01*
G01X1136350D02*
X1137606D01*
G01X1132413D02*
X1133669D01*
G01X1128476D02*
X1129731D01*
G01X1124539D02*
X1125794D01*
G01X1120602D02*
X1121857D01*
G01X1116665D02*
X1117920D01*
G01X1112728D02*
X1113983D01*
G01X1108791D02*
X1110046D01*
G01X1110022Y664647D02*
X1108815D01*
G01X1113959D02*
X1112752D01*
G01X1117896D02*
X1116689D01*
G01X1121833D02*
X1120626D01*
G01X1125770D02*
X1124563D01*
G01X1129707D02*
X1128500D01*
G01X1133644D02*
X1132437D01*
G01X1137581D02*
X1136374D01*
G01X1141519D02*
X1140311D01*
G01X1145456D02*
X1144248D01*
G01X1110034Y664365D02*
X1108804D01*
G01X1113971D02*
X1112741D01*
G01X1117908D02*
X1116678D01*
G01X1121845D02*
X1120615D01*
G01X1125782D02*
X1124552D01*
G01X1129719D02*
X1128489D01*
G01X1133656D02*
X1132426D01*
G01X1137593D02*
X1136363D01*
G01X1141530D02*
X1140300D01*
G01X1145467D02*
X1144237D01*
G01Y661020D02*
X1145467D01*
G01X1140300D02*
X1141530D01*
G01X1136363D02*
X1137593D01*
G01X1132426D02*
X1133656D01*
G01X1128489D02*
X1129719D01*
G01X1124552D02*
X1125782D01*
G01X1120615D02*
X1121845D01*
G01X1116678D02*
X1117908D01*
G01X1112741D02*
X1113971D01*
G01X1108804D02*
X1110034D01*
G01X1144248Y660738D02*
X1145456D01*
G01X1140311D02*
X1141519D01*
G01X1136374D02*
X1137581D01*
G01X1132437D02*
X1133644D01*
G01X1128500D02*
X1129707D01*
G01X1124563D02*
X1125770D01*
G01X1120626D02*
X1121833D01*
G01X1116689D02*
X1117896D01*
G01X1112752D02*
X1113959D01*
G01X1108815D02*
X1110022D01*
G01X1110046Y660650D02*
X1108791D01*
G01X1113983D02*
X1112728D01*
G01X1117920D02*
X1116665D01*
G01X1121857D02*
X1120602D01*
G01X1125794D02*
X1124539D01*
G01X1129731D02*
X1128476D01*
G01X1133669D02*
X1132413D01*
G01X1137606D02*
X1136350D01*
G01X1141543D02*
X1140287D01*
G01X1145480D02*
X1144224D01*
G01X1144237Y660036D02*
X1145467D01*
G01X1140300D02*
X1141530D01*
G01X1136363D02*
X1137593D01*
G01X1132426D02*
X1133656D01*
G01X1128489D02*
X1129719D01*
G01X1124552D02*
X1125782D01*
G01X1120615D02*
X1121845D01*
G01X1116678D02*
X1117908D01*
G01X1112741D02*
X1113971D01*
G01X1108804D02*
X1110034D01*
G01X1110025Y659810D02*
X1108813D01*
G01X1113962D02*
X1112750D01*
G01X1117899D02*
X1116687D01*
G01X1121836D02*
X1120624D01*
G01X1125773D02*
X1124561D01*
G01X1129710D02*
X1128498D01*
G01X1133647D02*
X1132435D01*
G01X1137584D02*
X1136372D01*
G01X1141521D02*
X1140309D01*
G01X1145458D02*
X1144246D01*
G01X1144227Y659740D02*
X1145477D01*
G01X1140290D02*
X1141540D01*
G01X1136353D02*
X1137603D01*
G01X1132416D02*
X1133666D01*
G01X1128479D02*
X1129729D01*
G01X1124542D02*
X1125792D01*
G01X1120605D02*
X1121855D01*
G01X1116668D02*
X1117918D01*
G01X1112731D02*
X1113981D01*
G01X1108794D02*
X1110044D01*
G01X1105285Y659150D02*
X1440324D01*
G01X1144296Y658264D02*
X1145407D01*
G01X1136422D02*
X1137533D01*
G01X1128548D02*
X1129659D01*
G01X1120674D02*
X1121785D01*
G01X1112800D02*
X1113911D01*
G01X1103710Y657575D02*
X1387969D01*
G01X1144296Y657280D02*
X1145407D01*
G01X1136422D02*
X1137533D01*
G01X1128548D02*
X1129659D01*
G01X1120674D02*
X1121785D01*
G01X1112800D02*
X1113911D01*
G01X1144278Y656830D02*
X1145426D01*
G01X1136404D02*
X1137552D01*
G01X1128530D02*
X1129678D01*
G01X1120656D02*
X1121804D01*
G01X1112782D02*
X1113930D01*
G01X1113920Y656563D02*
X1112791D01*
G01X1121794D02*
X1120665D01*
G01X1129669D02*
X1128539D01*
G01X1137543D02*
X1136413D01*
G01X1145417D02*
X1144287D01*
G01X1101151Y655705D02*
X1105954D01*
G01X1113935Y655043D02*
X1112777D01*
G01X1121809D02*
X1120651D01*
G01X1129683D02*
X1128525D01*
G01X1137557D02*
X1136399D01*
G01X1145431D02*
X1144273D01*
G01X1144282Y654776D02*
X1145422D01*
G01X1136408D02*
X1137548D01*
G01X1128534D02*
X1129674D01*
G01X1120660D02*
X1121800D01*
G01X1112786D02*
X1113926D01*
G01X1144263Y654327D02*
X1145440D01*
G01X1140326D02*
X1141503D01*
G01X1136389D02*
X1137566D01*
G01X1132452D02*
X1133629D01*
G01X1128515D02*
X1129692D01*
G01X1124578D02*
X1125755D01*
G01X1120641D02*
X1121818D01*
G01X1116704D02*
X1117881D01*
G01X1112767D02*
X1113944D01*
G01X1108830D02*
X1110007D01*
G01X1105088Y653343D02*
X1101151D01*
G01X1110007D02*
X1108830D01*
G01X1113944D02*
X1112767D01*
G01X1117881D02*
X1116704D01*
G01X1121818D02*
X1120641D01*
G01X1125755D02*
X1124578D01*
G01X1129692D02*
X1128515D01*
G01X1133629D02*
X1132452D01*
G01X1137566D02*
X1136389D01*
G01X1141503D02*
X1140326D01*
G01X1145440D02*
X1144263D01*
G01X1109989Y652893D02*
X1108849D01*
G01X1117863D02*
X1116723D01*
G01X1125737D02*
X1124597D01*
G01X1133611D02*
X1132471D01*
G01X1141485D02*
X1140345D01*
G01X1140336Y652626D02*
X1141494D01*
G01X1132462D02*
X1133620D01*
G01X1124588D02*
X1125746D01*
G01X1116714D02*
X1117872D01*
G01X1108840D02*
X1109998D01*
G01X1105482Y652161D02*
X1097608D01*
G01X1145445Y659150D02*
X1145458Y659810D01*
G01X1145456Y660738D02*
X1145425Y659150D01*
G01X1145480Y664735D02*
X1145505Y666236D01*
G01X1145487D02*
X1145477Y665645D01*
G01X1145431Y670342D02*
X1145426Y668555D01*
G01X1145417Y668823D02*
X1145422Y670610D01*
G01X1145440Y654327D02*
Y653343D01*
G01Y672043D02*
Y671059D01*
G01X1145285Y658264D02*
Y657280D01*
G01Y668106D02*
Y667122D01*
G01X1145426Y656830D02*
X1145431Y655043D01*
G01X1145422Y654776D02*
X1145417Y656563D01*
G01X1145505Y659150D02*
X1145480Y660650D01*
G01X1145477Y659740D02*
X1145487Y659150D01*
G01X1145458Y665575D02*
X1145445Y666236D01*
G01X1145425D02*
X1145456Y664647D01*
G01X1144248D02*
X1144279Y666236D01*
G01X1144259D02*
X1144246Y665575D01*
G01X1141508Y659150D02*
X1141521Y659810D01*
G01X1141519Y660738D02*
X1141488Y659150D01*
G01X1140311Y664647D02*
X1140342Y666236D01*
G01X1140322D02*
X1140309Y665575D01*
G01X1137571Y659150D02*
X1137584Y659810D01*
G01X1137581Y660738D02*
X1137551Y659150D01*
G01X1136374Y664647D02*
X1136405Y666236D01*
G01X1136385D02*
X1136372Y665575D01*
G01X1133634Y659150D02*
X1133647Y659810D01*
G01X1133644Y660738D02*
X1133614Y659150D01*
G01X1132437Y664647D02*
X1132468Y666236D01*
G01X1144217Y659150D02*
X1144227Y659740D01*
G01X1144224Y660650D02*
X1144199Y659150D01*
G01X1141543Y664735D02*
X1141568Y666236D01*
G01X1141550D02*
X1141540Y665645D01*
G01X1140280Y659150D02*
X1140290Y659740D01*
G01X1140287Y660650D02*
X1140262Y659150D01*
G01X1137606Y664735D02*
X1137631Y666236D01*
G01X1137613D02*
X1137603Y665645D01*
G01X1136343Y659150D02*
X1136353Y659740D01*
G01X1136350Y660650D02*
X1136325Y659150D01*
G01X1133669Y664735D02*
X1133694Y666236D01*
G01X1133676D02*
X1133666Y665645D01*
G01X1132406Y659150D02*
X1132416Y659740D01*
G01X1132413Y660650D02*
X1132388Y659150D01*
G01X1144287Y656563D02*
X1144282Y654776D01*
G01X1144273Y655043D02*
X1144278Y656830D01*
G01X1140350Y674279D02*
X1140345Y672492D01*
G01X1140336Y672760D02*
X1140341Y674547D01*
G01X1137557Y670342D02*
X1137552Y668555D01*
G01X1137543Y668823D02*
X1137548Y670610D01*
G01X1136413Y656563D02*
X1136408Y654776D01*
G01X1136399Y655043D02*
X1136404Y656830D01*
G01X1132476Y674279D02*
X1132471Y672492D01*
G01X1132462Y672760D02*
X1132467Y674547D01*
G01X1144419Y658264D02*
Y657280D01*
G01Y667122D02*
Y668106D01*
G01X1144263Y653343D02*
Y654327D01*
G01Y671059D02*
Y672043D01*
G01X1141503Y653343D02*
Y654327D01*
G01Y671059D02*
Y672043D01*
G01X1141348Y675980D02*
Y674996D01*
G01X1140482D02*
Y675980D01*
G01X1140326Y654327D02*
Y653343D01*
G01Y672043D02*
Y671059D01*
G01X1139970Y682772D02*
Y677161D01*
G01X1137566Y654327D02*
Y653343D01*
G01Y672043D02*
Y671059D01*
G01X1137411Y658264D02*
Y657280D01*
G01Y668106D02*
Y667122D01*
G01X1136545Y658264D02*
Y657280D01*
G01Y667122D02*
Y668106D01*
G01X1136389Y653343D02*
Y654327D01*
G01Y671059D02*
Y672043D01*
G01X1134970Y682772D02*
Y677161D01*
G01X1133629Y653343D02*
Y654327D01*
G01Y671059D02*
Y672043D01*
G01X1133474Y675980D02*
Y674996D01*
G01X1132608D02*
Y675980D01*
G01X1132452Y654327D02*
Y653343D01*
G01Y672043D02*
Y671059D01*
G01X1144282Y670610D02*
X1144287Y668823D01*
G01X1144278Y668555D02*
X1144273Y670342D01*
G01X1141489Y674547D02*
X1141494Y672760D01*
G01X1141485Y672492D02*
X1141480Y674279D01*
G01X1137552Y656830D02*
X1137557Y655043D01*
G01X1137548Y654776D02*
X1137543Y656563D01*
G01X1136408Y670610D02*
X1136413Y668823D01*
G01X1136404Y668555D02*
X1136399Y670342D01*
G01X1133615Y674547D02*
X1133620Y672760D01*
G01X1133611Y672492D02*
X1133606Y674279D01*
G01X1144227Y665645D02*
X1144217Y666236D01*
G01X1144199D02*
X1144224Y664735D01*
G01X1141568Y659150D02*
X1141543Y660650D01*
G01X1141540Y659740D02*
X1141550Y659150D01*
G01X1140290Y665645D02*
X1140280Y666236D01*
G01X1140262D02*
X1140287Y664735D01*
G01X1137631Y659150D02*
X1137606Y660650D01*
G01X1137603Y659740D02*
X1137613Y659150D01*
G01X1136353Y665645D02*
X1136343Y666236D01*
G01X1136325D02*
X1136350Y664735D01*
G01X1133694Y659150D02*
X1133669Y660650D01*
G01X1133666Y659740D02*
X1133676Y659150D01*
G01X1132416Y665645D02*
X1132406Y666236D01*
G01X1132388D02*
X1132413Y664735D01*
G01X1144279Y659150D02*
X1144248Y660738D01*
G01X1144246Y659810D02*
X1144259Y659150D01*
G01X1141521Y665575D02*
X1141508Y666236D01*
G01X1141488D02*
X1141519Y664647D01*
G01X1140342Y659150D02*
X1140311Y660738D01*
G01X1140309Y659810D02*
X1140322Y659150D01*
G01X1137584Y665575D02*
X1137571Y666236D01*
G01X1137551D02*
X1137581Y664647D01*
G01X1136405Y659150D02*
X1136374Y660738D01*
G01X1136372Y659810D02*
X1136385Y659150D01*
G01X1133647Y665575D02*
X1133634Y666236D01*
G01X1133614D02*
X1133644Y664647D01*
G01X1132468Y659150D02*
X1132437Y660738D01*
G01X1132435Y659810D02*
X1132448Y659150D01*
G01Y666236D02*
X1132435Y665575D01*
G01X1129697Y659150D02*
X1129710Y659810D01*
G01X1129707Y660738D02*
X1129677Y659150D01*
G01X1128500Y664647D02*
X1128531Y666236D01*
G01X1128511D02*
X1128498Y665575D01*
G01X1125760Y659150D02*
X1125773Y659810D01*
G01X1125770Y660738D02*
X1125740Y659150D01*
G01X1124563Y664647D02*
X1124594Y666236D01*
G01X1124574D02*
X1124561Y665575D01*
G01X1121823Y659150D02*
X1121836Y659810D01*
G01X1121833Y660738D02*
X1121803Y659150D01*
G01X1120626Y664647D02*
X1120657Y666236D01*
G01X1120637D02*
X1120624Y665575D01*
G01X1129731Y664735D02*
X1129757Y666236D01*
G01X1129739D02*
X1129729Y665645D01*
G01X1128469Y659150D02*
X1128479Y659740D01*
G01X1128476Y660650D02*
X1128451Y659150D01*
G01X1125794Y664735D02*
X1125820Y666236D01*
G01X1125802D02*
X1125792Y665645D01*
G01X1124532Y659150D02*
X1124542Y659740D01*
G01X1124539Y660650D02*
X1124514Y659150D01*
G01X1121857Y664735D02*
X1121883Y666236D01*
G01X1121865D02*
X1121855Y665645D01*
G01X1120595Y659150D02*
X1120605Y659740D01*
G01X1120602Y660650D02*
X1120577Y659150D01*
G01X1129683Y670342D02*
X1129678Y668555D01*
G01X1129669Y668823D02*
X1129674Y670610D01*
G01X1128539Y656563D02*
X1128534Y654776D01*
G01X1128525Y655043D02*
X1128530Y656830D01*
G01X1124602Y674279D02*
X1124597Y672492D01*
G01X1124588Y672760D02*
X1124593Y674547D01*
G01X1121809Y670342D02*
X1121804Y668555D01*
G01X1121794Y668823D02*
X1121800Y670610D01*
G01X1120665Y656563D02*
X1120660Y654776D01*
G01X1120651Y655043D02*
X1120656Y656830D01*
G01X1129692Y654327D02*
Y653343D01*
G01Y672043D02*
Y671059D01*
G01X1129537Y658264D02*
Y657280D01*
G01Y668106D02*
Y667122D01*
G01X1128671Y658264D02*
Y657280D01*
G01Y667122D02*
Y668106D01*
G01X1128515Y653343D02*
Y654327D01*
G01Y671059D02*
Y672043D01*
G01X1125755Y653343D02*
Y654327D01*
G01Y671059D02*
Y672043D01*
G01X1125600Y675980D02*
Y674996D01*
G01X1124734D02*
Y675980D01*
G01X1124578Y654327D02*
Y653343D01*
G01Y672043D02*
Y671059D01*
G01X1121818Y654327D02*
Y653343D01*
G01Y672043D02*
Y671059D01*
G01X1121663Y658264D02*
Y657280D01*
G01Y668106D02*
Y667122D01*
G01X1120797Y658264D02*
Y657280D01*
G01Y667122D02*
Y668106D01*
G01X1120641Y653343D02*
Y654327D01*
G01Y671059D02*
Y672043D01*
G01X1119065Y682772D02*
Y677161D01*
G01X1129678Y656830D02*
X1129683Y655043D01*
G01X1129674Y654776D02*
X1129669Y656563D01*
G01X1128534Y670610D02*
X1128539Y668823D01*
G01X1128530Y668555D02*
X1128525Y670342D01*
G01X1125741Y674547D02*
X1125746Y672760D01*
G01X1125737Y672492D02*
X1125731Y674279D01*
G01X1121804Y656830D02*
X1121809Y655043D01*
G01X1121800Y654776D02*
X1121794Y656563D01*
G01X1120660Y670610D02*
X1120665Y668823D01*
G01X1120656Y668555D02*
X1120651Y670342D01*
G01X1129757Y659150D02*
X1129731Y660650D01*
G01X1129729Y659740D02*
X1129739Y659150D01*
G01X1128479Y665645D02*
X1128469Y666236D01*
G01X1128451D02*
X1128476Y664735D01*
G01X1125820Y659150D02*
X1125794Y660650D01*
G01X1125792Y659740D02*
X1125802Y659150D01*
G01X1124542Y665645D02*
X1124532Y666236D01*
G01X1124514D02*
X1124539Y664735D01*
G01X1121883Y659150D02*
X1121857Y660650D01*
G01X1121855Y659740D02*
X1121865Y659150D01*
G01X1120605Y665645D02*
X1120595Y666236D01*
G01X1120577D02*
X1120602Y664735D01*
G01X1129710Y665575D02*
X1129697Y666236D01*
G01X1129677D02*
X1129707Y664647D01*
G01X1128531Y659150D02*
X1128500Y660738D01*
G01X1128498Y659810D02*
X1128511Y659150D01*
G01X1125773Y665575D02*
X1125760Y666236D01*
G01X1125740D02*
X1125770Y664647D01*
G01X1124594Y659150D02*
X1124563Y660738D01*
G01X1124561Y659810D02*
X1124574Y659150D01*
G01X1121836Y665575D02*
X1121823Y666236D01*
G01X1121803D02*
X1121833Y664647D01*
G01X1120657Y659150D02*
X1120626Y660738D01*
G01X1120624Y659810D02*
X1120637Y659150D01*
G01X1117886D02*
X1117899Y659810D01*
G01X1117896Y660738D02*
X1117866Y659150D01*
G01X1116689Y664647D02*
X1116720Y666236D01*
G01X1116700D02*
X1116687Y665575D01*
G01X1113949Y659150D02*
X1113962Y659810D01*
G01X1113959Y660738D02*
X1113929Y659150D01*
G01X1112752Y664647D02*
X1112783Y666236D01*
G01X1112763D02*
X1112750Y665575D01*
G01X1110012Y659150D02*
X1110025Y659810D01*
G01X1110022Y660738D02*
X1109992Y659150D01*
G01X1108815Y664647D02*
X1108846Y666236D01*
G01X1108826D02*
X1108813Y665575D01*
G01X1117920Y664735D02*
X1117946Y666236D01*
G01X1117928D02*
X1117918Y665645D01*
G01X1116658Y659150D02*
X1116668Y659740D01*
G01X1116665Y660650D02*
X1116640Y659150D01*
G01X1113983Y664735D02*
X1114009Y666236D01*
G01X1113991D02*
X1113981Y665645D01*
G01X1112721Y659150D02*
X1112731Y659740D01*
G01X1112728Y660650D02*
X1112703Y659150D01*
G01X1110046Y664735D02*
X1110072Y666236D01*
G01X1110054D02*
X1110044Y665645D01*
G01X1108784Y659150D02*
X1108794Y659740D01*
G01X1108791Y660650D02*
X1108766Y659150D01*
G01X1116728Y674279D02*
X1116723Y672492D01*
G01X1116714Y672760D02*
X1116719Y674547D01*
G01X1113935Y670342D02*
X1113930Y668555D01*
G01X1113920Y668823D02*
X1113926Y670610D01*
G01X1112791Y656563D02*
X1112786Y654776D01*
G01X1112777Y655043D02*
X1112782Y656830D01*
G01X1108854Y674279D02*
X1108849Y672492D01*
G01X1108840Y672760D02*
X1108844Y674547D01*
G01X1117881Y653343D02*
Y654327D01*
G01Y671059D02*
Y672043D01*
G01X1117726Y675980D02*
Y674996D01*
G01X1116860D02*
Y675980D01*
G01X1116704Y654327D02*
Y653343D01*
G01Y672043D02*
Y671059D01*
G01X1114065Y682772D02*
Y677161D01*
G01X1113944Y654327D02*
Y653343D01*
G01Y672043D02*
Y671059D01*
G01X1113789Y658264D02*
Y657280D01*
G01Y668106D02*
Y667122D01*
G01X1112923Y658264D02*
Y657280D01*
G01Y667122D02*
Y668106D01*
G01X1112767Y653343D02*
Y654327D01*
G01Y671059D02*
Y672043D01*
G01X1110007Y653343D02*
Y654327D01*
G01Y671059D02*
Y672043D01*
G01X1109852Y675980D02*
Y674996D01*
G01X1108986D02*
Y675980D01*
G01X1108830Y654327D02*
Y653343D01*
G01Y672043D02*
Y671059D01*
G01X1106072Y665065D02*
Y660320D01*
G01X1117867Y674547D02*
X1117872Y672760D01*
G01X1117863Y672492D02*
X1117857Y674279D01*
G01X1113930Y656830D02*
X1113935Y655043D01*
G01X1113926Y654776D02*
X1113920Y656563D01*
G01X1112786Y670610D02*
X1112791Y668823D01*
G01X1112781Y668555D02*
X1112777Y670342D01*
G01X1109993Y674547D02*
X1109998Y672760D01*
G01X1109989Y672492D02*
X1109983Y674279D01*
G01X1117946Y659150D02*
X1117920Y660650D01*
G01X1117918Y659740D02*
X1117928Y659150D01*
G01X1116668Y665645D02*
X1116658Y666236D01*
G01X1116640D02*
X1116665Y664735D01*
G01X1114009Y659150D02*
X1113983Y660650D01*
G01X1113981Y659740D02*
X1113991Y659150D01*
G01X1112731Y665645D02*
X1112721Y666236D01*
G01X1112703D02*
X1112728Y664735D01*
G01X1110072Y659150D02*
X1110046Y660650D01*
G01X1110044Y659740D02*
X1110054Y659150D01*
G01X1108794Y665645D02*
X1108784Y666236D01*
G01X1108766D02*
X1108791Y664735D01*
G01X1117899Y665575D02*
X1117886Y666236D01*
G01X1117866D02*
X1117896Y664647D01*
G01X1116720Y659150D02*
X1116689Y660738D01*
G01X1116687Y659810D02*
X1116700Y659150D01*
G01X1113962Y665575D02*
X1113949Y666236D01*
G01X1113929D02*
X1113959Y664647D01*
G01X1112783Y659150D02*
X1112752Y660738D01*
G01X1112750Y659810D02*
X1112763Y659150D01*
G01X1110025Y665575D02*
X1110012Y666236D01*
G01X1109992D02*
X1110022Y664647D01*
G01X1108846Y659150D02*
X1108815Y660738D01*
G01X1108813Y659810D02*
X1108826Y659150D01*
G01X1105954Y674012D02*
Y669681D01*
G01X1105482Y673224D02*
Y677181D01*
G01X1105285Y659150D02*
Y666236D01*
G01X1105088Y669681D02*
Y672043D01*
G01Y655705D02*
Y653343D01*
G01X1103710Y667811D02*
Y657575D01*
G01X1101151Y669681D02*
Y674012D01*
G01X1098592Y664454D02*
Y665065D01*
G01Y660320D02*
Y660932D01*
G01X1184443Y-259766D02*
Y-349896D01*
G01X1183343Y-305084D02*
X1596998D01*
G01X1203475Y272686D02*
X1206231D01*
G01X1199538D02*
X1202294D01*
G01X1195601D02*
X1198357D01*
G01X1191664D02*
X1194420D01*
G01X1187727D02*
X1190483D01*
G01X1183790D02*
X1186546D01*
G01X1179853D02*
X1182609D01*
G01X1175916D02*
X1178672D01*
G01X1171979D02*
X1174735D01*
G01X1168042D02*
X1170798D01*
G01X1164105D02*
X1166861D01*
G01X1160168D02*
X1162924D01*
G01X1156231D02*
X1158987D01*
G01X1152294D02*
X1155050D01*
G01X1148357D02*
X1151113D01*
G01Y256150D02*
X1148357D01*
G01X1155050D02*
X1152294D01*
G01X1158987D02*
X1156231D01*
G01X1162924D02*
X1160168D01*
G01X1166861D02*
X1164105D01*
G01X1170798D02*
X1168042D01*
G01X1174735D02*
X1171979D01*
G01X1178672D02*
X1175916D01*
G01X1182609D02*
X1179853D01*
G01X1186546D02*
X1183790D01*
G01X1190483D02*
X1187727D01*
G01X1194420D02*
X1191664D01*
G01X1198357D02*
X1195601D01*
G01X1202294D02*
X1199538D01*
G01X1206231D02*
X1203475D01*
G01X1206231Y272686D02*
Y256150D01*
G01X1203475D02*
Y272686D01*
G01X1202294D02*
Y256150D01*
G01X1199538D02*
Y272686D01*
G01X1198357D02*
Y256150D01*
G01X1195601D02*
Y272686D01*
G01X1194420D02*
Y256150D01*
G01X1191664D02*
Y272686D01*
G01X1190483D02*
Y256150D01*
G01X1187727D02*
Y272686D01*
G01X1186546D02*
Y256150D01*
G01X1183790D02*
Y272686D01*
G01X1182609D02*
Y256150D01*
G01X1179853D02*
Y272686D01*
G01X1178672D02*
Y256150D01*
G01X1175916D02*
Y272686D01*
G01X1174735D02*
Y256150D01*
G01X1171979D02*
Y272686D01*
G01X1170798D02*
Y256150D01*
G01X1168042D02*
Y272686D01*
G01X1166861D02*
Y256150D01*
G01X1164105D02*
Y272686D01*
G01X1162924D02*
Y256150D01*
G01X1160168D02*
Y272686D01*
G01X1158987D02*
Y256150D01*
G01X1156231D02*
Y272686D01*
G01X1155050D02*
Y256150D01*
G01X1152294D02*
Y272686D01*
G01X1151113D02*
Y256150D01*
G01X1148357D02*
Y272686D01*
G01X1147176D02*
Y256150D01*
G01X1150167Y589858D02*
X1147411D01*
G01X1154104D02*
X1151348D01*
G01X1158041D02*
X1155285D01*
G01X1161978D02*
X1159222D01*
G01X1165915D02*
X1163159D01*
G01X1169852D02*
X1167096D01*
G01X1173789D02*
X1171033D01*
G01X1177726D02*
X1174970D01*
G01X1181663D02*
X1178907D01*
G01X1185600D02*
X1182844D01*
G01X1189537D02*
X1186781D01*
G01X1193474D02*
X1190718D01*
G01X1197411D02*
X1194655D01*
G01X1201348D02*
X1198592D01*
G01X1205285D02*
X1202529D01*
G01X1209222D02*
X1206466D01*
G01D02*
Y606394D01*
G01X1205285D02*
Y589858D01*
G01X1202529D02*
Y606394D01*
G01X1201348D02*
Y589858D01*
G01X1198592D02*
Y606394D01*
G01X1197411D02*
Y589858D01*
G01X1194655D02*
Y606394D01*
G01X1193474D02*
Y589858D01*
G01X1190718D02*
Y606394D01*
G01X1189537D02*
Y589858D01*
G01X1186781D02*
Y606394D01*
G01X1185600D02*
Y589858D01*
G01X1182844D02*
Y606394D01*
G01X1181663D02*
Y589858D01*
G01X1178907D02*
Y606394D01*
G01X1177726D02*
Y589858D01*
G01X1174970D02*
Y606394D01*
G01X1173789D02*
Y589858D01*
G01X1171033D02*
Y606394D01*
G01X1169852D02*
Y589858D01*
G01X1167096D02*
Y606394D01*
G01X1165915D02*
Y589858D01*
G01X1163159D02*
Y606394D01*
G01X1161978D02*
Y589858D01*
G01X1159222D02*
Y606394D01*
G01X1158041D02*
Y589858D01*
G01X1155285D02*
Y606394D01*
G01X1154104D02*
Y589858D01*
G01X1151348D02*
Y606394D01*
G01X1150167D02*
Y589858D01*
G01X1147411D02*
Y606394D01*
G01X1146230D02*
Y589858D01*
G01X1203342Y651106D02*
X1204472D01*
G01X1195468D02*
X1196598D01*
G01X1187594D02*
X1188724D01*
G01X1179720D02*
X1180850D01*
G01X1171846D02*
X1172976D01*
G01X1163972D02*
X1165102D01*
G01X1156098D02*
X1157228D01*
G01X1148224D02*
X1149354D01*
G01X1149363Y650839D02*
X1148215D01*
G01X1157237D02*
X1156089D01*
G01X1165111D02*
X1163963D01*
G01X1172985D02*
X1171837D01*
G01X1180859D02*
X1179711D01*
G01X1188733D02*
X1187585D01*
G01X1196607D02*
X1195459D01*
G01X1204481D02*
X1203333D01*
G01X1203352Y650390D02*
X1204462D01*
G01X1195478D02*
X1196588D01*
G01X1187604D02*
X1188714D01*
G01X1179730D02*
X1180840D01*
G01X1171856D02*
X1172966D01*
G01X1163981D02*
X1165092D01*
G01X1156107D02*
X1157218D01*
G01X1148233D02*
X1149344D01*
G01X1203352Y649406D02*
X1204462D01*
G01X1195478D02*
X1196588D01*
G01X1187604D02*
X1188714D01*
G01X1179730D02*
X1180840D01*
G01X1171856D02*
X1172966D01*
G01X1163981D02*
X1165092D01*
G01X1156107D02*
X1157218D01*
G01X1148233D02*
X1149344D01*
G01X1206466Y606394D02*
X1209222D01*
G01X1202529D02*
X1205285D01*
G01X1198592D02*
X1201348D01*
G01X1194655D02*
X1197411D01*
G01X1190718D02*
X1193474D01*
G01X1186781D02*
X1189537D01*
G01X1182844D02*
X1185600D01*
G01X1178907D02*
X1181663D01*
G01X1174970D02*
X1177726D01*
G01X1171033D02*
X1173789D01*
G01X1167096D02*
X1169852D01*
G01X1163159D02*
X1165915D01*
G01X1159222D02*
X1161978D01*
G01X1155285D02*
X1158041D01*
G01X1151348D02*
X1154104D01*
G01X1147411D02*
X1150167D01*
G01X1204486Y652626D02*
X1204481Y650839D01*
G01X1204472Y651106D02*
X1204477Y652893D01*
G01X1204340Y650390D02*
Y649406D01*
G01X1203474Y650390D02*
Y649406D01*
G01X1203337Y652893D02*
X1203342Y651106D01*
G01X1203333Y650839D02*
X1203328Y652626D01*
G01X1196612D02*
X1196607Y650839D01*
G01X1196598Y651106D02*
X1196603Y652893D01*
G01X1188738Y652626D02*
X1188733Y650839D01*
G01X1188724Y651106D02*
X1188729Y652893D01*
G01X1196466Y650390D02*
Y649406D01*
G01X1195600Y650390D02*
Y649406D01*
G01X1188592Y650390D02*
Y649406D01*
G01X1187726Y650390D02*
Y649406D01*
G01X1195463Y652893D02*
X1195468Y651106D01*
G01X1195459Y650839D02*
X1195454Y652626D01*
G01X1187589Y652893D02*
X1187594Y651106D01*
G01X1187585Y650839D02*
X1187580Y652626D01*
G01X1180864D02*
X1180859Y650839D01*
G01X1180850Y651106D02*
X1180855Y652893D01*
G01X1172990Y652626D02*
X1172985Y650839D01*
G01X1172976Y651106D02*
X1172981Y652893D01*
G01X1180718Y650390D02*
Y649406D01*
G01X1179852Y650390D02*
Y649406D01*
G01X1172844Y650390D02*
Y649406D01*
G01X1171978Y650390D02*
Y649406D01*
G01X1179715Y652893D02*
X1179720Y651106D01*
G01X1179711Y650839D02*
X1179706Y652626D01*
G01X1171841Y652893D02*
X1171846Y651106D01*
G01X1171837Y650839D02*
X1171832Y652626D01*
G01X1165116D02*
X1165111Y650839D01*
G01X1165102Y651106D02*
X1165107Y652893D01*
G01X1164970Y650390D02*
Y649406D01*
G01X1164104Y650390D02*
Y649406D01*
G01X1163967Y652893D02*
X1163972Y651106D01*
G01X1163963Y650839D02*
X1163958Y652626D01*
G01X1157242D02*
X1157237Y650839D01*
G01X1157228Y651106D02*
X1157233Y652893D01*
G01X1149368Y652626D02*
X1149363Y650839D01*
G01X1149354Y651106D02*
X1149359Y652893D01*
G01X1157096Y650390D02*
Y649406D01*
G01X1156230Y650390D02*
Y649406D01*
G01X1149222Y650390D02*
Y649406D01*
G01X1148356Y650390D02*
Y649406D01*
G01X1156093Y652893D02*
X1156098Y651106D01*
G01X1156089Y650839D02*
X1156084Y652626D01*
G01X1148219Y652893D02*
X1148224Y651106D01*
G01X1148215Y650839D02*
X1148210Y652626D01*
G01X1229498Y691039D02*
X1198002D01*
G01X1237372Y683165D02*
X1198002D01*
G01X1176781Y682772D02*
X1160876D01*
G01X1197687D02*
X1181781D01*
G01X1218592D02*
X1202687D01*
G01X1149344Y675980D02*
X1148233D01*
G01X1157218D02*
X1156107D01*
G01X1165092D02*
X1163981D01*
G01X1172966D02*
X1171856D01*
G01X1180840D02*
X1179730D01*
G01X1188714D02*
X1187604D01*
G01X1196588D02*
X1195478D01*
G01X1204462D02*
X1203352D01*
G01X1149344Y674996D02*
X1148233D01*
G01X1157218D02*
X1156107D01*
G01X1165092D02*
X1163981D01*
G01X1172966D02*
X1171856D01*
G01X1180840D02*
X1179730D01*
G01X1188714D02*
X1187604D01*
G01X1196588D02*
X1195478D01*
G01X1204462D02*
X1203352D01*
G01X1203333Y674547D02*
X1204481D01*
G01X1195459D02*
X1196607D01*
G01X1187585D02*
X1188733D01*
G01X1179711D02*
X1180859D01*
G01X1171837D02*
X1172985D01*
G01X1163963D02*
X1165111D01*
G01X1156089D02*
X1157237D01*
G01X1148215D02*
X1149363D01*
G01X1149354Y674279D02*
X1148224D01*
G01X1157228D02*
X1156098D01*
G01X1165102D02*
X1163972D01*
G01X1172976D02*
X1171846D01*
G01X1180850D02*
X1179720D01*
G01X1188724D02*
X1187594D01*
G01X1196598D02*
X1195468D01*
G01X1204472D02*
X1203342D01*
G01X1149368Y672760D02*
X1148210D01*
G01X1157242D02*
X1156084D01*
G01X1165116D02*
X1163958D01*
G01X1172990D02*
X1171832D01*
G01X1180864D02*
X1179706D01*
G01X1188738D02*
X1187580D01*
G01X1196612D02*
X1195454D01*
G01X1204486D02*
X1203328D01*
G01X1203337Y672492D02*
X1204477D01*
G01X1195463D02*
X1196603D01*
G01X1187589D02*
X1188729D01*
G01X1179715D02*
X1180855D01*
G01X1171841D02*
X1172981D01*
G01X1163967D02*
X1165107D01*
G01X1156093D02*
X1157233D01*
G01X1148219D02*
X1149359D01*
G01X1149377Y672043D02*
X1148200D01*
G01X1153314D02*
X1152137D01*
G01X1157251D02*
X1156074D01*
G01X1161188D02*
X1160011D01*
G01X1165125D02*
X1163948D01*
G01X1169062D02*
X1167885D01*
G01X1172999D02*
X1171822D01*
G01X1176936D02*
X1175759D01*
G01X1180873D02*
X1179696D01*
G01X1184810D02*
X1183633D01*
G01X1188747D02*
X1187570D01*
G01X1192684D02*
X1191507D01*
G01X1196621D02*
X1195444D01*
G01X1200558D02*
X1199381D01*
G01X1204495D02*
X1203319D01*
G01X1149377Y671059D02*
X1148200D01*
G01X1153314D02*
X1152137D01*
G01X1157251D02*
X1156074D01*
G01X1161188D02*
X1160011D01*
G01X1165125D02*
X1163948D01*
G01X1169062D02*
X1167885D01*
G01X1172999D02*
X1171822D01*
G01X1176936D02*
X1175759D01*
G01X1180873D02*
X1179696D01*
G01X1184810D02*
X1183633D01*
G01X1188747D02*
X1187570D01*
G01X1192684D02*
X1191507D01*
G01X1196621D02*
X1195444D01*
G01X1200558D02*
X1199381D01*
G01X1204495D02*
X1203319D01*
G01X1153296Y670610D02*
X1152156D01*
G01X1161170D02*
X1160030D01*
G01X1169044D02*
X1167904D01*
G01X1176918D02*
X1175778D01*
G01X1184792D02*
X1183652D01*
G01X1192666D02*
X1191526D01*
G01X1200540D02*
X1199400D01*
G01X1199391Y670342D02*
X1200549D01*
G01X1191517D02*
X1192675D01*
G01X1183643D02*
X1184801D01*
G01X1175769D02*
X1176927D01*
G01X1167895D02*
X1169053D01*
G01X1160021D02*
X1161179D01*
G01X1152147D02*
X1153305D01*
G01X1199405Y668823D02*
X1200535D01*
G01X1191531D02*
X1192661D01*
G01X1183657D02*
X1184787D01*
G01X1175783D02*
X1176913D01*
G01X1167909D02*
X1169039D01*
G01X1160035D02*
X1161165D01*
G01X1152161D02*
X1153291D01*
G01X1153300Y668555D02*
X1152152D01*
G01X1161174D02*
X1160026D01*
G01X1169048D02*
X1167900D01*
G01X1176922D02*
X1175774D01*
G01X1184796D02*
X1183648D01*
G01X1192670D02*
X1191522D01*
G01X1200544D02*
X1199396D01*
G01X1153281Y668106D02*
X1152170D01*
G01X1161155D02*
X1160044D01*
G01X1169029D02*
X1167919D01*
G01X1176903D02*
X1175793D01*
G01X1184777D02*
X1183667D01*
G01X1192651D02*
X1191541D01*
G01X1200525D02*
X1199415D01*
G01X1153281Y667122D02*
X1152170D01*
G01X1161155D02*
X1160044D01*
G01X1169029D02*
X1167919D01*
G01X1176903D02*
X1175793D01*
G01X1184777D02*
X1183667D01*
G01X1192651D02*
X1191541D01*
G01X1200525D02*
X1199415D01*
G01X1149414Y665645D02*
X1148164D01*
G01X1153351D02*
X1152101D01*
G01X1157288D02*
X1156038D01*
G01X1161225D02*
X1159975D01*
G01X1165162D02*
X1163912D01*
G01X1169099D02*
X1167849D01*
G01X1173036D02*
X1171786D01*
G01X1176973D02*
X1175723D01*
G01X1180910D02*
X1179660D01*
G01X1184847D02*
X1183597D01*
G01X1188784D02*
X1187534D01*
G01X1192721D02*
X1191471D01*
G01X1196658D02*
X1195408D01*
G01X1200595D02*
X1199345D01*
G01X1204532D02*
X1203282D01*
G01X1203301Y665575D02*
X1204513D01*
G01X1199364D02*
X1200576D01*
G01X1195427D02*
X1196639D01*
G01X1191490D02*
X1192702D01*
G01X1187553D02*
X1188765D01*
G01X1183616D02*
X1184828D01*
G01X1179679D02*
X1180891D01*
G01X1175742D02*
X1176954D01*
G01X1171805D02*
X1173017D01*
G01X1167868D02*
X1169080D01*
G01X1163931D02*
X1165143D01*
G01X1159994D02*
X1161206D01*
G01X1156057D02*
X1157269D01*
G01X1152120D02*
X1153332D01*
G01X1148183D02*
X1149395D01*
G01X1149404Y665350D02*
X1148174D01*
G01X1153341D02*
X1152111D01*
G01X1157278D02*
X1156048D01*
G01X1161215D02*
X1159985D01*
G01X1165152D02*
X1163922D01*
G01X1169089D02*
X1167859D01*
G01X1173026D02*
X1171796D01*
G01X1176963D02*
X1175733D01*
G01X1180900D02*
X1179670D01*
G01X1184837D02*
X1183607D01*
G01X1188774D02*
X1187544D01*
G01X1192711D02*
X1191481D01*
G01X1196648D02*
X1195418D01*
G01X1200585D02*
X1199355D01*
G01X1204522D02*
X1203292D01*
G01X1203279Y664735D02*
X1204535D01*
G01X1199342D02*
X1200598D01*
G01X1195405D02*
X1196661D01*
G01X1191468D02*
X1192724D01*
G01X1187531D02*
X1188787D01*
G01X1183594D02*
X1184850D01*
G01X1179657D02*
X1180913D01*
G01X1175720D02*
X1176976D01*
G01X1171783D02*
X1173039D01*
G01X1167846D02*
X1169102D01*
G01X1163909D02*
X1165165D01*
G01X1159972D02*
X1161228D01*
G01X1156035D02*
X1157291D01*
G01X1152098D02*
X1153354D01*
G01X1148161D02*
X1149417D01*
G01X1149393Y664647D02*
X1148185D01*
G01X1153330D02*
X1152122D01*
G01X1157267D02*
X1156059D01*
G01X1161204D02*
X1159996D01*
G01X1165141D02*
X1163933D01*
G01X1169078D02*
X1167870D01*
G01X1173015D02*
X1171807D01*
G01X1176952D02*
X1175744D01*
G01X1180889D02*
X1179681D01*
G01X1184826D02*
X1183618D01*
G01X1188763D02*
X1187555D01*
G01X1192700D02*
X1191492D01*
G01X1196637D02*
X1195429D01*
G01X1200574D02*
X1199366D01*
G01X1204511D02*
X1203303D01*
G01X1149404Y664365D02*
X1148174D01*
G01X1153341D02*
X1152111D01*
G01X1157278D02*
X1156048D01*
G01X1161215D02*
X1159985D01*
G01X1165152D02*
X1163922D01*
G01X1169089D02*
X1167859D01*
G01X1173026D02*
X1171796D01*
G01X1176963D02*
X1175733D01*
G01X1180900D02*
X1179670D01*
G01X1184837D02*
X1183607D01*
G01X1188774D02*
X1187544D01*
G01X1192711D02*
X1191481D01*
G01X1196648D02*
X1195418D01*
G01X1200585D02*
X1199355D01*
G01X1204522D02*
X1203292D01*
G01Y661020D02*
X1204522D01*
G01X1199355D02*
X1200585D01*
G01X1195418D02*
X1196648D01*
G01X1191481D02*
X1192711D01*
G01X1187544D02*
X1188774D01*
G01X1183607D02*
X1184837D01*
G01X1179670D02*
X1180900D01*
G01X1175733D02*
X1176963D01*
G01X1171796D02*
X1173026D01*
G01X1167859D02*
X1169089D01*
G01X1163922D02*
X1165152D01*
G01X1159985D02*
X1161215D01*
G01X1156048D02*
X1157278D01*
G01X1152111D02*
X1153341D01*
G01X1148174D02*
X1149404D01*
G01X1203303Y660738D02*
X1204511D01*
G01X1199366D02*
X1200574D01*
G01X1195429D02*
X1196637D01*
G01X1191492D02*
X1192700D01*
G01X1187555D02*
X1188763D01*
G01X1183618D02*
X1184826D01*
G01X1179681D02*
X1180889D01*
G01X1175744D02*
X1176952D01*
G01X1171807D02*
X1173015D01*
G01X1167870D02*
X1169078D01*
G01X1163933D02*
X1165141D01*
G01X1159996D02*
X1161204D01*
G01X1156059D02*
X1157267D01*
G01X1152122D02*
X1153330D01*
G01X1148185D02*
X1149393D01*
G01X1149417Y660650D02*
X1148161D01*
G01X1153354D02*
X1152098D01*
G01X1157291D02*
X1156035D01*
G01X1161228D02*
X1159972D01*
G01X1165165D02*
X1163909D01*
G01X1169102D02*
X1167846D01*
G01X1173039D02*
X1171783D01*
G01X1176976D02*
X1175720D01*
G01X1180913D02*
X1179657D01*
G01X1184850D02*
X1183594D01*
G01X1188787D02*
X1187531D01*
G01X1192724D02*
X1191468D01*
G01X1196661D02*
X1195405D01*
G01X1200598D02*
X1199342D01*
G01X1204535D02*
X1203279D01*
G01X1203292Y660036D02*
X1204522D01*
G01X1199355D02*
X1200585D01*
G01X1195418D02*
X1196648D01*
G01X1191481D02*
X1192711D01*
G01X1187544D02*
X1188774D01*
G01X1183607D02*
X1184837D01*
G01X1179670D02*
X1180900D01*
G01X1175733D02*
X1176963D01*
G01X1171796D02*
X1173026D01*
G01X1167859D02*
X1169089D01*
G01X1163922D02*
X1165152D01*
G01X1159985D02*
X1161215D01*
G01X1156048D02*
X1157278D01*
G01X1152111D02*
X1153341D01*
G01X1148174D02*
X1149404D01*
G01X1149395Y659810D02*
X1148183D01*
G01X1153332D02*
X1152120D01*
G01X1157269D02*
X1156057D01*
G01X1161206D02*
X1159994D01*
G01X1165143D02*
X1163931D01*
G01X1169080D02*
X1167868D01*
G01X1173017D02*
X1171805D01*
G01X1176954D02*
X1175742D01*
G01X1180891D02*
X1179679D01*
G01X1184828D02*
X1183616D01*
G01X1188765D02*
X1187553D01*
G01X1192702D02*
X1191490D01*
G01X1196639D02*
X1195427D01*
G01X1200576D02*
X1199364D01*
G01X1204513D02*
X1203301D01*
G01X1203282Y659740D02*
X1204532D01*
G01X1199345D02*
X1200595D01*
G01X1195408D02*
X1196658D01*
G01X1191471D02*
X1192721D01*
G01X1187534D02*
X1188784D01*
G01X1183597D02*
X1184847D01*
G01X1179660D02*
X1180910D01*
G01X1175723D02*
X1176973D01*
G01X1171786D02*
X1173036D01*
G01X1167849D02*
X1169099D01*
G01X1163912D02*
X1165162D01*
G01X1159975D02*
X1161225D01*
G01X1156038D02*
X1157288D01*
G01X1152101D02*
X1153351D01*
G01X1148164D02*
X1149414D01*
G01X1199415Y658264D02*
X1200525D01*
G01X1191541D02*
X1192651D01*
G01X1183667D02*
X1184777D01*
G01X1175793D02*
X1176903D01*
G01X1167919D02*
X1169029D01*
G01X1160044D02*
X1161155D01*
G01X1152170D02*
X1153281D01*
G01X1199415Y657280D02*
X1200525D01*
G01X1191541D02*
X1192651D01*
G01X1183667D02*
X1184777D01*
G01X1175793D02*
X1176903D01*
G01X1167919D02*
X1169029D01*
G01X1160044D02*
X1161155D01*
G01X1152170D02*
X1153281D01*
G01X1199396Y656830D02*
X1200544D01*
G01X1191522D02*
X1192670D01*
G01X1183648D02*
X1184796D01*
G01X1175774D02*
X1176922D01*
G01X1167900D02*
X1169048D01*
G01X1160026D02*
X1161174D01*
G01X1152152D02*
X1153300D01*
G01X1153291Y656563D02*
X1152161D01*
G01X1161165D02*
X1160035D01*
G01X1169039D02*
X1167909D01*
G01X1176913D02*
X1175783D01*
G01X1184787D02*
X1183657D01*
G01X1192661D02*
X1191531D01*
G01X1200535D02*
X1199405D01*
G01X1153305Y655043D02*
X1152147D01*
G01X1161179D02*
X1160021D01*
G01X1169053D02*
X1167895D01*
G01X1176927D02*
X1175769D01*
G01X1184801D02*
X1183643D01*
G01X1192675D02*
X1191517D01*
G01X1200549D02*
X1199391D01*
G01X1199400Y654776D02*
X1200540D01*
G01X1191526D02*
X1192666D01*
G01X1183652D02*
X1184792D01*
G01X1175778D02*
X1176918D01*
G01X1167904D02*
X1169044D01*
G01X1160030D02*
X1161170D01*
G01X1152156D02*
X1153296D01*
G01X1203319Y654327D02*
X1204495D01*
G01X1199381D02*
X1200558D01*
G01X1195444D02*
X1196621D01*
G01X1191507D02*
X1192684D01*
G01X1187570D02*
X1188747D01*
G01X1183633D02*
X1184810D01*
G01X1179696D02*
X1180873D01*
G01X1175759D02*
X1176936D01*
G01X1171822D02*
X1172999D01*
G01X1167885D02*
X1169062D01*
G01X1163948D02*
X1165125D01*
G01X1160011D02*
X1161188D01*
G01X1156074D02*
X1157251D01*
G01X1152137D02*
X1153314D01*
G01X1148200D02*
X1149377D01*
G01Y653343D02*
X1148200D01*
G01X1153314D02*
X1152137D01*
G01X1157251D02*
X1156074D01*
G01X1161188D02*
X1160011D01*
G01X1165125D02*
X1163948D01*
G01X1169062D02*
X1167885D01*
G01X1172999D02*
X1171822D01*
G01X1176936D02*
X1175759D01*
G01X1180873D02*
X1179696D01*
G01X1184810D02*
X1183633D01*
G01X1188747D02*
X1187570D01*
G01X1192684D02*
X1191507D01*
G01X1196621D02*
X1195444D01*
G01X1200558D02*
X1199381D01*
G01X1204495D02*
X1203319D01*
G01X1149359Y652893D02*
X1148219D01*
G01X1157233D02*
X1156093D01*
G01X1165107D02*
X1163967D01*
G01X1172981D02*
X1171841D01*
G01X1180855D02*
X1179715D01*
G01X1188729D02*
X1187589D01*
G01X1196603D02*
X1195463D01*
G01X1204477D02*
X1203337D01*
G01X1203328Y652626D02*
X1204486D01*
G01X1195454D02*
X1196612D01*
G01X1187580D02*
X1188738D01*
G01X1179706D02*
X1180864D01*
G01X1171832D02*
X1172990D01*
G01X1163958D02*
X1165116D01*
G01X1156084D02*
X1157242D01*
G01X1148210D02*
X1149368D01*
G01X1204500Y659150D02*
X1204513Y659810D01*
G01X1204511Y660738D02*
X1204480Y659150D01*
G01X1203303Y664647D02*
X1203334Y666236D01*
G01X1203314D02*
X1203301Y665575D01*
G01X1200563Y659150D02*
X1200576Y659810D01*
G01X1200574Y660738D02*
X1200543Y659150D01*
G01X1199366Y664647D02*
X1199397Y666236D01*
G01X1199377D02*
X1199364Y665575D01*
G01X1204535Y664735D02*
X1204560Y666236D01*
G01X1204542D02*
X1204532Y665645D01*
G01X1203272Y659150D02*
X1203282Y659740D01*
G01X1203279Y660650D02*
X1203254Y659150D01*
G01X1200598Y664735D02*
X1200623Y666236D01*
G01X1200605D02*
X1200595Y665645D01*
G01X1199335Y659150D02*
X1199345Y659740D01*
G01X1199342Y660650D02*
X1199317Y659150D01*
G01X1203342Y674279D02*
X1203337Y672492D01*
G01X1203328Y672760D02*
X1203333Y674547D01*
G01X1200549Y670342D02*
X1200544Y668555D01*
G01X1200535Y668823D02*
X1200540Y670610D01*
G01X1199405Y656563D02*
X1199400Y654776D01*
G01X1199391Y655043D02*
X1199396Y656830D01*
G01X1204495Y653343D02*
Y654327D01*
G01Y671059D02*
Y672043D01*
G01X1204340Y675980D02*
Y674996D01*
G01X1203474D02*
Y675980D01*
G01X1203319Y654327D02*
Y653343D01*
G01Y672043D02*
Y671059D01*
G01X1202687Y682772D02*
Y677161D01*
G01X1200558Y654327D02*
Y653343D01*
G01Y672043D02*
Y671059D01*
G01X1200403Y658264D02*
Y657280D01*
G01Y668106D02*
Y667122D01*
G01X1199537Y658264D02*
Y657280D01*
G01Y667122D02*
Y668106D01*
G01X1199381Y653343D02*
Y654327D01*
G01Y671059D02*
Y672043D01*
G01X1197687Y682772D02*
Y677161D01*
G01X1204481Y674547D02*
X1204486Y672760D01*
G01X1204477Y672492D02*
X1204472Y674279D01*
G01X1200544Y656830D02*
X1200549Y655043D01*
G01X1200540Y654776D02*
X1200535Y656563D01*
G01X1199400Y670610D02*
X1199405Y668823D01*
G01X1199396Y668555D02*
X1199391Y670342D01*
G01X1204560Y659150D02*
X1204535Y660650D01*
G01X1204532Y659740D02*
X1204542Y659150D01*
G01X1203282Y665645D02*
X1203272Y666236D01*
G01X1203254D02*
X1203279Y664735D01*
G01X1200623Y659150D02*
X1200598Y660650D01*
G01X1200595Y659740D02*
X1200605Y659150D01*
G01X1199345Y665645D02*
X1199335Y666236D01*
G01X1199317D02*
X1199342Y664735D01*
G01X1196686Y659150D02*
X1196661Y660650D01*
G01X1196658Y659740D02*
X1196668Y659150D01*
G01X1204513Y665575D02*
X1204500Y666236D01*
G01X1204480D02*
X1204511Y664647D01*
G01X1203334Y659150D02*
X1203303Y660738D01*
G01X1203301Y659810D02*
X1203314Y659150D01*
G01X1200576Y665575D02*
X1200563Y666236D01*
G01X1200543D02*
X1200574Y664647D01*
G01X1199397Y659150D02*
X1199366Y660738D01*
G01X1199364Y659810D02*
X1199377Y659150D01*
G01X1196639Y665575D02*
X1196626Y666236D01*
G01X1196606D02*
X1196637Y664647D01*
G01X1196626Y659150D02*
X1196639Y659810D01*
G01X1196637Y660738D02*
X1196606Y659150D01*
G01X1195429Y664647D02*
X1195460Y666236D01*
G01X1195440D02*
X1195427Y665575D01*
G01X1192689Y659150D02*
X1192702Y659810D01*
G01X1192700Y660738D02*
X1192669Y659150D01*
G01X1191492Y664647D02*
X1191523Y666236D01*
G01X1191503D02*
X1191490Y665575D01*
G01X1188752Y659150D02*
X1188765Y659810D01*
G01X1188763Y660738D02*
X1188732Y659150D01*
G01X1187555Y664647D02*
X1187586Y666236D01*
G01X1187566D02*
X1187553Y665575D01*
G01X1184815Y659150D02*
X1184828Y659810D01*
G01X1184826Y660738D02*
X1184795Y659150D01*
G01X1196661Y664735D02*
X1196686Y666236D01*
G01X1196668D02*
X1196658Y665645D01*
G01X1195398Y659150D02*
X1195408Y659740D01*
G01X1195405Y660650D02*
X1195380Y659150D01*
G01X1192724Y664735D02*
X1192749Y666236D01*
G01X1192731D02*
X1192721Y665645D01*
G01X1191461Y659150D02*
X1191471Y659740D01*
G01X1191468Y660650D02*
X1191443Y659150D01*
G01X1188787Y664735D02*
X1188812Y666236D01*
G01X1188794D02*
X1188784Y665645D01*
G01X1187524Y659150D02*
X1187534Y659740D01*
G01X1187531Y660650D02*
X1187506Y659150D01*
G01X1184850Y664735D02*
X1184875Y666236D01*
G01X1184857D02*
X1184847Y665645D01*
G01X1195468Y674279D02*
X1195463Y672492D01*
G01X1195454Y672760D02*
X1195459Y674547D01*
G01X1192675Y670342D02*
X1192670Y668555D01*
G01X1192661Y668823D02*
X1192666Y670610D01*
G01X1191531Y656563D02*
X1191526Y654776D01*
G01X1191517Y655043D02*
X1191522Y656830D01*
G01X1187594Y674279D02*
X1187589Y672492D01*
G01X1187580Y672760D02*
X1187585Y674547D01*
G01X1184801Y670342D02*
X1184796Y668555D01*
G01X1184787Y668823D02*
X1184792Y670610D01*
G01X1196621Y653343D02*
Y654327D01*
G01Y672043D02*
Y671059D01*
G01X1196466Y675980D02*
Y674996D01*
G01X1195600D02*
Y675980D01*
G01X1195444Y654327D02*
Y653343D01*
G01Y671059D02*
Y672043D01*
G01X1192684Y654327D02*
Y653343D01*
G01Y672043D02*
Y671059D01*
G01X1192529Y658264D02*
Y657280D01*
G01Y668106D02*
Y667122D01*
G01X1191663Y658264D02*
Y657280D01*
G01Y667122D02*
Y668106D01*
G01X1191507Y653343D02*
Y654327D01*
G01Y671059D02*
Y672043D01*
G01X1188747Y653343D02*
Y654327D01*
G01Y671059D02*
Y672043D01*
G01X1188592Y675980D02*
Y674996D01*
G01X1187726D02*
Y675980D01*
G01X1187570Y654327D02*
Y653343D01*
G01Y672043D02*
Y671059D01*
G01X1184810Y654327D02*
Y653343D01*
G01Y672043D02*
Y671059D01*
G01X1184655Y658264D02*
Y657280D01*
G01Y668106D02*
Y667122D01*
G01X1196607Y674547D02*
X1196612Y672760D01*
G01X1196603Y672492D02*
X1196598Y674279D01*
G01X1192670Y656830D02*
X1192675Y655043D01*
G01X1192666Y654776D02*
X1192661Y656563D01*
G01X1191526Y670610D02*
X1191531Y668823D01*
G01X1191522Y668555D02*
X1191517Y670342D01*
G01X1188733Y674547D02*
X1188738Y672760D01*
G01X1188729Y672492D02*
X1188724Y674279D01*
G01X1184796Y656830D02*
X1184801Y655043D01*
G01X1184792Y654776D02*
X1184787Y656563D01*
G01X1195408Y665645D02*
X1195398Y666236D01*
G01X1195380D02*
X1195405Y664735D01*
G01X1192749Y659150D02*
X1192724Y660650D01*
G01X1192721Y659740D02*
X1192731Y659150D01*
G01X1191471Y665645D02*
X1191461Y666236D01*
G01X1191443D02*
X1191468Y664735D01*
G01X1188812Y659150D02*
X1188787Y660650D01*
G01X1188784Y659740D02*
X1188794Y659150D01*
G01X1187534Y665645D02*
X1187524Y666236D01*
G01X1187506D02*
X1187531Y664735D01*
G01X1184875Y659150D02*
X1184850Y660650D01*
G01X1184847Y659740D02*
X1184857Y659150D01*
G01X1183597Y665645D02*
X1183587Y666236D01*
G01X1183569D02*
X1183594Y664735D01*
G01X1195460Y659150D02*
X1195429Y660738D01*
G01X1195427Y659810D02*
X1195440Y659150D01*
G01X1192702Y665575D02*
X1192689Y666236D01*
G01X1192669D02*
X1192700Y664647D01*
G01X1191523Y659150D02*
X1191492Y660738D01*
G01X1191490Y659810D02*
X1191503Y659150D01*
G01X1188765Y665575D02*
X1188752Y666236D01*
G01X1188732D02*
X1188763Y664647D01*
G01X1187586Y659150D02*
X1187555Y660738D01*
G01X1187553Y659810D02*
X1187566Y659150D01*
G01X1184828Y665575D02*
X1184815Y666236D01*
G01X1184795D02*
X1184826Y664647D01*
G01X1183649Y659150D02*
X1183618Y660738D01*
G01X1183616Y659810D02*
X1183629Y659150D01*
G01X1183618Y664647D02*
X1183649Y666236D01*
G01X1183629D02*
X1183616Y665575D01*
G01X1180878Y659150D02*
X1180891Y659810D01*
G01X1180889Y660738D02*
X1180858Y659150D01*
G01X1179681Y664647D02*
X1179712Y666236D01*
G01X1179692D02*
X1179679Y665575D01*
G01X1176941Y659150D02*
X1176954Y659810D01*
G01X1176952Y660738D02*
X1176921Y659150D01*
G01X1175744Y664647D02*
X1175775Y666236D01*
G01X1175755D02*
X1175742Y665575D01*
G01X1173004Y659150D02*
X1173017Y659810D01*
G01X1173015Y660738D02*
X1172984Y659150D01*
G01X1171807Y664647D02*
X1171838Y666236D01*
G01X1171818D02*
X1171805Y665575D01*
G01X1183587Y659150D02*
X1183597Y659740D01*
G01X1183594Y660650D02*
X1183569Y659150D01*
G01X1180913Y664735D02*
X1180938Y666236D01*
G01X1180920D02*
X1180910Y665645D01*
G01X1179650Y659150D02*
X1179660Y659740D01*
G01X1179657Y660650D02*
X1179632Y659150D01*
G01X1176976Y664735D02*
X1177001Y666236D01*
G01X1176983D02*
X1176973Y665645D01*
G01X1175713Y659150D02*
X1175723Y659740D01*
G01X1175720Y660650D02*
X1175695Y659150D01*
G01X1173039Y664735D02*
X1173064Y666236D01*
G01X1173046D02*
X1173036Y665645D01*
G01X1171776Y659150D02*
X1171786Y659740D01*
G01X1171783Y660650D02*
X1171758Y659150D01*
G01X1183657Y656563D02*
X1183652Y654776D01*
G01X1183643Y655043D02*
X1183648Y656830D01*
G01X1179720Y674279D02*
X1179715Y672492D01*
G01X1179706Y672760D02*
X1179711Y674547D01*
G01X1176927Y670342D02*
X1176922Y668555D01*
G01X1176913Y668823D02*
X1176918Y670610D01*
G01X1175783Y656563D02*
X1175778Y654776D01*
G01X1175769Y655043D02*
X1175774Y656830D01*
G01X1171846Y674279D02*
X1171841Y672492D01*
G01X1171832Y672760D02*
X1171837Y674547D01*
G01X1183789Y658264D02*
Y657280D01*
G01Y667122D02*
Y668106D01*
G01X1183633Y653343D02*
Y654327D01*
G01Y671059D02*
Y672043D01*
G01X1181781Y682772D02*
Y677161D01*
G01X1180873Y653343D02*
Y654327D01*
G01Y671059D02*
Y672043D01*
G01X1180718Y675980D02*
Y674996D01*
G01X1179852D02*
Y675980D01*
G01X1179696Y654327D02*
Y653343D01*
G01Y672043D02*
Y671059D01*
G01X1176936Y654327D02*
Y653343D01*
G01Y672043D02*
Y671059D01*
G01X1176781Y658264D02*
Y657280D01*
G01Y682772D02*
Y677161D01*
G01Y668106D02*
Y667122D01*
G01X1175915Y658264D02*
Y657280D01*
G01Y667122D02*
Y668106D01*
G01X1175759Y653343D02*
Y654327D01*
G01Y671059D02*
Y672043D01*
G01X1172999Y653343D02*
Y654327D01*
G01Y671059D02*
Y672043D01*
G01X1172844Y675980D02*
Y674996D01*
G01X1171978D02*
Y675980D01*
G01X1171822Y654327D02*
Y653343D01*
G01Y672043D02*
Y671059D01*
G01X1183652Y670610D02*
X1183657Y668823D01*
G01X1183648Y668555D02*
X1183643Y670342D01*
G01X1180859Y674547D02*
X1180864Y672760D01*
G01X1180855Y672492D02*
X1180850Y674279D01*
G01X1176922Y656830D02*
X1176927Y655043D01*
G01X1176918Y654776D02*
X1176913Y656563D01*
G01X1175778Y670610D02*
X1175783Y668823D01*
G01X1175774Y668555D02*
X1175769Y670342D01*
G01X1172985Y674547D02*
X1172990Y672760D01*
G01X1172981Y672492D02*
X1172976Y674279D01*
G01X1180938Y659150D02*
X1180913Y660650D01*
G01X1180910Y659740D02*
X1180920Y659150D01*
G01X1179660Y665645D02*
X1179650Y666236D01*
G01X1179632D02*
X1179657Y664735D01*
G01X1177001Y659150D02*
X1176976Y660650D01*
G01X1176973Y659740D02*
X1176983Y659150D01*
G01X1175723Y665645D02*
X1175713Y666236D01*
G01X1175695D02*
X1175720Y664735D01*
G01X1173064Y659150D02*
X1173039Y660650D01*
G01X1173036Y659740D02*
X1173046Y659150D01*
G01X1171786Y665645D02*
X1171776Y666236D01*
G01X1171758D02*
X1171783Y664735D01*
G01X1180891Y665575D02*
X1180878Y666236D01*
G01X1180858D02*
X1180889Y664647D01*
G01X1179712Y659150D02*
X1179681Y660738D01*
G01X1179679Y659810D02*
X1179692Y659150D01*
G01X1176954Y665575D02*
X1176941Y666236D01*
G01X1176921D02*
X1176952Y664647D01*
G01X1175775Y659150D02*
X1175744Y660738D01*
G01X1175742Y659810D02*
X1175755Y659150D01*
G01X1173017Y665575D02*
X1173004Y666236D01*
G01X1172984D02*
X1173015Y664647D01*
G01X1171838Y659150D02*
X1171807Y660738D01*
G01X1171805Y659810D02*
X1171818Y659150D01*
G01X1169067D02*
X1169080Y659810D01*
G01X1169078Y660738D02*
X1169047Y659150D01*
G01X1167870Y664647D02*
X1167901Y666236D01*
G01X1167881D02*
X1167868Y665575D01*
G01X1165130Y659150D02*
X1165143Y659810D01*
G01X1165141Y660738D02*
X1165110Y659150D01*
G01X1163933Y664647D02*
X1163964Y666236D01*
G01X1163944D02*
X1163931Y665575D01*
G01X1161193Y659150D02*
X1161206Y659810D01*
G01X1161204Y660738D02*
X1161173Y659150D01*
G01X1159996Y664647D02*
X1160027Y666236D01*
G01X1160007D02*
X1159994Y665575D01*
G01X1169102Y664735D02*
X1169127Y666236D01*
G01X1169109D02*
X1169099Y665645D01*
G01X1167839Y659150D02*
X1167849Y659740D01*
G01X1167846Y660650D02*
X1167821Y659150D01*
G01X1165165Y664735D02*
X1165190Y666236D01*
G01X1165172D02*
X1165162Y665645D01*
G01X1163902Y659150D02*
X1163912Y659740D01*
G01X1163909Y660650D02*
X1163884Y659150D01*
G01X1161228Y664735D02*
X1161253Y666236D01*
G01X1161235D02*
X1161225Y665645D01*
G01X1159965Y659150D02*
X1159975Y659740D01*
G01X1159972Y660650D02*
X1159947Y659150D01*
G01X1169053Y670342D02*
X1169048Y668555D01*
G01X1169039Y668823D02*
X1169044Y670610D01*
G01X1167909Y656563D02*
X1167904Y654776D01*
G01X1167895Y655043D02*
X1167900Y656830D01*
G01X1163972Y674279D02*
X1163967Y672492D01*
G01X1163958Y672760D02*
X1163963Y674547D01*
G01X1161179Y670342D02*
X1161174Y668555D01*
G01X1161165Y668823D02*
X1161170Y670610D01*
G01X1160035Y656563D02*
X1160030Y654776D01*
G01X1160021Y655043D02*
X1160026Y656830D01*
G01X1169062Y654327D02*
Y653343D01*
G01Y672043D02*
Y671059D01*
G01X1168907Y658264D02*
Y657280D01*
G01Y668106D02*
Y667122D01*
G01X1168041Y658264D02*
Y657280D01*
G01Y667122D02*
Y668106D01*
G01X1167885Y653343D02*
Y654327D01*
G01Y671059D02*
Y672043D01*
G01X1165125Y653343D02*
Y654327D01*
G01Y671059D02*
Y672043D01*
G01X1164970Y675980D02*
Y674996D01*
G01X1164104D02*
Y675980D01*
G01X1163948Y654327D02*
Y653343D01*
G01Y672043D02*
Y671059D01*
G01X1161188Y654327D02*
Y653343D01*
G01Y671059D02*
Y672043D01*
G01X1161033Y658264D02*
Y657280D01*
G01Y668106D02*
Y667122D01*
G01X1160876Y682772D02*
Y677161D01*
G01X1160167Y658264D02*
Y657280D01*
G01Y667122D02*
Y668106D01*
G01X1160011Y653343D02*
Y654327D01*
G01Y672043D02*
Y671059D01*
G01X1169048Y656830D02*
X1169053Y655043D01*
G01X1169044Y654776D02*
X1169039Y656563D01*
G01X1167904Y670610D02*
X1167909Y668823D01*
G01X1167900Y668555D02*
X1167895Y670342D01*
G01X1165111Y674547D02*
X1165116Y672760D01*
G01X1165107Y672492D02*
X1165102Y674279D01*
G01X1161174Y656830D02*
X1161179Y655043D01*
G01X1161170Y654776D02*
X1161165Y656563D01*
G01X1160030Y670610D02*
X1160035Y668823D01*
G01X1160026Y668555D02*
X1160021Y670342D01*
G01X1169127Y659150D02*
X1169102Y660650D01*
G01X1169099Y659740D02*
X1169109Y659150D01*
G01X1167849Y665645D02*
X1167839Y666236D01*
G01X1167821D02*
X1167846Y664735D01*
G01X1165190Y659150D02*
X1165165Y660650D01*
G01X1165162Y659740D02*
X1165172Y659150D01*
G01X1163912Y665645D02*
X1163902Y666236D01*
G01X1163884D02*
X1163909Y664735D01*
G01X1161253Y659150D02*
X1161228Y660650D01*
G01X1161225Y659740D02*
X1161235Y659150D01*
G01X1159975Y665645D02*
X1159965Y666236D01*
G01X1159947D02*
X1159972Y664735D01*
G01X1169080Y665575D02*
X1169067Y666236D01*
G01X1169047D02*
X1169078Y664647D01*
G01X1167901Y659150D02*
X1167870Y660738D01*
G01X1167868Y659810D02*
X1167881Y659150D01*
G01X1165143Y665575D02*
X1165130Y666236D01*
G01X1165110D02*
X1165141Y664647D01*
G01X1163964Y659150D02*
X1163933Y660738D01*
G01X1163931Y659810D02*
X1163944Y659150D01*
G01X1161206Y665575D02*
X1161193Y666236D01*
G01X1161173D02*
X1161204Y664647D01*
G01X1160027Y659150D02*
X1159996Y660738D01*
G01X1159994Y659810D02*
X1160007Y659150D01*
G01X1157256D02*
X1157269Y659810D01*
G01X1157267Y660738D02*
X1157236Y659150D01*
G01X1156059Y664647D02*
X1156090Y666236D01*
G01X1156070D02*
X1156057Y665575D01*
G01X1153319Y659150D02*
X1153332Y659810D01*
G01X1153330Y660738D02*
X1153299Y659150D01*
G01X1152122Y664647D02*
X1152153Y666236D01*
G01X1152133D02*
X1152120Y665575D01*
G01X1149382Y659150D02*
X1149395Y659810D01*
G01X1149393Y660738D02*
X1149362Y659150D01*
G01X1148185Y664647D02*
X1148216Y666236D01*
G01X1148196D02*
X1148183Y665575D01*
G01X1157291Y664735D02*
X1157316Y666236D01*
G01X1157298D02*
X1157288Y665645D01*
G01X1156028Y659150D02*
X1156038Y659740D01*
G01X1156035Y660650D02*
X1156010Y659150D01*
G01X1153354Y664735D02*
X1153379Y666236D01*
G01X1153361D02*
X1153351Y665645D01*
G01X1152091Y659150D02*
X1152101Y659740D01*
G01X1152098Y660650D02*
X1152073Y659150D01*
G01X1149417Y664735D02*
X1149442Y666236D01*
G01X1149424D02*
X1149414Y665645D01*
G01X1148154Y659150D02*
X1148164Y659740D01*
G01X1148161Y660650D02*
X1148136Y659150D01*
G01X1156098Y674279D02*
X1156093Y672492D01*
G01X1156084Y672760D02*
X1156089Y674547D01*
G01X1153305Y670342D02*
X1153300Y668555D01*
G01X1153291Y668823D02*
X1153296Y670610D01*
G01X1152161Y656563D02*
X1152156Y654776D01*
G01X1152147Y655043D02*
X1152152Y656830D01*
G01X1148224Y674279D02*
X1148219Y672492D01*
G01X1148210Y672760D02*
X1148215Y674547D01*
G01X1157251Y653343D02*
Y654327D01*
G01Y671059D02*
Y672043D01*
G01X1157096Y675980D02*
Y674996D01*
G01X1156230D02*
Y675980D01*
G01X1156074Y654327D02*
Y653343D01*
G01Y672043D02*
Y671059D01*
G01X1155876Y682772D02*
Y677161D01*
G01X1153314Y654327D02*
Y653343D01*
G01Y672043D02*
Y671059D01*
G01X1153159Y658264D02*
Y657280D01*
G01Y668106D02*
Y667122D01*
G01X1152293Y658264D02*
Y657280D01*
G01Y667122D02*
Y668106D01*
G01X1152137Y653343D02*
Y654327D01*
G01Y671059D02*
Y672043D01*
G01X1149377Y653343D02*
Y654327D01*
G01Y671059D02*
Y672043D01*
G01X1149222Y675980D02*
Y674996D01*
G01X1148356D02*
Y675980D01*
G01X1148200Y654327D02*
Y653343D01*
G01Y672043D02*
Y671059D01*
G01X1157237Y674547D02*
X1157242Y672760D01*
G01X1157233Y672492D02*
X1157228Y674279D01*
G01X1153300Y656830D02*
X1153305Y655043D01*
G01X1153296Y654776D02*
X1153291Y656563D01*
G01X1152156Y670610D02*
X1152161Y668823D01*
G01X1152152Y668555D02*
X1152147Y670342D01*
G01X1149363Y674547D02*
X1149368Y672760D01*
G01X1149359Y672492D02*
X1149354Y674279D01*
G01X1157316Y659150D02*
X1157291Y660650D01*
G01X1157288Y659740D02*
X1157298Y659150D01*
G01X1156038Y665645D02*
X1156028Y666236D01*
G01X1156010D02*
X1156035Y664735D01*
G01X1153379Y659150D02*
X1153354Y660650D01*
G01X1153351Y659740D02*
X1153361Y659150D01*
G01X1152101Y665645D02*
X1152091Y666236D01*
G01X1152073D02*
X1152098Y664735D01*
G01X1149442Y659150D02*
X1149417Y660650D01*
G01X1149414Y659740D02*
X1149424Y659150D01*
G01X1148164Y665645D02*
X1148154Y666236D01*
G01X1148136D02*
X1148161Y664735D01*
G01X1157269Y665575D02*
X1157256Y666236D01*
G01X1157236D02*
X1157267Y664647D01*
G01X1156090Y659150D02*
X1156059Y660738D01*
G01X1156057Y659810D02*
X1156070Y659150D01*
G01X1153332Y665575D02*
X1153319Y666236D01*
G01X1153299D02*
X1153330Y664647D01*
G01X1152153Y659150D02*
X1152122Y660738D01*
G01X1152120Y659810D02*
X1152133Y659150D01*
G01X1149395Y665575D02*
X1149382Y666236D01*
G01X1149362D02*
X1149393Y664647D01*
G01X1148216Y659150D02*
X1148185Y660738D01*
G01X1148183Y659810D02*
X1148196Y659150D01*
G01X1225315Y-426126D02*
Y-443449D01*
G01X1266467Y256150D02*
Y272686D01*
G01X1265286D02*
Y256150D01*
G01X1262530D02*
Y272686D01*
G01X1266467D02*
X1269223D01*
G01X1262530D02*
X1265286D01*
G01X1258593D02*
X1261349D01*
G01X1254656D02*
X1257412D01*
G01X1250719D02*
X1253475D01*
G01X1246782D02*
X1249538D01*
G01X1242845D02*
X1245601D01*
G01X1238908D02*
X1241664D01*
G01X1234971D02*
X1237727D01*
G01X1231034D02*
X1233790D01*
G01X1227097D02*
X1229853D01*
G01X1223160D02*
X1225916D01*
G01X1219223D02*
X1221979D01*
G01X1215286D02*
X1218042D01*
G01X1211349D02*
X1214105D01*
G01X1207412D02*
X1210168D01*
G01X1261349D02*
Y256150D01*
G01X1258593D02*
Y272686D01*
G01X1257412D02*
Y256150D01*
G01X1254656D02*
Y272686D01*
G01X1253475D02*
Y256150D01*
G01X1250719D02*
Y272686D01*
G01X1249538D02*
Y256150D01*
G01X1210168D02*
X1207412D01*
G01X1214105D02*
X1211349D01*
G01X1218042D02*
X1215286D01*
G01X1221979D02*
X1219223D01*
G01X1225916D02*
X1223160D01*
G01X1229853D02*
X1227097D01*
G01X1233790D02*
X1231034D01*
G01X1237727D02*
X1234971D01*
G01X1241664D02*
X1238908D01*
G01X1245601D02*
X1242845D01*
G01X1249538D02*
X1246782D01*
G01X1253475D02*
X1250719D01*
G01X1257412D02*
X1254656D01*
G01X1261349D02*
X1258593D01*
G01X1265286D02*
X1262530D01*
G01X1269223D02*
X1266467D01*
G01X1246782D02*
Y272686D01*
G01X1245601D02*
Y256150D01*
G01X1242845D02*
Y272686D01*
G01X1241664D02*
Y256150D01*
G01X1238908D02*
Y272686D01*
G01X1237727D02*
Y256150D01*
G01X1234971D02*
Y272686D01*
G01X1233790D02*
Y256150D01*
G01X1231034D02*
Y272686D01*
G01X1229853D02*
Y256150D01*
G01X1227097D02*
Y272686D01*
G01X1225916D02*
Y256150D01*
G01X1223160D02*
Y272686D01*
G01X1221979D02*
Y256150D01*
G01X1219223D02*
Y272686D01*
G01X1218042D02*
Y256150D01*
G01X1215286D02*
Y272686D01*
G01X1214105D02*
Y256150D01*
G01X1211349D02*
Y272686D01*
G01X1210168D02*
Y256150D01*
G01X1207412D02*
Y272686D01*
G01X1246191Y353394D02*
G03X1250128Y349457I3937J0D01*
G01X1246191Y353394D02*
G03X1242254Y357331I-3937J0D01*
G01X1250128Y349457D02*
X1320994D01*
G01X1265521Y589858D02*
Y606394D01*
G01X1264340D02*
Y589858D01*
G01X1261584D02*
Y606394D01*
G01X1260403D02*
Y589858D01*
G01X1257647D02*
Y606394D01*
G01X1256466D02*
Y589858D01*
G01X1253710D02*
Y606394D01*
G01X1252529D02*
Y589858D01*
G01X1249773D02*
Y606394D01*
G01X1248592D02*
Y589858D01*
G01X1245836D02*
Y606394D01*
G01X1244655D02*
Y589858D01*
G01X1241899D02*
Y606394D01*
G01X1240718D02*
Y589858D01*
G01X1237962D02*
Y606394D01*
G01X1236781D02*
Y589858D01*
G01X1213159D02*
X1210403D01*
G01X1217096D02*
X1214340D01*
G01X1221033D02*
X1218277D01*
G01X1224970D02*
X1222214D01*
G01X1228907D02*
X1226151D01*
G01X1232844D02*
X1230088D01*
G01X1236781D02*
X1234025D01*
G01X1240718D02*
X1237962D01*
G01X1244655D02*
X1241899D01*
G01X1248592D02*
X1245836D01*
G01X1252529D02*
X1249773D01*
G01X1256466D02*
X1253710D01*
G01X1260403D02*
X1257647D01*
G01X1264340D02*
X1261584D01*
G01X1268277D02*
X1265521D01*
G01X1234025D02*
Y606394D01*
G01X1232844D02*
Y589858D01*
G01X1230088D02*
Y606394D01*
G01X1228907D02*
Y589858D01*
G01X1226151D02*
Y606394D01*
G01X1224970D02*
Y589858D01*
G01X1222214D02*
Y606394D01*
G01X1221033D02*
Y589858D01*
G01X1218277D02*
Y606394D01*
G01X1217096D02*
Y589858D01*
G01X1214340D02*
Y606394D01*
G01X1213159D02*
Y589858D01*
G01X1210403D02*
Y606394D01*
G01X1209222D02*
Y589858D01*
G01X1266334Y651106D02*
X1267464D01*
G01X1258460D02*
X1259590D01*
G01X1250586D02*
X1251716D01*
G01X1242712D02*
X1243842D01*
G01X1234838D02*
X1235968D01*
G01X1226964D02*
X1228094D01*
G01X1219090D02*
X1220220D01*
G01X1211216D02*
X1212346D01*
G01X1212355Y650839D02*
X1211207D01*
G01X1220229D02*
X1219081D01*
G01X1228103D02*
X1226955D01*
G01X1235977D02*
X1234829D01*
G01X1243851D02*
X1242703D01*
G01X1251725D02*
X1250577D01*
G01X1259599D02*
X1258451D01*
G01X1267473D02*
X1266325D01*
G01X1258470Y650390D02*
X1259580D01*
G01X1250596D02*
X1251706D01*
G01X1242722D02*
X1243832D01*
G01X1234848D02*
X1235958D01*
G01X1226974D02*
X1228084D01*
G01X1219100D02*
X1220210D01*
G01X1211226D02*
X1212336D01*
G01X1267454D02*
X1266344D01*
G01Y649406D02*
X1267454D01*
G01X1258470D02*
X1259580D01*
G01X1250596D02*
X1251706D01*
G01X1242722D02*
X1243832D01*
G01X1234848D02*
X1235958D01*
G01X1226974D02*
X1228084D01*
G01X1219100D02*
X1220210D01*
G01X1211226D02*
X1212336D01*
G01X1267478Y652626D02*
X1267473Y650839D01*
G01X1267464Y651106D02*
X1267469Y652893D01*
G01X1267332Y650390D02*
Y649406D01*
G01X1266466Y650390D02*
Y649406D01*
G01X1266330Y652893D02*
X1266334Y651106D01*
G01X1266325Y650839D02*
X1266320Y652626D01*
G01X1259604D02*
X1259599Y650839D01*
G01X1259590Y651106D02*
X1259595Y652893D01*
G01X1251730Y652626D02*
X1251725Y650839D01*
G01X1251716Y651106D02*
X1251721Y652893D01*
G01X1259458Y650390D02*
Y649406D01*
G01X1258592Y650390D02*
Y649406D01*
G01X1251584Y650390D02*
Y649406D01*
G01X1250718Y650390D02*
Y649406D01*
G01X1258456Y652893D02*
X1258460Y651106D01*
G01X1258451Y650839D02*
X1258446Y652626D01*
G01X1250581Y652893D02*
X1250586Y651106D01*
G01X1250577Y650839D02*
X1250572Y652626D01*
G01X1265521Y606394D02*
X1268277D01*
G01X1261584D02*
X1264340D01*
G01X1257647D02*
X1260403D01*
G01X1253710D02*
X1256466D01*
G01X1249773D02*
X1252529D01*
G01X1245836D02*
X1248592D01*
G01X1241899D02*
X1244655D01*
G01X1237962D02*
X1240718D01*
G01X1234025D02*
X1236781D01*
G01X1230088D02*
X1232844D01*
G01X1226151D02*
X1228907D01*
G01X1222214D02*
X1224970D01*
G01X1218277D02*
X1221033D01*
G01X1214340D02*
X1217096D01*
G01X1210403D02*
X1213159D01*
G01X1243856Y652626D02*
X1243851Y650839D01*
G01X1243842Y651106D02*
X1243847Y652893D01*
G01X1235982Y652626D02*
X1235977Y650839D01*
G01X1235968Y651106D02*
X1235973Y652893D01*
G01X1243710Y650390D02*
Y649406D01*
G01X1242844Y650390D02*
Y649406D01*
G01X1235836Y650390D02*
Y649406D01*
G01X1242707Y652893D02*
X1242712Y651106D01*
G01X1242703Y650839D02*
X1242698Y652626D01*
G01X1228108D02*
X1228103Y650839D01*
G01X1228094Y651106D02*
X1228099Y652893D01*
G01X1234970Y650390D02*
Y649406D01*
G01X1227962Y650390D02*
Y649406D01*
G01X1227096Y650390D02*
Y649406D01*
G01X1234833Y652893D02*
X1234838Y651106D01*
G01X1234829Y650839D02*
X1234824Y652626D01*
G01X1226959Y652893D02*
X1226964Y651106D01*
G01X1226955Y650839D02*
X1226950Y652626D01*
G01X1220234D02*
X1220229Y650839D01*
G01X1220220Y651106D02*
X1220225Y652893D01*
G01X1212360Y652626D02*
X1212355Y650839D01*
G01X1212346Y651106D02*
X1212351Y652893D01*
G01X1220088Y650390D02*
Y649406D01*
G01X1219222Y650390D02*
Y649406D01*
G01X1212214Y650390D02*
Y649406D01*
G01X1211348Y650390D02*
Y649406D01*
G01X1219085Y652893D02*
X1219090Y651106D01*
G01X1219081Y650839D02*
X1219076Y652626D01*
G01X1211211Y652893D02*
X1211216Y651106D01*
G01X1211207Y650839D02*
X1211202Y652626D01*
G01X1233435Y691039D02*
Y706394D01*
G01Y687102D02*
G03X1237372Y683165I3937J0D01*
G01X1233435Y687102D02*
G03X1229498Y691039I-3937J0D01*
G01X1233435Y687102D02*
G03X1237372Y683165I3937J0D01*
G01X1233435Y687102D02*
G03X1229498Y691039I-3937J0D01*
G01X1233435Y687102D02*
G03X1237372Y683165I3937J0D01*
G01X1233435Y687102D02*
G03X1229498Y691039I-3937J0D01*
G01X1237372Y683165D02*
X1308238D01*
G01X1239498Y682772D02*
X1223592D01*
G01X1260403D02*
X1244498D01*
G01X1281309D02*
X1265403D01*
G01X1212336Y675980D02*
X1211226D01*
G01X1220210D02*
X1219100D01*
G01X1228084D02*
X1226974D01*
G01X1235958D02*
X1234848D01*
G01X1243832D02*
X1242722D01*
G01X1251706D02*
X1250596D01*
G01X1259580D02*
X1258470D01*
G01X1267454D02*
X1266344D01*
G01X1212336Y674996D02*
X1211226D01*
G01X1220210D02*
X1219100D01*
G01X1228084D02*
X1226974D01*
G01X1235958D02*
X1234848D01*
G01X1243832D02*
X1242722D01*
G01X1251706D02*
X1250596D01*
G01X1259580D02*
X1258470D01*
G01X1267454D02*
X1266344D01*
G01X1266325Y674547D02*
X1267473D01*
G01X1258451D02*
X1259599D01*
G01X1250577D02*
X1251725D01*
G01X1242703D02*
X1243851D01*
G01X1234829D02*
X1235977D01*
G01X1226955D02*
X1228103D01*
G01X1219081D02*
X1220229D01*
G01X1211207D02*
X1212355D01*
G01X1212346Y674279D02*
X1211216D01*
G01X1220220D02*
X1219090D01*
G01X1228094D02*
X1226964D01*
G01X1235968D02*
X1234838D01*
G01X1243842D02*
X1242712D01*
G01X1251716D02*
X1250586D01*
G01X1259590D02*
X1258460D01*
G01X1267464D02*
X1266334D01*
G01X1212360Y672760D02*
X1211202D01*
G01X1220234D02*
X1219076D01*
G01X1228108D02*
X1226950D01*
G01X1235982D02*
X1234824D01*
G01X1243856D02*
X1242698D01*
G01X1251730D02*
X1250572D01*
G01X1259604D02*
X1258446D01*
G01X1267478D02*
X1266320D01*
G01X1266330Y672492D02*
X1267469D01*
G01X1258456D02*
X1259595D01*
G01X1250581D02*
X1251721D01*
G01X1242707D02*
X1243847D01*
G01X1234833D02*
X1235973D01*
G01X1226959D02*
X1228099D01*
G01X1219085D02*
X1220225D01*
G01X1211211D02*
X1212351D01*
G01X1208432Y672043D02*
X1207256D01*
G01X1212369D02*
X1211193D01*
G01X1216306D02*
X1215130D01*
G01X1220243D02*
X1219067D01*
G01X1224180D02*
X1223004D01*
G01X1228117D02*
X1226941D01*
G01X1232054D02*
X1230878D01*
G01X1235991D02*
X1234815D01*
G01X1239928D02*
X1238752D01*
G01X1243865D02*
X1242689D01*
G01X1247802D02*
X1246626D01*
G01X1251739D02*
X1250563D01*
G01X1255676D02*
X1254500D01*
G01X1259613D02*
X1258437D01*
G01X1263550D02*
X1262374D01*
G01X1267487D02*
X1266311D01*
G01X1208432Y671059D02*
X1207256D01*
G01X1212369D02*
X1211193D01*
G01X1216306D02*
X1215130D01*
G01X1220243D02*
X1219067D01*
G01X1224180D02*
X1223004D01*
G01X1228117D02*
X1226941D01*
G01X1232054D02*
X1230878D01*
G01X1235991D02*
X1234815D01*
G01X1239928D02*
X1238752D01*
G01X1243865D02*
X1242689D01*
G01X1247802D02*
X1246626D01*
G01X1251739D02*
X1250563D01*
G01X1255676D02*
X1254500D01*
G01X1259613D02*
X1258437D01*
G01X1263550D02*
X1262374D01*
G01X1267487D02*
X1266311D01*
G01X1208414Y670610D02*
X1207274D01*
G01X1216288D02*
X1215148D01*
G01X1224162D02*
X1223022D01*
G01X1232036D02*
X1230896D01*
G01X1239910D02*
X1238770D01*
G01X1247784D02*
X1246644D01*
G01X1255658D02*
X1254519D01*
G01X1263532D02*
X1262393D01*
G01X1262383Y670342D02*
X1263541D01*
G01X1254509D02*
X1255667D01*
G01X1246635D02*
X1247793D01*
G01X1238761D02*
X1239919D01*
G01X1230887D02*
X1232045D01*
G01X1223013D02*
X1224171D01*
G01X1215139D02*
X1216297D01*
G01X1207265D02*
X1208423D01*
G01X1262397Y668823D02*
X1263527D01*
G01X1254523D02*
X1255653D01*
G01X1246649D02*
X1247779D01*
G01X1238775D02*
X1239905D01*
G01X1230901D02*
X1232031D01*
G01X1223027D02*
X1224157D01*
G01X1215153D02*
X1216283D01*
G01X1207279D02*
X1208409D01*
G01X1208418Y668555D02*
X1207270D01*
G01X1216292D02*
X1215144D01*
G01X1224166D02*
X1223018D01*
G01X1232040D02*
X1230892D01*
G01X1239914D02*
X1238766D01*
G01X1247788D02*
X1246640D01*
G01X1255662D02*
X1254514D01*
G01X1263536D02*
X1262388D01*
G01X1208399Y668106D02*
X1207289D01*
G01X1216273D02*
X1215163D01*
G01X1224147D02*
X1223037D01*
G01X1232021D02*
X1230911D01*
G01X1239895D02*
X1238785D01*
G01X1247769D02*
X1246659D01*
G01X1255643D02*
X1254533D01*
G01X1263517D02*
X1262407D01*
G01X1208399Y667122D02*
X1207289D01*
G01X1216273D02*
X1215163D01*
G01X1224147D02*
X1223037D01*
G01X1232021D02*
X1230911D01*
G01X1239895D02*
X1238785D01*
G01X1247769D02*
X1246659D01*
G01X1255643D02*
X1254533D01*
G01X1263517D02*
X1262407D01*
G01X1208469Y665645D02*
X1207219D01*
G01X1212406D02*
X1211156D01*
G01X1216343D02*
X1215093D01*
G01X1220280D02*
X1219030D01*
G01X1224217D02*
X1222967D01*
G01X1228154D02*
X1226904D01*
G01X1232091D02*
X1230841D01*
G01X1236028D02*
X1234778D01*
G01X1239965D02*
X1238715D01*
G01X1243902D02*
X1242652D01*
G01X1247839D02*
X1246589D01*
G01X1251776D02*
X1250526D01*
G01X1255713D02*
X1254463D01*
G01X1259650D02*
X1258400D01*
G01X1263587D02*
X1262337D01*
G01X1267524D02*
X1266274D01*
G01X1266293Y665575D02*
X1267505D01*
G01X1262356D02*
X1263568D01*
G01X1258419D02*
X1259631D01*
G01X1254482D02*
X1255694D01*
G01X1250545D02*
X1251757D01*
G01X1246608D02*
X1247820D01*
G01X1242671D02*
X1243883D01*
G01X1238734D02*
X1239946D01*
G01X1234797D02*
X1236009D01*
G01X1230860D02*
X1232072D01*
G01X1226923D02*
X1228135D01*
G01X1222986D02*
X1224198D01*
G01X1219049D02*
X1220261D01*
G01X1215112D02*
X1216324D01*
G01X1211175D02*
X1212387D01*
G01X1207238D02*
X1208450D01*
G01X1208459Y665350D02*
X1207229D01*
G01X1212396D02*
X1211166D01*
G01X1216333D02*
X1215103D01*
G01X1220270D02*
X1219040D01*
G01X1224207D02*
X1222977D01*
G01X1228144D02*
X1226914D01*
G01X1232081D02*
X1230851D01*
G01X1236018D02*
X1234788D01*
G01X1239955D02*
X1238725D01*
G01X1243892D02*
X1242662D01*
G01X1247829D02*
X1246599D01*
G01X1251766D02*
X1250536D01*
G01X1255703D02*
X1254473D01*
G01X1259640D02*
X1258410D01*
G01X1263577D02*
X1262347D01*
G01X1267514D02*
X1266284D01*
G01X1266271Y664735D02*
X1267527D01*
G01X1262334D02*
X1263590D01*
G01X1258397D02*
X1259653D01*
G01X1254460D02*
X1255716D01*
G01X1250523D02*
X1251779D01*
G01X1246586D02*
X1247842D01*
G01X1242649D02*
X1243905D01*
G01X1238712D02*
X1239968D01*
G01X1234775D02*
X1236031D01*
G01X1230838D02*
X1232094D01*
G01X1226901D02*
X1228157D01*
G01X1222964D02*
X1224220D01*
G01X1219027D02*
X1220283D01*
G01X1215090D02*
X1216346D01*
G01X1211153D02*
X1212409D01*
G01X1207216D02*
X1208472D01*
G01X1208448Y664647D02*
X1207240D01*
G01X1212385D02*
X1211177D01*
G01X1216322D02*
X1215114D01*
G01X1220259D02*
X1219051D01*
G01X1224196D02*
X1222988D01*
G01X1228133D02*
X1226925D01*
G01X1232070D02*
X1230862D01*
G01X1236007D02*
X1234799D01*
G01X1239944D02*
X1238736D01*
G01X1243881D02*
X1242673D01*
G01X1247818D02*
X1246610D01*
G01X1251755D02*
X1250547D01*
G01X1255692D02*
X1254484D01*
G01X1259629D02*
X1258421D01*
G01X1263566D02*
X1262358D01*
G01X1267503D02*
X1266295D01*
G01X1208459Y664365D02*
X1207229D01*
G01X1212396D02*
X1211166D01*
G01X1216333D02*
X1215103D01*
G01X1220270D02*
X1219040D01*
G01X1224207D02*
X1222977D01*
G01X1228144D02*
X1226914D01*
G01X1232081D02*
X1230851D01*
G01X1236018D02*
X1234788D01*
G01X1239955D02*
X1238725D01*
G01X1243892D02*
X1242662D01*
G01X1247829D02*
X1246599D01*
G01X1251766D02*
X1250536D01*
G01X1255703D02*
X1254473D01*
G01X1259640D02*
X1258410D01*
G01X1263577D02*
X1262347D01*
G01X1267514D02*
X1266284D01*
G01Y661020D02*
X1267514D01*
G01X1262347D02*
X1263577D01*
G01X1258410D02*
X1259640D01*
G01X1254473D02*
X1255703D01*
G01X1250536D02*
X1251766D01*
G01X1246599D02*
X1247829D01*
G01X1242662D02*
X1243892D01*
G01X1238725D02*
X1239955D01*
G01X1234788D02*
X1236018D01*
G01X1230851D02*
X1232081D01*
G01X1226914D02*
X1228144D01*
G01X1222977D02*
X1224207D01*
G01X1219040D02*
X1220270D01*
G01X1215103D02*
X1216333D01*
G01X1211166D02*
X1212396D01*
G01X1207229D02*
X1208459D01*
G01X1266295Y660738D02*
X1267503D01*
G01X1262358D02*
X1263566D01*
G01X1258421D02*
X1259629D01*
G01X1254484D02*
X1255692D01*
G01X1250547D02*
X1251755D01*
G01X1246610D02*
X1247818D01*
G01X1242673D02*
X1243881D01*
G01X1238736D02*
X1239944D01*
G01X1234799D02*
X1236007D01*
G01X1230862D02*
X1232070D01*
G01X1226925D02*
X1228133D01*
G01X1222988D02*
X1224196D01*
G01X1219051D02*
X1220259D01*
G01X1215114D02*
X1216322D01*
G01X1211177D02*
X1212385D01*
G01X1207240D02*
X1208448D01*
G01X1208472Y660650D02*
X1207216D01*
G01X1212409D02*
X1211153D01*
G01X1216346D02*
X1215090D01*
G01X1220283D02*
X1219027D01*
G01X1224220D02*
X1222964D01*
G01X1228157D02*
X1226901D01*
G01X1232094D02*
X1230838D01*
G01X1236031D02*
X1234775D01*
G01X1239968D02*
X1238712D01*
G01X1243905D02*
X1242649D01*
G01X1247842D02*
X1246586D01*
G01X1251779D02*
X1250523D01*
G01X1255716D02*
X1254460D01*
G01X1259653D02*
X1258397D01*
G01X1263590D02*
X1262334D01*
G01X1267527D02*
X1266271D01*
G01X1266284Y660036D02*
X1267514D01*
G01X1262347D02*
X1263577D01*
G01X1258410D02*
X1259640D01*
G01X1254473D02*
X1255703D01*
G01X1250536D02*
X1251766D01*
G01X1246599D02*
X1247829D01*
G01X1242662D02*
X1243892D01*
G01X1238725D02*
X1239955D01*
G01X1234788D02*
X1236018D01*
G01X1230851D02*
X1232081D01*
G01X1226914D02*
X1228144D01*
G01X1222977D02*
X1224207D01*
G01X1219040D02*
X1220270D01*
G01X1215103D02*
X1216333D01*
G01X1211166D02*
X1212396D01*
G01X1207229D02*
X1208459D01*
G01X1208450Y659810D02*
X1207238D01*
G01X1212387D02*
X1211175D01*
G01X1216324D02*
X1215112D01*
G01X1220261D02*
X1219049D01*
G01X1224198D02*
X1222986D01*
G01X1228135D02*
X1226923D01*
G01X1232072D02*
X1230860D01*
G01X1236009D02*
X1234797D01*
G01X1239946D02*
X1238734D01*
G01X1243883D02*
X1242671D01*
G01X1247820D02*
X1246608D01*
G01X1251757D02*
X1250545D01*
G01X1255694D02*
X1254482D01*
G01X1259631D02*
X1258419D01*
G01X1263568D02*
X1262356D01*
G01X1267505D02*
X1266293D01*
G01X1266274Y659740D02*
X1267524D01*
G01X1262337D02*
X1263587D01*
G01X1258400D02*
X1259650D01*
G01X1254463D02*
X1255713D01*
G01X1250526D02*
X1251776D01*
G01X1246589D02*
X1247839D01*
G01X1242652D02*
X1243902D01*
G01X1238715D02*
X1239965D01*
G01X1234778D02*
X1236028D01*
G01X1230841D02*
X1232091D01*
G01X1226904D02*
X1228154D01*
G01X1222967D02*
X1224217D01*
G01X1219030D02*
X1220280D01*
G01X1215093D02*
X1216343D01*
G01X1211156D02*
X1212406D01*
G01X1207219D02*
X1208469D01*
G01X1262407Y658264D02*
X1263517D01*
G01X1254533D02*
X1255643D01*
G01X1246659D02*
X1247769D01*
G01X1238785D02*
X1239895D01*
G01X1230911D02*
X1232021D01*
G01X1223037D02*
X1224147D01*
G01X1215163D02*
X1216273D01*
G01X1207289D02*
X1208399D01*
G01X1262407Y657280D02*
X1263517D01*
G01X1254533D02*
X1255643D01*
G01X1246659D02*
X1247769D01*
G01X1238785D02*
X1239895D01*
G01X1230911D02*
X1232021D01*
G01X1223037D02*
X1224147D01*
G01X1215163D02*
X1216273D01*
G01X1207289D02*
X1208399D01*
G01X1262388Y656830D02*
X1263536D01*
G01X1254514D02*
X1255662D01*
G01X1246640D02*
X1247788D01*
G01X1238766D02*
X1239914D01*
G01X1230892D02*
X1232040D01*
G01X1223018D02*
X1224166D01*
G01X1215144D02*
X1216292D01*
G01X1207270D02*
X1208418D01*
G01X1208409Y656563D02*
X1207279D01*
G01X1216283D02*
X1215153D01*
G01X1224157D02*
X1223027D01*
G01X1232031D02*
X1230901D01*
G01X1239905D02*
X1238775D01*
G01X1247779D02*
X1246649D01*
G01X1255653D02*
X1254523D01*
G01X1263527D02*
X1262397D01*
G01X1208423Y655043D02*
X1207265D01*
G01X1216297D02*
X1215139D01*
G01X1224171D02*
X1223013D01*
G01X1232045D02*
X1230887D01*
G01X1239919D02*
X1238761D01*
G01X1247793D02*
X1246635D01*
G01X1255667D02*
X1254509D01*
G01X1263541D02*
X1262383D01*
G01X1262393Y654776D02*
X1263532D01*
G01X1254519D02*
X1255658D01*
G01X1246644D02*
X1247784D01*
G01X1238770D02*
X1239910D01*
G01X1230896D02*
X1232036D01*
G01X1223022D02*
X1224162D01*
G01X1215148D02*
X1216288D01*
G01X1207274D02*
X1208414D01*
G01X1266311Y654327D02*
X1267487D01*
G01X1262374D02*
X1263550D01*
G01X1258437D02*
X1259613D01*
G01X1254500D02*
X1255676D01*
G01X1250563D02*
X1251739D01*
G01X1246626D02*
X1247802D01*
G01X1242689D02*
X1243865D01*
G01X1238752D02*
X1239928D01*
G01X1234815D02*
X1235991D01*
G01X1230878D02*
X1232054D01*
G01X1226941D02*
X1228117D01*
G01X1223004D02*
X1224180D01*
G01X1219067D02*
X1220243D01*
G01X1215130D02*
X1216306D01*
G01X1211193D02*
X1212369D01*
G01X1207256D02*
X1208432D01*
G01Y653343D02*
X1207256D01*
G01X1212369D02*
X1211193D01*
G01X1216306D02*
X1215130D01*
G01X1220243D02*
X1219067D01*
G01X1224180D02*
X1223004D01*
G01X1228117D02*
X1226941D01*
G01X1232054D02*
X1230878D01*
G01X1235991D02*
X1234815D01*
G01X1239928D02*
X1238752D01*
G01X1243865D02*
X1242689D01*
G01X1247802D02*
X1246626D01*
G01X1251739D02*
X1250563D01*
G01X1255676D02*
X1254500D01*
G01X1259613D02*
X1258437D01*
G01X1263550D02*
X1262374D01*
G01X1267487D02*
X1266311D01*
G01X1212351Y652893D02*
X1211211D01*
G01X1220225D02*
X1219085D01*
G01X1228099D02*
X1226959D01*
G01X1235973D02*
X1234833D01*
G01X1243847D02*
X1242707D01*
G01X1251721D02*
X1250581D01*
G01X1259595D02*
X1258456D01*
G01X1267469D02*
X1266330D01*
G01X1266320Y652626D02*
X1267478D01*
G01X1258446D02*
X1259604D01*
G01X1250572D02*
X1251730D01*
G01X1242698D02*
X1243856D01*
G01X1234824D02*
X1235982D01*
G01X1226950D02*
X1228108D01*
G01X1219076D02*
X1220234D01*
G01X1211202D02*
X1212360D01*
G01X1267492Y659150D02*
X1267505Y659810D01*
G01X1267503Y660738D02*
X1267472Y659150D01*
G01X1266295Y664647D02*
X1266326Y666236D01*
G01X1266306D02*
X1266293Y665575D01*
G01X1263555Y659150D02*
X1263568Y659810D01*
G01X1263566Y660738D02*
X1263535Y659150D01*
G01X1262358Y664647D02*
X1262389Y666236D01*
G01X1262369D02*
X1262356Y665575D01*
G01X1267527Y664735D02*
X1267552Y666236D01*
G01X1267534D02*
X1267524Y665645D01*
G01X1266264Y659150D02*
X1266274Y659740D01*
G01X1266271Y660650D02*
X1266246Y659150D01*
G01X1263590Y664735D02*
X1263615Y666236D01*
G01X1263597D02*
X1263587Y665645D01*
G01X1262327Y659150D02*
X1262337Y659740D01*
G01X1262334Y660650D02*
X1262309Y659150D01*
G01X1266334Y674279D02*
X1266330Y672492D01*
G01X1266320Y672760D02*
X1266325Y674547D01*
G01X1263541Y670342D02*
X1263536Y668555D01*
G01X1263527Y668823D02*
X1263532Y670610D01*
G01X1262397Y656563D02*
X1262393Y654776D01*
G01X1262383Y655043D02*
X1262388Y656830D01*
G01X1267487Y653343D02*
Y654327D01*
G01Y671059D02*
Y672043D01*
G01X1267332Y675980D02*
Y674996D01*
G01X1266466D02*
Y675980D01*
G01X1266311Y654327D02*
Y653343D01*
G01Y672043D02*
Y671059D01*
G01X1265403Y682772D02*
Y677161D01*
G01X1263550Y654327D02*
Y653343D01*
G01Y672043D02*
Y671059D01*
G01X1263395Y658264D02*
Y657280D01*
G01Y668106D02*
Y667122D01*
G01X1262529Y658264D02*
Y657280D01*
G01Y667122D02*
Y668106D01*
G01X1262374Y653343D02*
Y654327D01*
G01Y671059D02*
Y672043D01*
G01X1267473Y674547D02*
X1267478Y672760D01*
G01X1267469Y672492D02*
X1267464Y674279D01*
G01X1263536Y656830D02*
X1263541Y655043D01*
G01X1263532Y654776D02*
X1263527Y656563D01*
G01X1262393Y670610D02*
X1262397Y668823D01*
G01X1262388Y668555D02*
X1262383Y670342D01*
G01X1267552Y659150D02*
X1267527Y660650D01*
G01X1267524Y659740D02*
X1267534Y659150D01*
G01X1266274Y665645D02*
X1266264Y666236D01*
G01X1266246D02*
X1266271Y664735D01*
G01X1263615Y659150D02*
X1263590Y660650D01*
G01X1263587Y659740D02*
X1263597Y659150D01*
G01X1262337Y665645D02*
X1262327Y666236D01*
G01X1262309D02*
X1262334Y664735D01*
G01X1267505Y665575D02*
X1267492Y666236D01*
G01X1267472D02*
X1267503Y664647D01*
G01X1266326Y659150D02*
X1266295Y660738D01*
G01X1266293Y659810D02*
X1266306Y659150D01*
G01X1263568Y665575D02*
X1263555Y666236D01*
G01X1263535D02*
X1263566Y664647D01*
G01X1262389Y659150D02*
X1262358Y660738D01*
G01X1262356Y659810D02*
X1262369Y659150D01*
G01X1259618D02*
X1259631Y659810D01*
G01X1259629Y660738D02*
X1259598Y659150D01*
G01X1258421Y664647D02*
X1258452Y666236D01*
G01X1258432D02*
X1258419Y665575D01*
G01X1255681Y659150D02*
X1255694Y659810D01*
G01X1255692Y660738D02*
X1255661Y659150D01*
G01X1254484Y664647D02*
X1254515Y666236D01*
G01X1254495D02*
X1254482Y665575D01*
G01X1251744Y659150D02*
X1251757Y659810D01*
G01X1251755Y660738D02*
X1251724Y659150D01*
G01X1250547Y664647D02*
X1250578Y666236D01*
G01X1250558D02*
X1250545Y665575D01*
G01X1259653Y664735D02*
X1259678Y666236D01*
G01X1259660D02*
X1259650Y665645D01*
G01X1258390Y659150D02*
X1258400Y659740D01*
G01X1258397Y660650D02*
X1258372Y659150D01*
G01X1255716Y664735D02*
X1255741Y666236D01*
G01X1255723D02*
X1255713Y665645D01*
G01X1254453Y659150D02*
X1254463Y659740D01*
G01X1254460Y660650D02*
X1254435Y659150D01*
G01X1251779Y664735D02*
X1251804Y666236D01*
G01X1251786D02*
X1251776Y665645D01*
G01X1250516Y659150D02*
X1250526Y659740D01*
G01X1250523Y660650D02*
X1250498Y659150D01*
G01X1258460Y674279D02*
X1258456Y672492D01*
G01X1258446Y672760D02*
X1258451Y674547D01*
G01X1255667Y670342D02*
X1255662Y668555D01*
G01X1255653Y668823D02*
X1255658Y670610D01*
G01X1254523Y656563D02*
X1254519Y654776D01*
G01X1254509Y655043D02*
X1254514Y656830D01*
G01X1250586Y674279D02*
X1250581Y672492D01*
G01X1250572Y672760D02*
X1250577Y674547D01*
G01X1260403Y682772D02*
Y677161D01*
G01X1259613Y653343D02*
Y654327D01*
G01Y671059D02*
Y672043D01*
G01X1259458Y675980D02*
Y674996D01*
G01X1258592D02*
Y675980D01*
G01X1258437Y654327D02*
Y653343D01*
G01Y672043D02*
Y671059D01*
G01X1255676Y653343D02*
Y654327D01*
G01Y672043D02*
Y671059D01*
G01X1255521Y658264D02*
Y657280D01*
G01Y668106D02*
Y667122D01*
G01X1254655Y658264D02*
Y657280D01*
G01Y667122D02*
Y668106D01*
G01X1254500Y654327D02*
Y653343D01*
G01Y671059D02*
Y672043D01*
G01X1251739Y653343D02*
Y654327D01*
G01Y671059D02*
Y672043D01*
G01X1251584Y675980D02*
Y674996D01*
G01X1250718D02*
Y675980D01*
G01X1250563Y654327D02*
Y653343D01*
G01Y672043D02*
Y671059D01*
G01X1259599Y674547D02*
X1259604Y672760D01*
G01X1259595Y672492D02*
X1259590Y674279D01*
G01X1255662Y656830D02*
X1255667Y655043D01*
G01X1255658Y654776D02*
X1255653Y656563D01*
G01X1254519Y670610D02*
X1254523Y668823D01*
G01X1254514Y668555D02*
X1254509Y670342D01*
G01X1251725Y674547D02*
X1251730Y672760D01*
G01X1251721Y672492D02*
X1251716Y674279D01*
G01X1259678Y659150D02*
X1259653Y660650D01*
G01X1259650Y659740D02*
X1259660Y659150D01*
G01X1258400Y665645D02*
X1258390Y666236D01*
G01X1258372D02*
X1258397Y664735D01*
G01X1255741Y659150D02*
X1255716Y660650D01*
G01X1255713Y659740D02*
X1255723Y659150D01*
G01X1254463Y665645D02*
X1254453Y666236D01*
G01X1254435D02*
X1254460Y664735D01*
G01X1251804Y659150D02*
X1251779Y660650D01*
G01X1251776Y659740D02*
X1251786Y659150D01*
G01X1250526Y665645D02*
X1250516Y666236D01*
G01X1250498D02*
X1250523Y664735D01*
G01X1259631Y665575D02*
X1259618Y666236D01*
G01X1259598D02*
X1259629Y664647D01*
G01X1258452Y659150D02*
X1258421Y660738D01*
G01X1258419Y659810D02*
X1258432Y659150D01*
G01X1255694Y665575D02*
X1255681Y666236D01*
G01X1255661D02*
X1255692Y664647D01*
G01X1254515Y659150D02*
X1254484Y660738D01*
G01X1254482Y659810D02*
X1254495Y659150D01*
G01X1251757Y665575D02*
X1251744Y666236D01*
G01X1251724D02*
X1251755Y664647D01*
G01X1250578Y659150D02*
X1250547Y660738D01*
G01X1250545Y659810D02*
X1250558Y659150D01*
G01X1247807D02*
X1247820Y659810D01*
G01X1247818Y660738D02*
X1247787Y659150D01*
G01X1246610Y664647D02*
X1246641Y666236D01*
G01X1246621D02*
X1246608Y665575D01*
G01X1243870Y659150D02*
X1243883Y659810D01*
G01X1243881Y660738D02*
X1243850Y659150D01*
G01X1242673Y664647D02*
X1242704Y666236D01*
G01X1242684D02*
X1242671Y665575D01*
G01X1239933Y659150D02*
X1239946Y659810D01*
G01X1239944Y660738D02*
X1239913Y659150D01*
G01X1238736Y664647D02*
X1238767Y666236D01*
G01X1238747D02*
X1238734Y665575D01*
G01X1247842Y664735D02*
X1247867Y666236D01*
G01X1247849D02*
X1247839Y665645D01*
G01X1246579Y659150D02*
X1246589Y659740D01*
G01X1246586Y660650D02*
X1246561Y659150D01*
G01X1243905Y664735D02*
X1243930Y666236D01*
G01X1243912D02*
X1243902Y665645D01*
G01X1242642Y659150D02*
X1242652Y659740D01*
G01X1242649Y660650D02*
X1242624Y659150D01*
G01X1239968Y664735D02*
X1239993Y666236D01*
G01X1239975D02*
X1239965Y665645D01*
G01X1238705Y659150D02*
X1238715Y659740D01*
G01X1238712Y660650D02*
X1238687Y659150D01*
G01X1247793Y670342D02*
X1247788Y668555D01*
G01X1247779Y668823D02*
X1247784Y670610D01*
G01X1246649Y656563D02*
X1246644Y654776D01*
G01X1246635Y655043D02*
X1246640Y656830D01*
G01X1242712Y674279D02*
X1242707Y672492D01*
G01X1242698Y672760D02*
X1242703Y674547D01*
G01X1239919Y670342D02*
X1239914Y668555D01*
G01X1239905Y668823D02*
X1239910Y670610D01*
G01X1238775Y656563D02*
X1238770Y654776D01*
G01X1238761Y655043D02*
X1238766Y656830D01*
G01X1247802Y654327D02*
Y653343D01*
G01Y672043D02*
Y671059D01*
G01X1247647Y658264D02*
Y657280D01*
G01Y668106D02*
Y667122D01*
G01X1246781Y658264D02*
Y657280D01*
G01Y667122D02*
Y668106D01*
G01X1246626Y653343D02*
Y654327D01*
G01Y671059D02*
Y672043D01*
G01X1244498Y682772D02*
Y677161D01*
G01X1243865Y653343D02*
Y654327D01*
G01Y671059D02*
Y672043D01*
G01X1243710Y675980D02*
Y674996D01*
G01X1242844D02*
Y675980D01*
G01X1242689Y654327D02*
Y653343D01*
G01Y672043D02*
Y671059D01*
G01X1239928Y654327D02*
Y653343D01*
G01Y672043D02*
Y671059D01*
G01X1239773Y658264D02*
Y657280D01*
G01Y668106D02*
Y667122D01*
G01X1239498Y682772D02*
Y677161D01*
G01X1238907Y658264D02*
Y657280D01*
G01Y667122D02*
Y668106D01*
G01X1238752Y653343D02*
Y654327D01*
G01Y671059D02*
Y672043D01*
G01X1235991Y653343D02*
Y654327D01*
G01Y671059D02*
Y672043D01*
G01X1235836Y675980D02*
Y674996D01*
G01X1247788Y656830D02*
X1247793Y655043D01*
G01X1247784Y654776D02*
X1247779Y656563D01*
G01X1246644Y670610D02*
X1246649Y668823D01*
G01X1246640Y668555D02*
X1246635Y670342D01*
G01X1243851Y674547D02*
X1243856Y672760D01*
G01X1243847Y672492D02*
X1243842Y674279D01*
G01X1239914Y656830D02*
X1239919Y655043D01*
G01X1239910Y654776D02*
X1239905Y656563D01*
G01X1238770Y670610D02*
X1238775Y668823D01*
G01X1238766Y668555D02*
X1238761Y670342D01*
G01X1235977Y674547D02*
X1235982Y672760D01*
G01X1235973Y672492D02*
X1235968Y674279D01*
G01X1247867Y659150D02*
X1247842Y660650D01*
G01X1247839Y659740D02*
X1247849Y659150D01*
G01X1246589Y665645D02*
X1246579Y666236D01*
G01X1246561D02*
X1246586Y664735D01*
G01X1243930Y659150D02*
X1243905Y660650D01*
G01X1243902Y659740D02*
X1243912Y659150D01*
G01X1242652Y665645D02*
X1242642Y666236D01*
G01X1242624D02*
X1242649Y664735D01*
G01X1239993Y659150D02*
X1239968Y660650D01*
G01X1239965Y659740D02*
X1239975Y659150D01*
G01X1238715Y665645D02*
X1238705Y666236D01*
G01X1238687D02*
X1238712Y664735D01*
G01X1236056Y659150D02*
X1236031Y660650D01*
G01X1236028Y659740D02*
X1236038Y659150D01*
G01X1247820Y665575D02*
X1247807Y666236D01*
G01X1247787D02*
X1247818Y664647D01*
G01X1246641Y659150D02*
X1246610Y660738D01*
G01X1246608Y659810D02*
X1246621Y659150D01*
G01X1243883Y665575D02*
X1243870Y666236D01*
G01X1243850D02*
X1243881Y664647D01*
G01X1242704Y659150D02*
X1242673Y660738D01*
G01X1242671Y659810D02*
X1242684Y659150D01*
G01X1239946Y665575D02*
X1239933Y666236D01*
G01X1239913D02*
X1239944Y664647D01*
G01X1238767Y659150D02*
X1238736Y660738D01*
G01X1238734Y659810D02*
X1238747Y659150D01*
G01X1236009Y665575D02*
X1235996Y666236D01*
G01X1235976D02*
X1236007Y664647D01*
G01X1235996Y659150D02*
X1236009Y659810D01*
G01X1236007Y660738D02*
X1235976Y659150D01*
G01X1234799Y664647D02*
X1234830Y666236D01*
G01X1234810D02*
X1234797Y665575D01*
G01X1232059Y659150D02*
X1232072Y659810D01*
G01X1232070Y660738D02*
X1232039Y659150D01*
G01X1230862Y664647D02*
X1230893Y666236D01*
G01X1230873D02*
X1230860Y665575D01*
G01X1228122Y659150D02*
X1228135Y659810D01*
G01X1228133Y660738D02*
X1228102Y659150D01*
G01X1226925Y664647D02*
X1226956Y666236D01*
G01X1226936D02*
X1226923Y665575D01*
G01X1224185Y659150D02*
X1224198Y659810D01*
G01X1224196Y660738D02*
X1224165Y659150D01*
G01X1236031Y664735D02*
X1236056Y666236D01*
G01X1236038D02*
X1236028Y665645D01*
G01X1234768Y659150D02*
X1234778Y659740D01*
G01X1234775Y660650D02*
X1234750Y659150D01*
G01X1232094Y664735D02*
X1232119Y666236D01*
G01X1232101D02*
X1232091Y665645D01*
G01X1230831Y659150D02*
X1230841Y659740D01*
G01X1230838Y660650D02*
X1230813Y659150D01*
G01X1228157Y664735D02*
X1228182Y666236D01*
G01X1228164D02*
X1228154Y665645D01*
G01X1226894Y659150D02*
X1226904Y659740D01*
G01X1226901Y660650D02*
X1226876Y659150D01*
G01X1224220Y664735D02*
X1224245Y666236D01*
G01X1224227D02*
X1224217Y665645D01*
G01X1234838Y674279D02*
X1234833Y672492D01*
G01X1234824Y672760D02*
X1234829Y674547D01*
G01X1232045Y670342D02*
X1232040Y668555D01*
G01X1232031Y668823D02*
X1232036Y670610D01*
G01X1230901Y656563D02*
X1230896Y654776D01*
G01X1230887Y655043D02*
X1230892Y656830D01*
G01X1226964Y674279D02*
X1226959Y672492D01*
G01X1226950Y672760D02*
X1226955Y674547D01*
G01X1224171Y670342D02*
X1224166Y668555D01*
G01X1224157Y668823D02*
X1224162Y670610D01*
G01X1223027Y656563D02*
X1223022Y654776D01*
G01X1223013Y655043D02*
X1223018Y656830D01*
G01X1234970Y674996D02*
Y675980D01*
G01X1234815Y654327D02*
Y653343D01*
G01Y672043D02*
Y671059D01*
G01X1232054Y654327D02*
Y653343D01*
G01Y672043D02*
Y671059D01*
G01X1231899Y658264D02*
Y657280D01*
G01Y668106D02*
Y667122D01*
G01X1231033Y658264D02*
Y657280D01*
G01Y667122D02*
Y668106D01*
G01X1230878Y653343D02*
Y654327D01*
G01Y671059D02*
Y672043D01*
G01X1228117Y653343D02*
Y654327D01*
G01Y671059D02*
Y672043D01*
G01X1227962Y675980D02*
Y674996D01*
G01X1227096D02*
Y675980D01*
G01X1226941Y654327D02*
Y653343D01*
G01Y672043D02*
Y671059D01*
G01X1224180Y654327D02*
Y653343D01*
G01Y672043D02*
Y671059D01*
G01X1224025Y658264D02*
Y657280D01*
G01Y668106D02*
Y667122D01*
G01X1223592Y682772D02*
Y677161D01*
G01X1223159Y658264D02*
Y657280D01*
G01Y667122D02*
Y668106D01*
G01X1223004Y653343D02*
Y654327D01*
G01Y671059D02*
Y672043D01*
G01X1232040Y656830D02*
X1232045Y655043D01*
G01X1232036Y654776D02*
X1232031Y656563D01*
G01X1230896Y670610D02*
X1230901Y668823D01*
G01X1230892Y668555D02*
X1230887Y670342D01*
G01X1228103Y674547D02*
X1228108Y672760D01*
G01X1228099Y672492D02*
X1228094Y674279D01*
G01X1224166Y656830D02*
X1224171Y655043D01*
G01X1224162Y654776D02*
X1224157Y656563D01*
G01X1223022Y670610D02*
X1223027Y668823D01*
G01X1223018Y668555D02*
X1223013Y670342D01*
G01X1234778Y665645D02*
X1234768Y666236D01*
G01X1234750D02*
X1234775Y664735D01*
G01X1232119Y659150D02*
X1232094Y660650D01*
G01X1232091Y659740D02*
X1232101Y659150D01*
G01X1230841Y665645D02*
X1230831Y666236D01*
G01X1230813D02*
X1230838Y664735D01*
G01X1228182Y659150D02*
X1228157Y660650D01*
G01X1228154Y659740D02*
X1228164Y659150D01*
G01X1226904Y665645D02*
X1226894Y666236D01*
G01X1226876D02*
X1226901Y664735D01*
G01X1224245Y659150D02*
X1224220Y660650D01*
G01X1224217Y659740D02*
X1224227Y659150D01*
G01X1222967Y665645D02*
X1222957Y666236D01*
G01X1222939D02*
X1222964Y664735D01*
G01X1234830Y659150D02*
X1234799Y660738D01*
G01X1234797Y659810D02*
X1234810Y659150D01*
G01X1232072Y665575D02*
X1232059Y666236D01*
G01X1232039D02*
X1232070Y664647D01*
G01X1230893Y659150D02*
X1230862Y660738D01*
G01X1230860Y659810D02*
X1230873Y659150D01*
G01X1228135Y665575D02*
X1228122Y666236D01*
G01X1228102D02*
X1228133Y664647D01*
G01X1226956Y659150D02*
X1226925Y660738D01*
G01X1226923Y659810D02*
X1226936Y659150D01*
G01X1224198Y665575D02*
X1224185Y666236D01*
G01X1224165D02*
X1224196Y664647D01*
G01X1223019Y659150D02*
X1222988Y660738D01*
G01X1222986Y659810D02*
X1222999Y659150D01*
G01X1222988Y664647D02*
X1223019Y666236D01*
G01X1222999D02*
X1222986Y665575D01*
G01X1220248Y659150D02*
X1220261Y659810D01*
G01X1220259Y660738D02*
X1220228Y659150D01*
G01X1219051Y664647D02*
X1219082Y666236D01*
G01X1219062D02*
X1219049Y665575D01*
G01X1216311Y659150D02*
X1216324Y659810D01*
G01X1216322Y660738D02*
X1216291Y659150D01*
G01X1215114Y664647D02*
X1215145Y666236D01*
G01X1215125D02*
X1215112Y665575D01*
G01X1212374Y659150D02*
X1212387Y659810D01*
G01X1212385Y660738D02*
X1212354Y659150D01*
G01X1211177Y664647D02*
X1211208Y666236D01*
G01X1211188D02*
X1211175Y665575D01*
G01X1222957Y659150D02*
X1222967Y659740D01*
G01X1222964Y660650D02*
X1222939Y659150D01*
G01X1220283Y664735D02*
X1220308Y666236D01*
G01X1220290D02*
X1220280Y665645D01*
G01X1219020Y659150D02*
X1219030Y659740D01*
G01X1219027Y660650D02*
X1219002Y659150D01*
G01X1216346Y664735D02*
X1216371Y666236D01*
G01X1216353D02*
X1216343Y665645D01*
G01X1215083Y659150D02*
X1215093Y659740D01*
G01X1215090Y660650D02*
X1215065Y659150D01*
G01X1212409Y664735D02*
X1212434Y666236D01*
G01X1212416D02*
X1212406Y665645D01*
G01X1211146Y659150D02*
X1211156Y659740D01*
G01X1211153Y660650D02*
X1211128Y659150D01*
G01X1219090Y674279D02*
X1219085Y672492D01*
G01X1219076Y672760D02*
X1219081Y674547D01*
G01X1216297Y670342D02*
X1216292Y668555D01*
G01X1216283Y668823D02*
X1216288Y670610D01*
G01X1215153Y656563D02*
X1215148Y654776D01*
G01X1215139Y655043D02*
X1215144Y656830D01*
G01X1211216Y674279D02*
X1211211Y672492D01*
G01X1211202Y672760D02*
X1211207Y674547D01*
G01X1220243Y653343D02*
Y654327D01*
G01Y671059D02*
Y672043D01*
G01X1220088Y675980D02*
Y674996D01*
G01X1219222D02*
Y675980D01*
G01X1219067Y654327D02*
Y653343D01*
G01Y672043D02*
Y671059D01*
G01X1218592Y682772D02*
Y677161D01*
G01X1216306Y654327D02*
Y653343D01*
G01Y672043D02*
Y671059D01*
G01X1216151Y658264D02*
Y657280D01*
G01Y668106D02*
Y667122D01*
G01X1215285Y658264D02*
Y657280D01*
G01Y667122D02*
Y668106D01*
G01X1215130Y653343D02*
Y654327D01*
G01Y671059D02*
Y672043D01*
G01X1212369Y653343D02*
Y654327D01*
G01Y671059D02*
Y672043D01*
G01X1212214Y675980D02*
Y674996D01*
G01X1211348D02*
Y675980D01*
G01X1211193Y654327D02*
Y653343D01*
G01Y672043D02*
Y671059D01*
G01X1220229Y674547D02*
X1220234Y672760D01*
G01X1220225Y672492D02*
X1220220Y674279D01*
G01X1216292Y656830D02*
X1216297Y655043D01*
G01X1216288Y654776D02*
X1216283Y656563D01*
G01X1215148Y670610D02*
X1215153Y668823D01*
G01X1215144Y668555D02*
X1215139Y670342D01*
G01X1212355Y674547D02*
X1212360Y672760D01*
G01X1212351Y672492D02*
X1212346Y674279D01*
G01X1220308Y659150D02*
X1220283Y660650D01*
G01X1220280Y659740D02*
X1220290Y659150D01*
G01X1219030Y665645D02*
X1219020Y666236D01*
G01X1219002D02*
X1219027Y664735D01*
G01X1216371Y659150D02*
X1216346Y660650D01*
G01X1216343Y659740D02*
X1216353Y659150D01*
G01X1215093Y665645D02*
X1215083Y666236D01*
G01X1215065D02*
X1215090Y664735D01*
G01X1212434Y659150D02*
X1212409Y660650D01*
G01X1212406Y659740D02*
X1212416Y659150D01*
G01X1211156Y665645D02*
X1211146Y666236D01*
G01X1211128D02*
X1211153Y664735D01*
G01X1220261Y665575D02*
X1220248Y666236D01*
G01X1220228D02*
X1220259Y664647D01*
G01X1219082Y659150D02*
X1219051Y660738D01*
G01X1219049Y659810D02*
X1219062Y659150D01*
G01X1216324Y665575D02*
X1216311Y666236D01*
G01X1216291D02*
X1216322Y664647D01*
G01X1215145Y659150D02*
X1215114Y660738D01*
G01X1215112Y659810D02*
X1215125Y659150D01*
G01X1212387Y665575D02*
X1212374Y666236D01*
G01X1212354D02*
X1212385Y664647D01*
G01X1211208Y659150D02*
X1211177Y660738D01*
G01X1211175Y659810D02*
X1211188Y659150D01*
G01X1208437D02*
X1208450Y659810D01*
G01X1208448Y660738D02*
X1208417Y659150D01*
G01X1207240Y664647D02*
X1207271Y666236D01*
G01X1207251D02*
X1207238Y665575D01*
G01X1208472Y664735D02*
X1208497Y666236D01*
G01X1208479D02*
X1208469Y665645D01*
G01X1207209Y659150D02*
X1207219Y659740D01*
G01X1207216Y660650D02*
X1207191Y659150D01*
G01X1208423Y670342D02*
X1208418Y668555D01*
G01X1208409Y668823D02*
X1208414Y670610D01*
G01X1207279Y656563D02*
X1207274Y654776D01*
G01X1207265Y655043D02*
X1207270Y656830D01*
G01X1208432Y654327D02*
Y653343D01*
G01Y672043D02*
Y671059D01*
G01X1208277Y658264D02*
Y657280D01*
G01Y668106D02*
Y667122D01*
G01X1207411Y658264D02*
Y657280D01*
G01Y667122D02*
Y668106D01*
G01X1207256Y653343D02*
Y654327D01*
G01Y671059D02*
Y672043D01*
G01X1208418Y656830D02*
X1208423Y655043D01*
G01X1208414Y654776D02*
X1208409Y656563D01*
G01X1207274Y670610D02*
X1207279Y668823D01*
G01X1207270Y668555D02*
X1207265Y670342D01*
G01X1208497Y659150D02*
X1208472Y660650D01*
G01X1208469Y659740D02*
X1208479Y659150D01*
G01X1207219Y665645D02*
X1207209Y666236D01*
G01X1207191D02*
X1207216Y664735D01*
G01X1208450Y665575D02*
X1208437Y666236D01*
G01X1208417D02*
X1208448Y664647D01*
G01X1207271Y659150D02*
X1207240Y660738D01*
G01X1207238Y659810D02*
X1207251Y659150D01*
G01X1225315Y934504D02*
Y917181D01*
G01X1316546Y270717D02*
Y300245D01*
G01Y290402D02*
Y270717D01*
G01X1328278Y272686D02*
Y256150D01*
G01X1325522D02*
Y272686D01*
G01X1324341D02*
Y256150D01*
G01X1321585D02*
Y272686D01*
G01X1320404D02*
Y256150D01*
G01X1317648D02*
Y272686D01*
G01X1316467D02*
Y256150D01*
G01X1313711D02*
Y272686D01*
G01X1312530D02*
Y256150D01*
G01X1309774D02*
Y272686D01*
G01X1308593D02*
Y256150D01*
G01X1305837D02*
Y272686D01*
G01X1304656D02*
Y256150D01*
G01X1301900D02*
Y272686D01*
G01X1300719D02*
Y256150D01*
G01X1297963D02*
Y272686D01*
G01X1296782D02*
Y256150D01*
G01X1294026D02*
Y272686D01*
G01X1292845D02*
Y256150D01*
G01X1290089D02*
Y272686D01*
G01X1288908D02*
Y256150D01*
G01X1286152D02*
Y272686D01*
G01X1284971D02*
Y256150D01*
G01X1282215D02*
Y272686D01*
G01X1281034D02*
Y256150D01*
G01X1278278D02*
Y272686D01*
G01X1277097D02*
Y256150D01*
G01X1274341D02*
Y272686D01*
G01X1273160D02*
Y256150D01*
G01X1270404D02*
Y272686D01*
G01X1269223D02*
Y256150D01*
G01X1325522Y272686D02*
X1328278D01*
G01X1321585D02*
X1324341D01*
G01X1317648D02*
X1320404D01*
G01X1313711D02*
X1316467D01*
G01X1309774D02*
X1312530D01*
G01X1305837D02*
X1308593D01*
G01X1301900D02*
X1304656D01*
G01X1297963D02*
X1300719D01*
G01X1294026D02*
X1296782D01*
G01X1290089D02*
X1292845D01*
G01X1286152D02*
X1288908D01*
G01X1282215D02*
X1284971D01*
G01X1278278D02*
X1281034D01*
G01X1274341D02*
X1277097D01*
G01X1270404D02*
X1273160D01*
G01Y256150D02*
X1270404D01*
G01X1277097D02*
X1274341D01*
G01X1281034D02*
X1278278D01*
G01X1284971D02*
X1282215D01*
G01X1288908D02*
X1286152D01*
G01X1292845D02*
X1290089D01*
G01X1296782D02*
X1294026D01*
G01X1300719D02*
X1297963D01*
G01X1304656D02*
X1301900D01*
G01X1308593D02*
X1305837D01*
G01X1312530D02*
X1309774D01*
G01X1316467D02*
X1313711D01*
G01X1320404D02*
X1317648D01*
G01X1324341D02*
X1321585D01*
G01X1328278D02*
X1325522D01*
G01X1316546Y347845D02*
Y300245D01*
G01Y310087D02*
Y347845D01*
G01X1353475Y290402D02*
X1312609D01*
G01X1353475Y310087D02*
X1312609D01*
G01X1304380Y364115D02*
X1363317D01*
G01X1353475D02*
X1304380D01*
G01X1320994Y349457D02*
G03X1324931Y353394I0J3937D01*
G01X1328869Y357331D02*
G03X1324931Y353394I-1J-3937D01*
G01X1328869Y357331D02*
X1468632D01*
G01X1328513Y589858D02*
Y606394D01*
G01X1327332D02*
Y589858D01*
G01X1324576D02*
Y606394D01*
G01X1323395D02*
Y589858D01*
G01X1320639D02*
Y606394D01*
G01X1319458D02*
Y589858D01*
G01X1316702D02*
Y606394D01*
G01X1315521D02*
Y589858D01*
G01X1312765D02*
Y606394D01*
G01X1311584D02*
Y589858D01*
G01X1308828D02*
Y606394D01*
G01X1307647D02*
Y589858D01*
G01X1304891D02*
Y606394D01*
G01X1303710D02*
Y589858D01*
G01X1300954D02*
Y606394D01*
G01X1299773D02*
Y589858D01*
G01X1297017D02*
Y606394D01*
G01X1295836D02*
Y589858D01*
G01X1293080D02*
Y606394D01*
G01X1291899D02*
Y589858D01*
G01X1289143D02*
Y606394D01*
G01X1287962D02*
Y589858D01*
G01X1285206D02*
Y606394D01*
G01X1284025D02*
Y589858D01*
G01X1281269D02*
Y606394D01*
G01X1280088D02*
Y589858D01*
G01X1277332D02*
Y606394D01*
G01X1276151D02*
Y589858D01*
G01X1273395D02*
Y606394D01*
G01X1272214D02*
Y589858D01*
G01X1269458D02*
Y606394D01*
G01X1268277D02*
Y589858D01*
G01X1272214D02*
X1269458D01*
G01X1276151D02*
X1273395D01*
G01X1280088D02*
X1277332D01*
G01X1284025D02*
X1281269D01*
G01X1287962D02*
X1285206D01*
G01X1291899D02*
X1289143D01*
G01X1295836D02*
X1293080D01*
G01X1299773D02*
X1297017D01*
G01X1303710D02*
X1300954D01*
G01X1307647D02*
X1304891D01*
G01X1311584D02*
X1308828D01*
G01X1315521D02*
X1312765D01*
G01X1319458D02*
X1316702D01*
G01X1323395D02*
X1320639D01*
G01X1327332D02*
X1324576D01*
G01X1331269D02*
X1328513D01*
G01X1322596Y652626D02*
X1322591Y650839D01*
G01X1322582Y651106D02*
X1322587Y652893D01*
G01X1314722Y652626D02*
X1314717Y650839D01*
G01X1314708Y651106D02*
X1314713Y652893D01*
G01X1322450Y650390D02*
Y649406D01*
G01X1321584Y650390D02*
Y649406D01*
G01X1314576Y650390D02*
Y649406D01*
G01X1313710Y650390D02*
Y649406D01*
G01X1321448Y652893D02*
X1321452Y651106D01*
G01X1321443Y650839D02*
X1321438Y652626D01*
G01X1313574Y652893D02*
X1313578Y651106D01*
G01X1313569Y650839D02*
X1313564Y652626D01*
G01X1306848D02*
X1306843Y650839D01*
G01X1306834Y651106D02*
X1306839Y652893D01*
G01X1306702Y650390D02*
Y649406D01*
G01X1305836Y650390D02*
Y649406D01*
G01X1305700Y652893D02*
X1305704Y651106D01*
G01X1305695Y650839D02*
X1305690Y652626D01*
G01X1298974D02*
X1298969Y650839D01*
G01X1298960Y651106D02*
X1298965Y652893D01*
G01X1291100Y652626D02*
X1291095Y650839D01*
G01X1291086Y651106D02*
X1291091Y652893D01*
G01X1298828Y650390D02*
Y649406D01*
G01X1297962Y650390D02*
Y649406D01*
G01X1290954Y650390D02*
Y649406D01*
G01X1290088Y650390D02*
Y649406D01*
G01X1297826Y652893D02*
X1297830Y651106D01*
G01X1297821Y650839D02*
X1297816Y652626D01*
G01X1289952Y652893D02*
X1289956Y651106D01*
G01X1289947Y650839D02*
X1289942Y652626D01*
G01X1321452Y651106D02*
X1322582D01*
G01X1313578D02*
X1314708D01*
G01X1305704D02*
X1306834D01*
G01X1297830D02*
X1298960D01*
G01X1289956D02*
X1291086D01*
G01X1282082D02*
X1283212D01*
G01X1274208D02*
X1275338D01*
G01X1275347Y650839D02*
X1274199D01*
G01X1283221D02*
X1282073D01*
G01X1291095D02*
X1289947D01*
G01X1298969D02*
X1297821D01*
G01X1306843D02*
X1305695D01*
G01X1314717D02*
X1313569D01*
G01X1322591D02*
X1321443D01*
G01X1275328Y650390D02*
X1274218D01*
G01X1283202D02*
X1282092D01*
G01X1291076D02*
X1289966D01*
G01X1298950D02*
X1297840D01*
G01X1306824D02*
X1305714D01*
G01X1314698D02*
X1313588D01*
G01X1322572D02*
X1321462D01*
G01Y649406D02*
X1322572D01*
G01X1313588D02*
X1314698D01*
G01X1305714D02*
X1306824D01*
G01X1297840D02*
X1298950D01*
G01X1289966D02*
X1291076D01*
G01X1282092D02*
X1283202D01*
G01X1274218D02*
X1275328D01*
G01X1283226Y652626D02*
X1283221Y650839D01*
G01X1283212Y651106D02*
X1283217Y652893D01*
G01X1275352Y652626D02*
X1275347Y650839D01*
G01X1275338Y651106D02*
X1275343Y652893D01*
G01X1283080Y650390D02*
Y649406D01*
G01X1282214Y650390D02*
Y649406D01*
G01X1275206Y650390D02*
Y649406D01*
G01X1282078Y652893D02*
X1282082Y651106D01*
G01X1282073Y650839D02*
X1282068Y652626D01*
G01X1274340Y650390D02*
Y649406D01*
G01X1274204Y652893D02*
X1274208Y651106D01*
G01X1274199Y650839D02*
X1274194Y652626D01*
G01X1328513Y606394D02*
X1331269D01*
G01X1324576D02*
X1327332D01*
G01X1320639D02*
X1323395D01*
G01X1316702D02*
X1319458D01*
G01X1312765D02*
X1315521D01*
G01X1308828D02*
X1311584D01*
G01X1304891D02*
X1307647D01*
G01X1300954D02*
X1303710D01*
G01X1297017D02*
X1299773D01*
G01X1293080D02*
X1295836D01*
G01X1289143D02*
X1291899D01*
G01X1285206D02*
X1287962D01*
G01X1281269D02*
X1284025D01*
G01X1277332D02*
X1280088D01*
G01X1273395D02*
X1276151D01*
G01X1269458D02*
X1272214D01*
G01X1312175Y691039D02*
Y706394D01*
G01X1308238Y683165D02*
G03X1312175Y687102I0J3937D01*
G01X1316112Y691039D02*
G03X1312175Y687102I0J-3937D01*
G01X1316112Y691039D02*
X1347608D01*
G01X1316112D02*
G03X1312175Y687102I0J-3937D01*
G01X1308238Y683165D02*
G03X1312175Y687102I0J3937D01*
G01X1308238Y683165D02*
G03X1312175Y687102I0J3937D01*
G01X1316112Y691039D02*
G03X1312175Y687102I0J-3937D01*
G01X1326533Y670342D02*
X1326528Y668555D01*
G01X1326519Y668823D02*
X1326524Y670610D01*
G01X1328120Y682772D02*
Y677161D01*
G01X1326543Y654327D02*
Y653343D01*
G01Y672043D02*
Y671059D01*
G01X1326528Y656830D02*
X1326533Y655043D01*
G01X1326524Y654776D02*
X1326519Y656563D01*
G01X1326607Y659150D02*
X1326582Y660650D01*
G01X1326580Y659740D02*
X1326589Y659150D01*
G01X1326560Y665575D02*
X1326547Y666236D01*
G01X1326527D02*
X1326558Y664647D01*
G01X1316112Y691039D02*
X1455876D01*
G01X1302214Y682772D02*
X1286309D01*
G01X1323120D02*
X1307214D01*
G01X1344025D02*
X1328120D01*
G01X1326547Y659150D02*
X1326560Y659810D01*
G01X1326558Y660738D02*
X1326527Y659150D01*
G01X1325350Y664647D02*
X1325381Y666236D01*
G01X1325361D02*
X1325348Y665575D01*
G01X1322610Y659150D02*
X1322623Y659810D01*
G01X1322621Y660738D02*
X1322590Y659150D01*
G01X1321413Y664647D02*
X1321444Y666236D01*
G01X1321424D02*
X1321411Y665575D01*
G01X1318673Y659150D02*
X1318686Y659810D01*
G01X1318684Y660738D02*
X1318653Y659150D01*
G01X1317476Y664647D02*
X1317507Y666236D01*
G01X1317487D02*
X1317474Y665575D01*
G01X1314736Y659150D02*
X1314749Y659810D01*
G01X1314747Y660738D02*
X1314716Y659150D01*
G01X1326582Y664735D02*
X1326607Y666236D01*
G01X1326589D02*
X1326580Y665645D01*
G01X1325319Y659150D02*
X1325329Y659740D01*
G01X1325326Y660650D02*
X1325302Y659150D01*
G01X1322645Y664735D02*
X1322670Y666236D01*
G01X1322652D02*
X1322643Y665645D01*
G01X1321382Y659150D02*
X1321392Y659740D01*
G01X1321389Y660650D02*
X1321365Y659150D01*
G01X1318708Y664735D02*
X1318733Y666236D01*
G01X1318715D02*
X1318706Y665645D01*
G01X1317445Y659150D02*
X1317455Y659740D01*
G01X1317452Y660650D02*
X1317428Y659150D01*
G01X1314771Y664735D02*
X1314796Y666236D01*
G01X1314778D02*
X1314769Y665645D01*
G01X1325389Y656563D02*
X1325385Y654776D01*
G01X1325375Y655043D02*
X1325380Y656830D01*
G01X1321452Y674279D02*
X1321448Y672492D01*
G01X1321438Y672760D02*
X1321443Y674547D01*
G01X1318659Y670342D02*
X1318654Y668555D01*
G01X1318645Y668823D02*
X1318650Y670610D01*
G01X1317515Y656563D02*
X1317511Y654776D01*
G01X1317501Y655043D02*
X1317506Y656830D01*
G01X1313578Y674279D02*
X1313574Y672492D01*
G01X1313564Y672760D02*
X1313569Y674547D01*
G01X1326387Y658264D02*
Y657280D01*
G01Y668106D02*
Y667122D01*
G01X1325521Y658264D02*
Y657280D01*
G01Y667122D02*
Y668106D01*
G01X1325366Y653343D02*
Y654327D01*
G01Y671059D02*
Y672043D01*
G01X1323120Y682772D02*
Y677161D01*
G01X1322606Y653343D02*
Y654327D01*
G01Y671059D02*
Y672043D01*
G01X1322450Y675980D02*
Y674996D01*
G01X1321584D02*
Y675980D01*
G01X1321429Y654327D02*
Y653343D01*
G01Y672043D02*
Y671059D01*
G01X1318669Y654327D02*
Y653343D01*
G01Y672043D02*
Y671059D01*
G01X1318513Y658264D02*
Y657280D01*
G01Y668106D02*
Y667122D01*
G01X1317647Y658264D02*
Y657280D01*
G01Y667122D02*
Y668106D01*
G01X1317492Y653343D02*
Y654327D01*
G01Y671059D02*
Y672043D01*
G01X1314731Y653343D02*
Y654327D01*
G01Y671059D02*
Y672043D01*
G01X1314576Y675980D02*
Y674996D01*
G01X1313710D02*
Y675980D01*
G01X1313555Y654327D02*
Y653343D01*
G01Y672043D02*
Y671059D01*
G01X1325385Y670610D02*
X1325389Y668823D01*
G01X1325380Y668555D02*
X1325375Y670342D01*
G01X1322591Y674547D02*
X1322596Y672760D01*
G01X1322587Y672492D02*
X1322582Y674279D01*
G01X1318654Y656830D02*
X1318659Y655043D01*
G01X1318650Y654776D02*
X1318645Y656563D01*
G01X1317511Y670610D02*
X1317515Y668823D01*
G01X1317506Y668555D02*
X1317501Y670342D01*
G01X1314717Y674547D02*
X1314722Y672760D01*
G01X1314713Y672492D02*
X1314708Y674279D01*
G01X1325329Y665645D02*
X1325319Y666236D01*
G01X1325302D02*
X1325326Y664735D01*
G01X1322670Y659150D02*
X1322645Y660650D01*
G01X1322643Y659740D02*
X1322652Y659150D01*
G01X1321392Y665645D02*
X1321382Y666236D01*
G01X1321365D02*
X1321389Y664735D01*
G01X1318733Y659150D02*
X1318708Y660650D01*
G01X1318706Y659740D02*
X1318715Y659150D01*
G01X1317455Y665645D02*
X1317445Y666236D01*
G01X1317428D02*
X1317452Y664735D01*
G01X1314796Y659150D02*
X1314771Y660650D01*
G01X1314769Y659740D02*
X1314778Y659150D01*
G01X1313518Y665645D02*
X1313508Y666236D01*
G01X1313491D02*
X1313515Y664735D01*
G01X1325381Y659150D02*
X1325350Y660738D01*
G01X1325348Y659810D02*
X1325361Y659150D01*
G01X1322623Y665575D02*
X1322610Y666236D01*
G01X1322590D02*
X1322621Y664647D01*
G01X1321444Y659150D02*
X1321413Y660738D01*
G01X1321411Y659810D02*
X1321424Y659150D01*
G01X1318686Y665575D02*
X1318673Y666236D01*
G01X1318653D02*
X1318684Y664647D01*
G01X1317507Y659150D02*
X1317476Y660738D01*
G01X1317474Y659810D02*
X1317487Y659150D01*
G01X1314749Y665575D02*
X1314736Y666236D01*
G01X1314716D02*
X1314747Y664647D01*
G01X1313570Y659150D02*
X1313539Y660738D01*
G01X1313537Y659810D02*
X1313550Y659150D01*
G01X1275328Y675980D02*
X1274218D01*
G01X1283202D02*
X1282092D01*
G01X1291076D02*
X1289966D01*
G01X1298950D02*
X1297840D01*
G01X1306824D02*
X1305714D01*
G01X1314698D02*
X1313588D01*
G01X1322572D02*
X1321462D01*
G01X1275328Y674996D02*
X1274218D01*
G01X1283202D02*
X1282092D01*
G01X1291076D02*
X1289966D01*
G01X1298950D02*
X1297840D01*
G01X1306824D02*
X1305714D01*
G01X1314698D02*
X1313588D01*
G01X1322572D02*
X1321462D01*
G01X1321443Y674547D02*
X1322591D01*
G01X1313569D02*
X1314717D01*
G01X1305695D02*
X1306843D01*
G01X1297821D02*
X1298969D01*
G01X1289947D02*
X1291095D01*
G01X1282073D02*
X1283221D01*
G01X1274199D02*
X1275347D01*
G01X1275338Y674279D02*
X1274208D01*
G01X1283212D02*
X1282082D01*
G01X1291086D02*
X1289956D01*
G01X1298960D02*
X1297830D01*
G01X1306834D02*
X1305704D01*
G01X1314708D02*
X1313578D01*
G01X1322582D02*
X1321452D01*
G01X1275352Y672760D02*
X1274194D01*
G01X1283226D02*
X1282068D01*
G01X1291100D02*
X1289942D01*
G01X1298974D02*
X1297816D01*
G01X1306848D02*
X1305690D01*
G01X1314722D02*
X1313564D01*
G01X1322596D02*
X1321438D01*
G01X1321448Y672492D02*
X1322587D01*
G01X1313574D02*
X1314713D01*
G01X1305700D02*
X1306839D01*
G01X1297826D02*
X1298965D01*
G01X1289952D02*
X1291091D01*
G01X1282078D02*
X1283217D01*
G01X1274204D02*
X1275343D01*
G01X1271424Y672043D02*
X1270248D01*
G01X1275361D02*
X1274185D01*
G01X1279298D02*
X1278122D01*
G01X1283235D02*
X1282059D01*
G01X1287172D02*
X1285996D01*
G01X1291109D02*
X1289933D01*
G01X1295046D02*
X1293870D01*
G01X1298983D02*
X1297807D01*
G01X1302920D02*
X1301744D01*
G01X1306857D02*
X1305681D01*
G01X1310794D02*
X1309618D01*
G01X1314731D02*
X1313555D01*
G01X1318669D02*
X1317492D01*
G01X1322606D02*
X1321429D01*
G01X1326543D02*
X1325366D01*
G01X1271424Y671059D02*
X1270248D01*
G01X1275361D02*
X1274185D01*
G01X1279298D02*
X1278122D01*
G01X1283235D02*
X1282059D01*
G01X1287172D02*
X1285996D01*
G01X1291109D02*
X1289933D01*
G01X1295046D02*
X1293870D01*
G01X1298983D02*
X1297807D01*
G01X1302920D02*
X1301744D01*
G01X1306857D02*
X1305681D01*
G01X1310794D02*
X1309618D01*
G01X1314731D02*
X1313555D01*
G01X1318669D02*
X1317492D01*
G01X1322606D02*
X1321429D01*
G01X1326543D02*
X1325366D01*
G01X1271406Y670610D02*
X1270267D01*
G01X1279280D02*
X1278141D01*
G01X1287154D02*
X1286015D01*
G01X1295028D02*
X1293889D01*
G01X1302902D02*
X1301763D01*
G01X1310776D02*
X1309637D01*
G01X1318650D02*
X1317511D01*
G01X1326524D02*
X1325385D01*
G01X1325375Y670342D02*
X1326533D01*
G01X1317501D02*
X1318659D01*
G01X1309627D02*
X1310785D01*
G01X1301753D02*
X1302911D01*
G01X1293879D02*
X1295037D01*
G01X1286005D02*
X1287163D01*
G01X1278131D02*
X1279289D01*
G01X1270257D02*
X1271415D01*
G01X1325389Y668823D02*
X1326519D01*
G01X1317515D02*
X1318645D01*
G01X1309641D02*
X1310771D01*
G01X1301767D02*
X1302897D01*
G01X1293893D02*
X1295023D01*
G01X1286019D02*
X1287149D01*
G01X1278145D02*
X1279275D01*
G01X1270271D02*
X1271401D01*
G01X1271410Y668555D02*
X1270262D01*
G01X1279284D02*
X1278136D01*
G01X1287158D02*
X1286010D01*
G01X1295032D02*
X1293884D01*
G01X1302906D02*
X1301758D01*
G01X1310780D02*
X1309632D01*
G01X1318654D02*
X1317506D01*
G01X1326528D02*
X1325380D01*
G01X1271391Y668106D02*
X1270281D01*
G01X1279265D02*
X1278155D01*
G01X1287139D02*
X1286029D01*
G01X1295013D02*
X1293903D01*
G01X1302887D02*
X1301777D01*
G01X1310761D02*
X1309651D01*
G01X1318635D02*
X1317525D01*
G01X1326509D02*
X1325399D01*
G01X1271391Y667122D02*
X1270281D01*
G01X1279265D02*
X1278155D01*
G01X1287139D02*
X1286029D01*
G01X1295013D02*
X1293903D01*
G01X1302887D02*
X1301777D01*
G01X1310761D02*
X1309651D01*
G01X1318635D02*
X1317525D01*
G01X1326509D02*
X1325399D01*
G01X1271461Y665645D02*
X1270211D01*
G01X1275398D02*
X1274148D01*
G01X1279335D02*
X1278085D01*
G01X1283272D02*
X1282022D01*
G01X1287209D02*
X1285959D01*
G01X1291146D02*
X1289896D01*
G01X1295083D02*
X1293833D01*
G01X1299020D02*
X1297770D01*
G01X1302957D02*
X1301707D01*
G01X1306894D02*
X1305644D01*
G01X1310831D02*
X1309581D01*
G01X1314769D02*
X1313518D01*
G01X1318706D02*
X1317455D01*
G01X1322643D02*
X1321392D01*
G01X1326580D02*
X1325329D01*
G01X1325348Y665575D02*
X1326560D01*
G01X1321411D02*
X1322623D01*
G01X1317474D02*
X1318686D01*
G01X1313537D02*
X1314749D01*
G01X1309600D02*
X1310812D01*
G01X1305663D02*
X1306875D01*
G01X1301726D02*
X1302938D01*
G01X1297789D02*
X1299001D01*
G01X1293852D02*
X1295064D01*
G01X1289915D02*
X1291127D01*
G01X1285978D02*
X1287190D01*
G01X1282041D02*
X1283253D01*
G01X1278104D02*
X1279316D01*
G01X1274167D02*
X1275379D01*
G01X1270230D02*
X1271442D01*
G01X1313539Y664647D02*
X1313570Y666236D01*
G01X1313550D02*
X1313537Y665575D01*
G01X1310799Y659150D02*
X1310812Y659810D01*
G01X1310810Y660738D02*
X1310779Y659150D01*
G01X1309602Y664647D02*
X1309633Y666236D01*
G01X1309613D02*
X1309600Y665575D01*
G01X1306862Y659150D02*
X1306875Y659810D01*
G01X1306873Y660738D02*
X1306842Y659150D01*
G01X1305665Y664647D02*
X1305696Y666236D01*
G01X1305676D02*
X1305663Y665575D01*
G01X1302925Y659150D02*
X1302938Y659810D01*
G01X1302936Y660738D02*
X1302905Y659150D01*
G01X1301728Y664647D02*
X1301759Y666236D01*
G01X1301739D02*
X1301726Y665575D01*
G01X1313508Y659150D02*
X1313518Y659740D01*
G01X1313515Y660650D02*
X1313491Y659150D01*
G01X1310834Y664735D02*
X1310859Y666236D01*
G01X1310841D02*
X1310831Y665645D01*
G01X1309571Y659150D02*
X1309581Y659740D01*
G01X1309578Y660650D02*
X1309554Y659150D01*
G01X1306897Y664735D02*
X1306922Y666236D01*
G01X1306904D02*
X1306894Y665645D01*
G01X1305634Y659150D02*
X1305644Y659740D01*
G01X1305641Y660650D02*
X1305617Y659150D01*
G01X1302960Y664735D02*
X1302985Y666236D01*
G01X1302967D02*
X1302957Y665645D01*
G01X1301697Y659150D02*
X1301707Y659740D01*
G01X1301704Y660650D02*
X1301680Y659150D01*
G01X1310785Y670342D02*
X1310780Y668555D01*
G01X1310771Y668823D02*
X1310776Y670610D01*
G01X1309641Y656563D02*
X1309637Y654776D01*
G01X1309627Y655043D02*
X1309632Y656830D01*
G01X1305704Y674279D02*
X1305700Y672492D01*
G01X1305690Y672760D02*
X1305695Y674547D01*
G01X1302911Y670342D02*
X1302906Y668555D01*
G01X1302897Y668823D02*
X1302902Y670610D01*
G01X1301767Y656563D02*
X1301763Y654776D01*
G01X1301753Y655043D02*
X1301758Y656830D01*
G01X1310794Y654327D02*
Y653343D01*
G01Y672043D02*
Y671059D01*
G01X1310639Y658264D02*
Y657280D01*
G01Y668106D02*
Y667122D01*
G01X1309773Y658264D02*
Y657280D01*
G01Y667122D02*
Y668106D01*
G01X1309618Y653343D02*
Y654327D01*
G01Y671059D02*
Y672043D01*
G01X1307214Y682772D02*
Y677161D01*
G01X1306857Y653343D02*
Y654327D01*
G01Y672043D02*
Y671059D01*
G01X1306702Y675980D02*
Y674996D01*
G01X1305836D02*
Y675980D01*
G01X1305681Y654327D02*
Y653343D01*
G01Y671059D02*
Y672043D01*
G01X1302920Y653343D02*
Y654327D01*
G01Y672043D02*
Y671059D01*
G01X1302765Y658264D02*
Y657280D01*
G01Y668106D02*
Y667122D01*
G01X1302214Y682772D02*
Y677161D01*
G01X1301899Y658264D02*
Y657280D01*
G01Y667122D02*
Y668106D01*
G01X1301744Y654327D02*
Y653343D01*
G01Y671059D02*
Y672043D01*
G01X1310780Y656830D02*
X1310785Y655043D01*
G01X1310776Y654776D02*
X1310771Y656563D01*
G01X1309637Y670610D02*
X1309641Y668823D01*
G01X1309632Y668555D02*
X1309627Y670342D01*
G01X1306843Y674547D02*
X1306848Y672760D01*
G01X1306839Y672492D02*
X1306834Y674279D01*
G01X1302906Y656830D02*
X1302911Y655043D01*
G01X1302902Y654776D02*
X1302897Y656563D01*
G01X1301763Y670610D02*
X1301767Y668823D01*
G01X1301758Y668555D02*
X1301753Y670342D01*
G01X1310859Y659150D02*
X1310834Y660650D01*
G01X1310831Y659740D02*
X1310841Y659150D01*
G01X1309581Y665645D02*
X1309571Y666236D01*
G01X1309554D02*
X1309578Y664735D01*
G01X1306922Y659150D02*
X1306897Y660650D01*
G01X1306894Y659740D02*
X1306904Y659150D01*
G01X1305644Y665645D02*
X1305634Y666236D01*
G01X1305617D02*
X1305641Y664735D01*
G01X1302985Y659150D02*
X1302960Y660650D01*
G01X1302957Y659740D02*
X1302967Y659150D01*
G01X1301707Y665645D02*
X1301697Y666236D01*
G01X1301680D02*
X1301704Y664735D01*
G01X1310812Y665575D02*
X1310799Y666236D01*
G01X1310779D02*
X1310810Y664647D01*
G01X1309633Y659150D02*
X1309602Y660738D01*
G01X1309600Y659810D02*
X1309613Y659150D01*
G01X1306875Y665575D02*
X1306862Y666236D01*
G01X1306842D02*
X1306873Y664647D01*
G01X1305696Y659150D02*
X1305665Y660738D01*
G01X1305663Y659810D02*
X1305676Y659150D01*
G01X1302938Y665575D02*
X1302925Y666236D01*
G01X1302905D02*
X1302936Y664647D01*
G01X1301759Y659150D02*
X1301728Y660738D01*
G01X1301726Y659810D02*
X1301739Y659150D01*
G01X1271451Y665350D02*
X1270221D01*
G01X1275388D02*
X1274158D01*
G01X1279325D02*
X1278095D01*
G01X1283262D02*
X1282032D01*
G01X1287199D02*
X1285969D01*
G01X1291136D02*
X1289906D01*
G01X1295073D02*
X1293843D01*
G01X1299010D02*
X1297780D01*
G01X1302947D02*
X1301717D01*
G01X1306884D02*
X1305654D01*
G01X1310821D02*
X1309591D01*
G01X1314758D02*
X1313528D01*
G01X1318695D02*
X1317465D01*
G01X1322632D02*
X1321402D01*
G01X1326569D02*
X1325339D01*
G01X1325326Y664735D02*
X1326582D01*
G01X1321389D02*
X1322645D01*
G01X1317452D02*
X1318708D01*
G01X1313515D02*
X1314771D01*
G01X1309578D02*
X1310834D01*
G01X1305641D02*
X1306897D01*
G01X1301704D02*
X1302960D01*
G01X1297767D02*
X1299023D01*
G01X1293830D02*
X1295086D01*
G01X1289893D02*
X1291149D01*
G01X1285956D02*
X1287212D01*
G01X1282019D02*
X1283275D01*
G01X1278082D02*
X1279338D01*
G01X1274145D02*
X1275401D01*
G01X1270208D02*
X1271464D01*
G01X1271440Y664647D02*
X1270232D01*
G01X1275377D02*
X1274169D01*
G01X1279314D02*
X1278106D01*
G01X1283251D02*
X1282043D01*
G01X1287188D02*
X1285980D01*
G01X1291125D02*
X1289917D01*
G01X1295062D02*
X1293854D01*
G01X1298999D02*
X1297791D01*
G01X1302936D02*
X1301728D01*
G01X1306873D02*
X1305665D01*
G01X1310810D02*
X1309602D01*
G01X1314747D02*
X1313539D01*
G01X1318684D02*
X1317476D01*
G01X1322621D02*
X1321413D01*
G01X1326558D02*
X1325350D01*
G01X1271451Y664365D02*
X1270221D01*
G01X1275388D02*
X1274158D01*
G01X1279325D02*
X1278095D01*
G01X1283262D02*
X1282032D01*
G01X1287199D02*
X1285969D01*
G01X1291136D02*
X1289906D01*
G01X1295073D02*
X1293843D01*
G01X1299010D02*
X1297780D01*
G01X1302947D02*
X1301717D01*
G01X1306884D02*
X1305654D01*
G01X1310821D02*
X1309591D01*
G01X1314758D02*
X1313528D01*
G01X1318695D02*
X1317465D01*
G01X1322632D02*
X1321402D01*
G01X1326569D02*
X1325339D01*
G01Y661020D02*
X1326569D01*
G01X1321402D02*
X1322632D01*
G01X1317465D02*
X1318695D01*
G01X1313528D02*
X1314758D01*
G01X1309591D02*
X1310821D01*
G01X1305654D02*
X1306884D01*
G01X1301717D02*
X1302947D01*
G01X1297780D02*
X1299010D01*
G01X1293843D02*
X1295073D01*
G01X1289906D02*
X1291136D01*
G01X1285969D02*
X1287199D01*
G01X1282032D02*
X1283262D01*
G01X1278095D02*
X1279325D01*
G01X1274158D02*
X1275388D01*
G01X1270221D02*
X1271451D01*
G01X1325350Y660738D02*
X1326558D01*
G01X1321413D02*
X1322621D01*
G01X1317476D02*
X1318684D01*
G01X1313539D02*
X1314747D01*
G01X1309602D02*
X1310810D01*
G01X1305665D02*
X1306873D01*
G01X1301728D02*
X1302936D01*
G01X1297791D02*
X1298999D01*
G01X1293854D02*
X1295062D01*
G01X1289917D02*
X1291125D01*
G01X1285980D02*
X1287188D01*
G01X1282043D02*
X1283251D01*
G01X1278106D02*
X1279314D01*
G01X1274169D02*
X1275377D01*
G01X1270232D02*
X1271440D01*
G01X1271464Y660650D02*
X1270208D01*
G01X1275401D02*
X1274145D01*
G01X1279338D02*
X1278082D01*
G01X1283275D02*
X1282019D01*
G01X1287212D02*
X1285956D01*
G01X1291149D02*
X1289893D01*
G01X1295086D02*
X1293830D01*
G01X1299023D02*
X1297767D01*
G01X1302960D02*
X1301704D01*
G01X1306897D02*
X1305641D01*
G01X1310834D02*
X1309578D01*
G01X1314771D02*
X1313515D01*
G01X1318708D02*
X1317452D01*
G01X1322645D02*
X1321389D01*
G01X1326582D02*
X1325326D01*
G01X1325339Y660036D02*
X1326569D01*
G01X1321402D02*
X1322632D01*
G01X1317465D02*
X1318695D01*
G01X1313528D02*
X1314758D01*
G01X1309591D02*
X1310821D01*
G01X1305654D02*
X1306884D01*
G01X1301717D02*
X1302947D01*
G01X1297780D02*
X1299010D01*
G01X1293843D02*
X1295073D01*
G01X1289906D02*
X1291136D01*
G01X1285969D02*
X1287199D01*
G01X1282032D02*
X1283262D01*
G01X1278095D02*
X1279325D01*
G01X1274158D02*
X1275388D01*
G01X1270221D02*
X1271451D01*
G01X1271442Y659810D02*
X1270230D01*
G01X1275379D02*
X1274167D01*
G01X1279316D02*
X1278104D01*
G01X1283253D02*
X1282041D01*
G01X1287190D02*
X1285978D01*
G01X1291127D02*
X1289915D01*
G01X1295064D02*
X1293852D01*
G01X1299001D02*
X1297789D01*
G01X1302938D02*
X1301726D01*
G01X1306875D02*
X1305663D01*
G01X1310812D02*
X1309600D01*
G01X1314749D02*
X1313537D01*
G01X1318686D02*
X1317474D01*
G01X1322623D02*
X1321411D01*
G01X1326560D02*
X1325348D01*
G01X1325329Y659740D02*
X1326580D01*
G01X1321392D02*
X1322643D01*
G01X1317455D02*
X1318706D01*
G01X1313518D02*
X1314769D01*
G01X1309581D02*
X1310831D01*
G01X1305644D02*
X1306894D01*
G01X1301707D02*
X1302957D01*
G01X1297770D02*
X1299020D01*
G01X1293833D02*
X1295083D01*
G01X1289896D02*
X1291146D01*
G01X1285959D02*
X1287209D01*
G01X1282022D02*
X1283272D01*
G01X1278085D02*
X1279335D01*
G01X1274148D02*
X1275398D01*
G01X1270211D02*
X1271461D01*
G01X1325399Y658264D02*
X1326509D01*
G01X1317525D02*
X1318635D01*
G01X1309651D02*
X1310761D01*
G01X1301777D02*
X1302887D01*
G01X1293903D02*
X1295013D01*
G01X1286029D02*
X1287139D01*
G01X1278155D02*
X1279265D01*
G01X1270281D02*
X1271391D01*
G01X1325399Y657280D02*
X1326509D01*
G01X1317525D02*
X1318635D01*
G01X1309651D02*
X1310761D01*
G01X1301777D02*
X1302887D01*
G01X1293903D02*
X1295013D01*
G01X1286029D02*
X1287139D01*
G01X1278155D02*
X1279265D01*
G01X1270281D02*
X1271391D01*
G01X1325380Y656830D02*
X1326528D01*
G01X1317506D02*
X1318654D01*
G01X1309632D02*
X1310780D01*
G01X1301758D02*
X1302906D01*
G01X1293884D02*
X1295032D01*
G01X1286010D02*
X1287158D01*
G01X1278136D02*
X1279284D01*
G01X1270262D02*
X1271410D01*
G01X1271401Y656563D02*
X1270271D01*
G01X1279275D02*
X1278145D01*
G01X1287149D02*
X1286019D01*
G01X1295023D02*
X1293893D01*
G01X1302897D02*
X1301767D01*
G01X1310771D02*
X1309641D01*
G01X1318645D02*
X1317515D01*
G01X1326519D02*
X1325389D01*
G01X1271415Y655043D02*
X1270257D01*
G01X1279289D02*
X1278131D01*
G01X1287163D02*
X1286005D01*
G01X1295037D02*
X1293879D01*
G01X1302911D02*
X1301753D01*
G01X1310785D02*
X1309627D01*
G01X1318659D02*
X1317501D01*
G01X1326533D02*
X1325375D01*
G01X1325385Y654776D02*
X1326524D01*
G01X1317511D02*
X1318650D01*
G01X1309637D02*
X1310776D01*
G01X1301763D02*
X1302902D01*
G01X1293889D02*
X1295028D01*
G01X1286015D02*
X1287154D01*
G01X1278141D02*
X1279280D01*
G01X1270267D02*
X1271406D01*
G01X1325366Y654327D02*
X1326543D01*
G01X1321429D02*
X1322606D01*
G01X1317492D02*
X1318669D01*
G01X1313555D02*
X1314731D01*
G01X1309618D02*
X1310794D01*
G01X1305681D02*
X1306857D01*
G01X1301744D02*
X1302920D01*
G01X1297807D02*
X1298983D01*
G01X1293870D02*
X1295046D01*
G01X1289933D02*
X1291109D01*
G01X1285996D02*
X1287172D01*
G01X1282059D02*
X1283235D01*
G01X1278122D02*
X1279298D01*
G01X1274185D02*
X1275361D01*
G01X1270248D02*
X1271424D01*
G01Y653343D02*
X1270248D01*
G01X1275361D02*
X1274185D01*
G01X1279298D02*
X1278122D01*
G01X1283235D02*
X1282059D01*
G01X1287172D02*
X1285996D01*
G01X1291109D02*
X1289933D01*
G01X1295046D02*
X1293870D01*
G01X1298983D02*
X1297807D01*
G01X1302920D02*
X1301744D01*
G01X1306857D02*
X1305681D01*
G01X1310794D02*
X1309618D01*
G01X1314731D02*
X1313555D01*
G01X1318669D02*
X1317492D01*
G01X1322606D02*
X1321429D01*
G01X1326543D02*
X1325366D01*
G01X1275343Y652893D02*
X1274204D01*
G01X1283217D02*
X1282078D01*
G01X1291091D02*
X1289952D01*
G01X1298965D02*
X1297826D01*
G01X1306839D02*
X1305700D01*
G01X1314713D02*
X1313574D01*
G01X1322587D02*
X1321448D01*
G01X1321438Y652626D02*
X1322596D01*
G01X1313564D02*
X1314722D01*
G01X1305690D02*
X1306848D01*
G01X1297816D02*
X1298974D01*
G01X1289942D02*
X1291100D01*
G01X1282068D02*
X1283226D01*
G01X1274194D02*
X1275352D01*
G01X1298988Y659150D02*
X1299001Y659810D01*
G01X1298999Y660738D02*
X1298968Y659150D01*
G01X1297791Y664647D02*
X1297822Y666236D01*
G01X1297802D02*
X1297789Y665575D01*
G01X1295051Y659150D02*
X1295064Y659810D01*
G01X1295062Y660738D02*
X1295031Y659150D01*
G01X1293854Y664647D02*
X1293885Y666236D01*
G01X1293865D02*
X1293852Y665575D01*
G01X1291114Y659150D02*
X1291127Y659810D01*
G01X1291125Y660738D02*
X1291094Y659150D01*
G01X1289917Y664647D02*
X1289948Y666236D01*
G01X1289928D02*
X1289915Y665575D01*
G01X1299023Y664735D02*
X1299048Y666236D01*
G01X1299030D02*
X1299020Y665645D01*
G01X1297760Y659150D02*
X1297770Y659740D01*
G01X1297767Y660650D02*
X1297743Y659150D01*
G01X1295086Y664735D02*
X1295111Y666236D01*
G01X1295093D02*
X1295083Y665645D01*
G01X1293823Y659150D02*
X1293833Y659740D01*
G01X1293830Y660650D02*
X1293806Y659150D01*
G01X1291149Y664735D02*
X1291174Y666236D01*
G01X1291156D02*
X1291146Y665645D01*
G01X1289886Y659150D02*
X1289896Y659740D01*
G01X1289893Y660650D02*
X1289869Y659150D01*
G01X1297830Y674279D02*
X1297826Y672492D01*
G01X1297816Y672760D02*
X1297821Y674547D01*
G01X1295037Y670342D02*
X1295032Y668555D01*
G01X1295023Y668823D02*
X1295028Y670610D01*
G01X1293893Y656563D02*
X1293889Y654776D01*
G01X1293879Y655043D02*
X1293884Y656830D01*
G01X1289956Y674279D02*
X1289952Y672492D01*
G01X1289942Y672760D02*
X1289947Y674547D01*
G01X1298983Y653343D02*
Y654327D01*
G01Y671059D02*
Y672043D01*
G01X1298828Y675980D02*
Y674996D01*
G01X1297962D02*
Y675980D01*
G01X1297807Y654327D02*
Y653343D01*
G01Y672043D02*
Y671059D01*
G01X1295046Y654327D02*
Y653343D01*
G01Y672043D02*
Y671059D01*
G01X1294891Y658264D02*
Y657280D01*
G01Y668106D02*
Y667122D01*
G01X1294025Y658264D02*
Y657280D01*
G01Y667122D02*
Y668106D01*
G01X1293870Y653343D02*
Y654327D01*
G01Y671059D02*
Y672043D01*
G01X1291109Y653343D02*
Y654327D01*
G01Y671059D02*
Y672043D01*
G01X1290954Y675980D02*
Y674996D01*
G01X1290088D02*
Y675980D01*
G01X1289933Y654327D02*
Y653343D01*
G01Y672043D02*
Y671059D01*
G01X1298969Y674547D02*
X1298974Y672760D01*
G01X1298965Y672492D02*
X1298960Y674279D01*
G01X1295032Y656830D02*
X1295037Y655043D01*
G01X1295028Y654776D02*
X1295023Y656563D01*
G01X1293889Y670610D02*
X1293893Y668823D01*
G01X1293884Y668555D02*
X1293879Y670342D01*
G01X1291095Y674547D02*
X1291100Y672760D01*
G01X1291091Y672492D02*
X1291086Y674279D01*
G01X1299048Y659150D02*
X1299023Y660650D01*
G01X1299020Y659740D02*
X1299030Y659150D01*
G01X1297770Y665645D02*
X1297760Y666236D01*
G01X1297743D02*
X1297767Y664735D01*
G01X1295111Y659150D02*
X1295086Y660650D01*
G01X1295083Y659740D02*
X1295093Y659150D01*
G01X1293833Y665645D02*
X1293823Y666236D01*
G01X1293806D02*
X1293830Y664735D01*
G01X1291174Y659150D02*
X1291149Y660650D01*
G01X1291146Y659740D02*
X1291156Y659150D01*
G01X1289896Y665645D02*
X1289886Y666236D01*
G01X1289869D02*
X1289893Y664735D01*
G01X1287237Y659150D02*
X1287212Y660650D01*
G01X1287209Y659740D02*
X1287219Y659150D01*
G01X1299001Y665575D02*
X1298988Y666236D01*
G01X1298968D02*
X1298999Y664647D01*
G01X1297822Y659150D02*
X1297791Y660738D01*
G01X1297789Y659810D02*
X1297802Y659150D01*
G01X1295064Y665575D02*
X1295051Y666236D01*
G01X1295031D02*
X1295062Y664647D01*
G01X1293885Y659150D02*
X1293854Y660738D01*
G01X1293852Y659810D02*
X1293865Y659150D01*
G01X1291127Y665575D02*
X1291114Y666236D01*
G01X1291094D02*
X1291125Y664647D01*
G01X1289948Y659150D02*
X1289917Y660738D01*
G01X1289915Y659810D02*
X1289928Y659150D01*
G01X1287190Y665575D02*
X1287177Y666236D01*
G01X1287157D02*
X1287188Y664647D01*
G01X1287177Y659150D02*
X1287190Y659810D01*
G01X1287188Y660738D02*
X1287157Y659150D01*
G01X1285980Y664647D02*
X1286011Y666236D01*
G01X1285991D02*
X1285978Y665575D01*
G01X1283240Y659150D02*
X1283253Y659810D01*
G01X1283251Y660738D02*
X1283220Y659150D01*
G01X1282043Y664647D02*
X1282074Y666236D01*
G01X1282054D02*
X1282041Y665575D01*
G01X1279303Y659150D02*
X1279316Y659810D01*
G01X1279314Y660738D02*
X1279283Y659150D01*
G01X1278106Y664647D02*
X1278137Y666236D01*
G01X1278117D02*
X1278104Y665575D01*
G01X1275366Y659150D02*
X1275379Y659810D01*
G01X1275377Y660738D02*
X1275346Y659150D01*
G01X1287212Y664735D02*
X1287237Y666236D01*
G01X1287219D02*
X1287209Y665645D01*
G01X1285949Y659150D02*
X1285959Y659740D01*
G01X1285956Y660650D02*
X1285931Y659150D01*
G01X1283275Y664735D02*
X1283300Y666236D01*
G01X1283282D02*
X1283272Y665645D01*
G01X1282012Y659150D02*
X1282022Y659740D01*
G01X1282019Y660650D02*
X1281994Y659150D01*
G01X1279338Y664735D02*
X1279363Y666236D01*
G01X1279345D02*
X1279335Y665645D01*
G01X1278075Y659150D02*
X1278085Y659740D01*
G01X1278082Y660650D02*
X1278057Y659150D01*
G01X1275401Y664735D02*
X1275426Y666236D01*
G01X1275408D02*
X1275398Y665645D01*
G01X1287163Y670342D02*
X1287158Y668555D01*
G01X1287149Y668823D02*
X1287154Y670610D01*
G01X1286019Y656563D02*
X1286015Y654776D01*
G01X1286005Y655043D02*
X1286010Y656830D01*
G01X1282082Y674279D02*
X1282078Y672492D01*
G01X1282068Y672760D02*
X1282073Y674547D01*
G01X1279289Y670342D02*
X1279284Y668555D01*
G01X1279275Y668823D02*
X1279280Y670610D01*
G01X1278145Y656563D02*
X1278141Y654776D01*
G01X1278131Y655043D02*
X1278136Y656830D01*
G01X1287172Y654327D02*
Y653343D01*
G01Y672043D02*
Y671059D01*
G01X1287017Y658264D02*
Y657280D01*
G01Y668106D02*
Y667122D01*
G01X1286309Y682772D02*
Y677161D01*
G01X1286151Y658264D02*
Y657280D01*
G01Y667122D02*
Y668106D01*
G01X1285996Y653343D02*
Y654327D01*
G01Y671059D02*
Y672043D01*
G01X1283235Y653343D02*
Y654327D01*
G01Y671059D02*
Y672043D01*
G01X1283080Y675980D02*
Y674996D01*
G01X1282214D02*
Y675980D01*
G01X1282059Y654327D02*
Y653343D01*
G01Y672043D02*
Y671059D01*
G01X1281309Y682772D02*
Y677161D01*
G01X1279298Y654327D02*
Y653343D01*
G01Y672043D02*
Y671059D01*
G01X1279143Y658264D02*
Y657280D01*
G01Y668106D02*
Y667122D01*
G01X1278277Y658264D02*
Y657280D01*
G01Y667122D02*
Y668106D01*
G01X1278122Y653343D02*
Y654327D01*
G01Y671059D02*
Y672043D01*
G01X1275361Y653343D02*
Y654327D01*
G01Y671059D02*
Y672043D01*
G01X1275206Y675980D02*
Y674996D01*
G01X1287158Y656830D02*
X1287163Y655043D01*
G01X1287154Y654776D02*
X1287149Y656563D01*
G01X1286015Y670610D02*
X1286019Y668823D01*
G01X1286010Y668555D02*
X1286005Y670342D01*
G01X1283221Y674547D02*
X1283226Y672760D01*
G01X1283217Y672492D02*
X1283212Y674279D01*
G01X1279284Y656830D02*
X1279289Y655043D01*
G01X1279280Y654776D02*
X1279275Y656563D01*
G01X1278141Y670610D02*
X1278145Y668823D01*
G01X1278136Y668555D02*
X1278131Y670342D01*
G01X1275347Y674547D02*
X1275352Y672760D01*
G01X1275343Y672492D02*
X1275338Y674279D01*
G01X1285959Y665645D02*
X1285949Y666236D01*
G01X1285931D02*
X1285956Y664735D01*
G01X1283300Y659150D02*
X1283275Y660650D01*
G01X1283272Y659740D02*
X1283282Y659150D01*
G01X1282022Y665645D02*
X1282012Y666236D01*
G01X1281994D02*
X1282019Y664735D01*
G01X1279363Y659150D02*
X1279338Y660650D01*
G01X1279335Y659740D02*
X1279345Y659150D01*
G01X1278085Y665645D02*
X1278075Y666236D01*
G01X1278057D02*
X1278082Y664735D01*
G01X1275426Y659150D02*
X1275401Y660650D01*
G01X1275398Y659740D02*
X1275408Y659150D01*
G01X1274148Y665645D02*
X1274138Y666236D01*
G01X1274120D02*
X1274145Y664735D01*
G01X1286011Y659150D02*
X1285980Y660738D01*
G01X1285978Y659810D02*
X1285991Y659150D01*
G01X1283253Y665575D02*
X1283240Y666236D01*
G01X1283220D02*
X1283251Y664647D01*
G01X1282074Y659150D02*
X1282043Y660738D01*
G01X1282041Y659810D02*
X1282054Y659150D01*
G01X1279316Y665575D02*
X1279303Y666236D01*
G01X1279283D02*
X1279314Y664647D01*
G01X1278137Y659150D02*
X1278106Y660738D01*
G01X1278104Y659810D02*
X1278117Y659150D01*
G01X1275379Y665575D02*
X1275366Y666236D01*
G01X1275346D02*
X1275377Y664647D01*
G01X1274200Y659150D02*
X1274169Y660738D01*
G01X1274167Y659810D02*
X1274180Y659150D01*
G01X1274169Y664647D02*
X1274200Y666236D01*
G01X1274180D02*
X1274167Y665575D01*
G01X1271429Y659150D02*
X1271442Y659810D01*
G01X1271440Y660738D02*
X1271409Y659150D01*
G01X1270232Y664647D02*
X1270263Y666236D01*
G01X1270243D02*
X1270230Y665575D01*
G01X1274138Y659150D02*
X1274148Y659740D01*
G01X1274145Y660650D02*
X1274120Y659150D01*
G01X1271464Y664735D02*
X1271489Y666236D01*
G01X1271471D02*
X1271461Y665645D01*
G01X1270201Y659150D02*
X1270211Y659740D01*
G01X1270208Y660650D02*
X1270183Y659150D01*
G01X1274208Y674279D02*
X1274204Y672492D01*
G01X1274194Y672760D02*
X1274199Y674547D01*
G01X1271415Y670342D02*
X1271410Y668555D01*
G01X1271401Y668823D02*
X1271406Y670610D01*
G01X1270271Y656563D02*
X1270267Y654776D01*
G01X1270257Y655043D02*
X1270262Y656830D01*
G01X1274340Y674996D02*
Y675980D01*
G01X1274185Y654327D02*
Y653343D01*
G01Y672043D02*
Y671059D01*
G01X1271424Y654327D02*
Y653343D01*
G01Y672043D02*
Y671059D01*
G01X1271269Y658264D02*
Y657280D01*
G01Y668106D02*
Y667122D01*
G01X1270403Y658264D02*
Y657280D01*
G01Y667122D02*
Y668106D01*
G01X1270248Y653343D02*
Y654327D01*
G01Y671059D02*
Y672043D01*
G01X1271410Y656830D02*
X1271415Y655043D01*
G01X1271406Y654776D02*
X1271401Y656563D01*
G01X1270267Y670610D02*
X1270271Y668823D01*
G01X1270262Y668555D02*
X1270257Y670342D01*
G01X1271489Y659150D02*
X1271464Y660650D01*
G01X1271461Y659740D02*
X1271471Y659150D01*
G01X1270211Y665645D02*
X1270201Y666236D01*
G01X1270183D02*
X1270208Y664735D01*
G01X1271442Y665575D02*
X1271429Y666236D01*
G01X1271409D02*
X1271440Y664647D01*
G01X1270263Y659150D02*
X1270232Y660738D01*
G01X1270230Y659810D02*
X1270243Y659150D01*
G01X1368041Y-259766D02*
Y-349896D01*
G01X1388514Y256150D02*
Y272686D01*
G01X1387333D02*
Y256150D01*
G01X1384577D02*
Y272686D01*
G01X1383396D02*
Y256150D01*
G01X1380640D02*
Y272686D01*
G01X1379459D02*
Y256150D01*
G01X1376703D02*
Y272686D01*
G01X1375522D02*
Y256150D01*
G01X1372766D02*
Y272686D01*
G01X1371585D02*
Y256150D01*
G01X1368829D02*
Y272686D01*
G01X1367648D02*
Y256150D01*
G01X1364892D02*
Y272686D01*
G01X1363711D02*
Y256150D01*
G01X1360955D02*
Y272686D01*
G01X1359774D02*
Y256150D01*
G01X1357018D02*
Y272686D01*
G01X1355837D02*
Y256150D01*
G01X1353081D02*
Y272686D01*
G01X1351900D02*
Y256150D01*
G01X1349144D02*
Y272686D01*
G01X1347963D02*
Y256150D01*
G01X1345207D02*
Y272686D01*
G01X1344026D02*
Y256150D01*
G01X1341270D02*
Y272686D01*
G01X1340089D02*
Y256150D01*
G01X1337333D02*
Y272686D01*
G01X1336152D02*
Y256150D01*
G01X1333396D02*
Y272686D01*
G01X1332215D02*
Y256150D01*
G01X1329459D02*
Y272686D01*
G01X1388514D02*
X1391270D01*
G01X1384577D02*
X1387333D01*
G01X1380640D02*
X1383396D01*
G01X1376703D02*
X1379459D01*
G01X1372766D02*
X1375522D01*
G01X1368829D02*
X1371585D01*
G01X1364892D02*
X1367648D01*
G01X1360955D02*
X1363711D01*
G01X1357018D02*
X1359774D01*
G01X1353081D02*
X1355837D01*
G01X1349144D02*
X1351900D01*
G01X1345207D02*
X1347963D01*
G01X1341270D02*
X1344026D01*
G01X1337333D02*
X1340089D01*
G01X1333396D02*
X1336152D01*
G01X1329459D02*
X1332215D01*
G01Y256150D02*
X1329459D01*
G01X1336152D02*
X1333396D01*
G01X1340089D02*
X1337333D01*
G01X1344026D02*
X1341270D01*
G01X1347963D02*
X1345207D01*
G01X1351900D02*
X1349144D01*
G01X1355837D02*
X1353081D01*
G01X1359774D02*
X1357018D01*
G01X1363711D02*
X1360955D01*
G01X1367648D02*
X1364892D01*
G01X1371585D02*
X1368829D01*
G01X1375522D02*
X1372766D01*
G01X1379459D02*
X1376703D01*
G01X1383396D02*
X1380640D01*
G01X1387333D02*
X1384577D01*
G01X1391270D02*
X1388514D01*
G01X1373160Y304182D02*
Y368052D01*
G01X1353475Y304182D02*
Y368052D01*
G01X1371896Y309041D02*
X1416201Y356945D01*
G01X1379459Y294339D02*
G03X1383396Y290402I3937J0D01*
G01Y310087D02*
G03X1379459Y306150I0J-3937D01*
G01X1369223Y290402D02*
G03X1373160Y294339I0J3937D01*
G01X1353475D02*
G03X1357412Y290402I3937J0D01*
G01Y310087D02*
G03X1353475Y306150I0J-3937D01*
G01X1373160D02*
G03X1369223Y310087I-3937J0D01*
G01X1379459Y294339D02*
Y306150D01*
G01X1373160D02*
Y294339D01*
G01X1353475D02*
Y306150D01*
G01X1383396Y310087D02*
X1395207D01*
G01X1357412D02*
X1369223D01*
G01Y290402D02*
X1357412D01*
G01X1395207D02*
X1383396D01*
G01X1392845Y364115D02*
X1363317D01*
G01X1373160D02*
X1392845D01*
G01X1385206Y584346D02*
X1387175Y586315D01*
G01D02*
Y613677D01*
G01X1386387Y606394D02*
Y589858D01*
G01X1383631D02*
Y606394D01*
G01X1382450D02*
Y589858D01*
G01X1379694D02*
Y606394D01*
G01X1378513D02*
Y589858D01*
G01X1375757D02*
Y606394D01*
G01X1374576D02*
Y589858D01*
G01X1371820D02*
Y606394D01*
G01X1370639D02*
Y589858D01*
G01X1367883D02*
Y606394D01*
G01X1366702D02*
Y589858D01*
G01X1363946D02*
Y606394D01*
G01X1362765D02*
Y589858D01*
G01X1360009D02*
Y606394D01*
G01X1358828D02*
Y589858D01*
G01X1356072D02*
Y606394D01*
G01X1354891D02*
Y589858D01*
G01X1352135D02*
Y606394D01*
G01X1350954D02*
Y589858D01*
G01X1348198D02*
Y606394D01*
G01X1347017D02*
Y589858D01*
G01X1344261D02*
Y606394D01*
G01X1343080D02*
Y589858D01*
G01X1340324D02*
Y606394D01*
G01X1339143D02*
Y589858D01*
G01X1336387D02*
Y606394D01*
G01X1335206D02*
Y589858D01*
G01X1332450D02*
Y606394D01*
G01X1331269D02*
Y589858D01*
G01X1335206D02*
X1332450D01*
G01X1339143D02*
X1336387D01*
G01X1343080D02*
X1340324D01*
G01X1347017D02*
X1344261D01*
G01X1350954D02*
X1348198D01*
G01X1354891D02*
X1352135D01*
G01X1358828D02*
X1356072D01*
G01X1362765D02*
X1360009D01*
G01X1366702D02*
X1363946D01*
G01X1370639D02*
X1367883D01*
G01X1374576D02*
X1371820D01*
G01X1378513D02*
X1375757D01*
G01X1382450D02*
X1379694D01*
G01X1386387D02*
X1383631D01*
G01X1393671D02*
X1388159D01*
G01X1344655Y633953D02*
X1475167D01*
G01X1350561Y647732D02*
Y706394D01*
G01X1376545Y647732D02*
Y706394D01*
G01X1394655Y613677D02*
G03X1387175I-3740J0D01*
G01X1386387Y639858D02*
G03X1382450Y643795I-3937J0D01*
G01Y624110D02*
G03X1386387Y628047I0J3937D01*
G01X1366702D02*
G03X1370639Y624110I3937J0D01*
G01Y643795D02*
G03X1366702Y639858I0J-3937D01*
G01X1356466Y624110D02*
G03X1360403Y628047I0J3937D01*
G01X1340718D02*
G03X1344655Y624110I3937J0D01*
G01Y643795D02*
G03X1340718Y639858I0J-3937D01*
G01X1360403D02*
G03X1356466Y643795I-3937J0D01*
G01X1385954Y601394D02*
X1385298Y599425D01*
G01X1385544D02*
X1385708Y599928D01*
G01X1386118Y601226D02*
X1385749Y600095D01*
G01X1382919Y600933D02*
X1383002Y601058D01*
G01X1382715Y601100D02*
X1382673Y600933D01*
G01X1385589Y652626D02*
X1385583Y650839D01*
G01X1385574Y651106D02*
X1385579Y652893D01*
G01X1389685Y649898D02*
Y649701D01*
G01X1389439Y649898D02*
Y649701D01*
G01X1388700D02*
Y649898D01*
G01X1388208Y649701D02*
Y649898D01*
G01X1387962Y649701D02*
Y649898D01*
G01X1386387Y639858D02*
Y628047D01*
G01X1385994Y649701D02*
Y649898D01*
G01X1385443Y650390D02*
Y649406D01*
G01X1384970Y600765D02*
Y601100D01*
G01X1384724Y599425D02*
Y601058D01*
G01X1384576Y650390D02*
Y649406D01*
G01X1384478Y601394D02*
Y599425D01*
G01X1384150D02*
Y599634D01*
G01X1382919Y600849D02*
Y600933D01*
G01X1382673Y599634D02*
Y599425D01*
G01Y600933D02*
Y600849D01*
G01X1378612Y649701D02*
Y649898D01*
G01X1384440Y652893D02*
X1384444Y651106D01*
G01X1384435Y650839D02*
X1384430Y652626D01*
G01X1384109Y600933D02*
X1384068Y601100D01*
G01X1382673Y600849D02*
X1382715Y600681D01*
G01X1386487Y600095D02*
X1386118Y601226D01*
G01X1386528Y599928D02*
X1386693Y599425D01*
G01X1386939D02*
X1386282Y601394D01*
G01X1382878Y601268D02*
X1382715Y601100D01*
G01X1377715Y652626D02*
X1377709Y650839D01*
G01X1377700Y651106D02*
X1377705Y652893D01*
G01X1369841Y652626D02*
X1369835Y650839D01*
G01X1369826Y651106D02*
X1369831Y652893D01*
G01X1377569Y650390D02*
Y649406D01*
G01X1377135Y649898D02*
Y649701D01*
G01X1376702Y650390D02*
Y649406D01*
G01X1369694Y650390D02*
Y649406D01*
G01X1368828Y650390D02*
Y649406D01*
G01X1366702Y628047D02*
Y639858D01*
G01X1376566Y652893D02*
X1376570Y651106D01*
G01X1376561Y650839D02*
X1376556Y652626D01*
G01X1368692Y652893D02*
X1368696Y651106D01*
G01X1368687Y650839D02*
X1368682Y652626D01*
G01X1383002Y600681D02*
X1382919Y600849D01*
G01X1383043Y601352D02*
X1382878Y601268D01*
G01X1383002Y601058D02*
X1383124Y601142D01*
G01X1361967Y652626D02*
X1361961Y650839D01*
G01X1361952Y651106D02*
X1361957Y652893D01*
G01X1354093Y652626D02*
X1354087Y650839D01*
G01X1354078Y651106D02*
X1354083Y652893D01*
G01X1361820Y650390D02*
Y649406D01*
G01X1360954Y650390D02*
Y649406D01*
G01X1360403Y639858D02*
Y628047D01*
G01X1353946Y650390D02*
Y649406D01*
G01X1353080Y650390D02*
Y649406D01*
G01X1360818Y652893D02*
X1360822Y651106D01*
G01X1360813Y650839D02*
X1360808Y652626D01*
G01X1352944Y652893D02*
X1352948Y651106D01*
G01X1352939Y650839D02*
X1352934Y652626D01*
G01X1383822Y601058D02*
X1383904Y600933D01*
G01X1382715Y600681D02*
X1382796Y600556D01*
G01X1390136Y593787D02*
X1389602Y594583D01*
G01X1389356D02*
X1390013Y593619D01*
G01X1346219Y652626D02*
X1346213Y650839D01*
G01X1346204Y651106D02*
X1346209Y652893D01*
G01X1346072Y650390D02*
Y649406D01*
G01X1345206Y650390D02*
Y649406D01*
G01X1340718Y628047D02*
Y639858D01*
G01X1345070Y652893D02*
X1345074Y651106D01*
G01X1345065Y650839D02*
X1345060Y652626D01*
G01X1384970Y601100D02*
X1384724Y601394D01*
G01Y601058D02*
X1384970Y600765D01*
G01X1384068Y601100D02*
X1383904Y601268D01*
G01X1338344Y652626D02*
X1338339Y650839D01*
G01X1338330Y651106D02*
X1338335Y652893D01*
G01X1330470Y652626D02*
X1330465Y650839D01*
G01X1330456Y651106D02*
X1330461Y652893D01*
G01X1338198Y650390D02*
Y649406D01*
G01X1337332Y650390D02*
Y649406D01*
G01X1330324Y650390D02*
Y649406D01*
G01X1329458Y650390D02*
Y649406D01*
G01X1337196Y652893D02*
X1337200Y651106D01*
G01X1337191Y650839D02*
X1337186Y652626D01*
G01X1329322Y652893D02*
X1329326Y651106D01*
G01X1329317Y650839D02*
X1329312Y652626D01*
G01X1384150Y599634D02*
X1383002Y600681D01*
G01X1382796Y600556D02*
X1383822Y599634D01*
G01X1383699Y601142D02*
X1383822Y601058D01*
G01X1383904Y601268D02*
X1383740Y601352D01*
G01X1384444Y651106D02*
X1385574D01*
G01X1376570D02*
X1377700D01*
G01X1368696D02*
X1369826D01*
G01X1360822D02*
X1361952D01*
G01X1352948D02*
X1354078D01*
G01X1345074D02*
X1346204D01*
G01X1337200D02*
X1338330D01*
G01X1329326D02*
X1330456D01*
G01X1330465Y650839D02*
X1329317D01*
G01X1338339D02*
X1337191D01*
G01X1346213D02*
X1345065D01*
G01X1354087D02*
X1352939D01*
G01X1361961D02*
X1360813D01*
G01X1369835D02*
X1368687D01*
G01X1377709D02*
X1376561D01*
G01X1385583D02*
X1384435D01*
G01X1330446Y650390D02*
X1329336D01*
G01X1338320D02*
X1337210D01*
G01X1346194D02*
X1345084D01*
G01X1354069D02*
X1352958D01*
G01X1361943D02*
X1360832D01*
G01X1369817D02*
X1368706D01*
G01X1377691D02*
X1376580D01*
G01X1385565D02*
X1384454D01*
G01X1385994Y649701D02*
X1377135D01*
G01X1397805D02*
X1387962D01*
G01X1384454Y649406D02*
X1385565D01*
G01X1376580D02*
X1377691D01*
G01X1368706D02*
X1369817D01*
G01X1360832D02*
X1361943D01*
G01X1352958D02*
X1354069D01*
G01X1345084D02*
X1346194D01*
G01X1337210D02*
X1338320D01*
G01X1329336D02*
X1330446D01*
G01X1370639Y643795D02*
X1382450D01*
G01X1344655D02*
X1356466D01*
G01X1383494Y601184D02*
X1383699Y601142D01*
G01X1383740Y601352D02*
X1383453Y601394D01*
G01X1356466Y624110D02*
X1344655D01*
G01X1382450D02*
X1370639D01*
G01X1383631Y606394D02*
X1386387D01*
G01X1379694D02*
X1382450D01*
G01X1375757D02*
X1378513D01*
G01X1371820D02*
X1374576D01*
G01X1367883D02*
X1370639D01*
G01X1363946D02*
X1366702D01*
G01X1360009D02*
X1362765D01*
G01X1356072D02*
X1358828D01*
G01X1352135D02*
X1354891D01*
G01X1348198D02*
X1350954D01*
G01X1344261D02*
X1347017D01*
G01X1340324D02*
X1343080D01*
G01X1336387D02*
X1339143D01*
G01X1332450D02*
X1335206D01*
G01X1383453Y601394D02*
X1383289D01*
G01X1384724D02*
X1384478D01*
G01X1386282D02*
X1385954D01*
G01X1383330Y601184D02*
X1383494D01*
G01X1383904Y600933D02*
X1384109D01*
G01X1385749Y600095D02*
X1386487D01*
G01X1385708Y599928D02*
X1386528D01*
G01X1383822Y599634D02*
X1382673D01*
G01X1386693Y599425D02*
X1386939D01*
G01X1385298D02*
X1385544D01*
G01X1384478D02*
X1384724D01*
G01X1382673D02*
X1384150D01*
G01X1389602Y594583D02*
X1389356D01*
G01X1383289Y601394D02*
X1383043Y601352D01*
G01X1383124Y601142D02*
X1383330Y601184D01*
G01X1387766Y661219D02*
G03Y664167I2558J1474D01*
G01X1394065Y664454D02*
G03X1387765Y665939I-3740J-1761D01*
G01Y659446D02*
G03X1394065Y660932I2559J3247D01*
G01Y665065D02*
G03X1387765Y666308I-3741J-2372D01*
G01Y659078D02*
G03X1394065Y660320I2560J3615D01*
G01X1385602Y659150D02*
X1385615Y659810D01*
G01X1385613Y660738D02*
X1385582Y659150D01*
G01X1384406Y664647D02*
X1384436Y666236D01*
G01X1384416D02*
X1384404Y665575D01*
G01X1381665Y659150D02*
X1381678Y659810D01*
G01X1381676Y660738D02*
X1381645Y659150D01*
G01X1380469Y664647D02*
X1380499Y666236D01*
G01X1380479D02*
X1380467Y665575D01*
G01X1385637Y664735D02*
X1385662Y666236D01*
G01X1385644D02*
X1385635Y665645D01*
G01X1384374Y659150D02*
X1384384Y659740D01*
G01X1384381Y660650D02*
X1384357Y659150D01*
G01X1381700Y664735D02*
X1381725Y666236D01*
G01X1381707D02*
X1381698Y665645D01*
G01X1380437Y659150D02*
X1380447Y659740D01*
G01X1380444Y660650D02*
X1380420Y659150D01*
G01X1384444Y674279D02*
X1384440Y672492D01*
G01X1384430Y672760D02*
X1384435Y674547D01*
G01X1381652Y670342D02*
X1381646Y668555D01*
G01X1381637Y668823D02*
X1381642Y670610D01*
G01X1380507Y656563D02*
X1380503Y654776D01*
G01X1380493Y655043D02*
X1380498Y656830D01*
G01X1389439Y675488D02*
Y675291D01*
G01X1387969Y659150D02*
Y657575D01*
G01Y667811D02*
Y666236D01*
G01X1387765Y666308D02*
Y659078D01*
G01X1387470Y675291D02*
Y675488D01*
G01X1387372Y666236D02*
Y659150D01*
G01X1387224Y675291D02*
Y675488D01*
G01X1386732Y675291D02*
Y675488D01*
G01X1386486Y675291D02*
Y675488D01*
G01X1385994Y675291D02*
Y675488D01*
G01X1385836Y682772D02*
Y677161D01*
G01X1385748Y675291D02*
Y675488D01*
G01X1385598Y653343D02*
Y654327D01*
G01Y671059D02*
Y672043D01*
G01X1385502Y675291D02*
Y675488D01*
G01X1385443Y675980D02*
Y674996D01*
G01X1385256Y675291D02*
Y675488D01*
G01X1385009Y675291D02*
Y675488D01*
G01X1384576Y674996D02*
Y675980D01*
G01X1384517Y675291D02*
Y675488D01*
G01X1384421Y654327D02*
Y653343D01*
G01Y672043D02*
Y671059D01*
G01X1384271Y675291D02*
Y675488D01*
G01X1384025Y675291D02*
Y675488D01*
G01X1383533Y675291D02*
Y675488D01*
G01X1382303Y675291D02*
Y675488D01*
G01X1382057Y675291D02*
Y675488D01*
G01X1381661Y654327D02*
Y653343D01*
G01Y672043D02*
Y671059D01*
G01X1381506Y658264D02*
Y657280D01*
G01Y668106D02*
Y667122D01*
G01X1381319Y675291D02*
Y675488D01*
G01X1381072Y675291D02*
Y675488D01*
G01X1380826Y675291D02*
Y675488D01*
G01X1380639Y658264D02*
Y657280D01*
G01Y667122D02*
Y668106D01*
G01X1380580Y675488D02*
Y675291D01*
G01X1380484Y653343D02*
Y654327D01*
G01Y671059D02*
Y672043D01*
G01X1380334Y675291D02*
Y675488D01*
G01X1380088Y675291D02*
Y675488D01*
G01X1379842Y675291D02*
Y675488D01*
G01X1379350Y675291D02*
Y675488D01*
G01X1379104Y675291D02*
Y675488D01*
G01X1378858Y675291D02*
Y675488D01*
G01X1378366Y675291D02*
Y675488D01*
G01X1385583Y674547D02*
X1385589Y672760D01*
G01X1385579Y672492D02*
X1385574Y674279D01*
G01X1381646Y656830D02*
X1381652Y655043D01*
G01X1381642Y654776D02*
X1381637Y656563D01*
G01X1380503Y670610D02*
X1380507Y668823D01*
G01X1380498Y668555D02*
X1380493Y670342D01*
G01X1385662Y659150D02*
X1385637Y660650D01*
G01X1385635Y659740D02*
X1385644Y659150D01*
G01X1384384Y665645D02*
X1384374Y666236D01*
G01X1384357D02*
X1384381Y664735D01*
G01X1381725Y659150D02*
X1381700Y660650D01*
G01X1381698Y659740D02*
X1381707Y659150D01*
G01X1380447Y665645D02*
X1380437Y666236D01*
G01X1380420D02*
X1380444Y664735D01*
G01X1385615Y665575D02*
X1385602Y666236D01*
G01X1385582D02*
X1385613Y664647D01*
G01X1384436Y659150D02*
X1384406Y660738D01*
G01X1384404Y659810D02*
X1384416Y659150D01*
G01X1381678Y665575D02*
X1381665Y666236D01*
G01X1381645D02*
X1381676Y664647D01*
G01X1380499Y659150D02*
X1380469Y660738D01*
G01X1380467Y659810D02*
X1380479Y659150D01*
G01X1377741Y665575D02*
X1377728Y666236D01*
G01Y659150D02*
X1377741Y659810D01*
G01X1377739Y660738D02*
X1377708Y659150D01*
G01X1376531Y664647D02*
X1376562Y666236D01*
G01X1376542D02*
X1376530Y665575D01*
G01X1373791Y659150D02*
X1373804Y659810D01*
G01X1373802Y660738D02*
X1373771Y659150D01*
G01X1372594Y664647D02*
X1372625Y666236D01*
G01X1372605D02*
X1372593Y665575D01*
G01X1369854Y659150D02*
X1369867Y659810D01*
G01X1369865Y660738D02*
X1369834Y659150D01*
G01X1368657Y664647D02*
X1368688Y666236D01*
G01X1368668D02*
X1368656Y665575D01*
G01X1365917Y659150D02*
X1365930Y659810D01*
G01X1365928Y660738D02*
X1365897Y659150D01*
G01X1377763Y664735D02*
X1377788Y666236D01*
G01X1377770D02*
X1377761Y665645D01*
G01X1376500Y659150D02*
X1376510Y659740D01*
G01X1376507Y660650D02*
X1376483Y659150D01*
G01X1373826Y664735D02*
X1373851Y666236D01*
G01X1373833D02*
X1373824Y665645D01*
G01X1372563Y659150D02*
X1372573Y659740D01*
G01X1372570Y660650D02*
X1372546Y659150D01*
G01X1369889Y664735D02*
X1369914Y666236D01*
G01X1369896D02*
X1369887Y665645D01*
G01X1368626Y659150D02*
X1368636Y659740D01*
G01X1368633Y660650D02*
X1368609Y659150D01*
G01X1365952Y664735D02*
X1365977Y666236D01*
G01X1365959D02*
X1365950Y665645D01*
G01X1376570Y674279D02*
X1376566Y672492D01*
G01X1376556Y672760D02*
X1376561Y674547D01*
G01X1373778Y670342D02*
X1373772Y668555D01*
G01X1373763Y668823D02*
X1373768Y670610D01*
G01X1372633Y656563D02*
X1372629Y654776D01*
G01X1372619Y655043D02*
X1372624Y656830D01*
G01X1368696Y674279D02*
X1368692Y672492D01*
G01X1368682Y672760D02*
X1368687Y674547D01*
G01X1365904Y670342D02*
X1365898Y668555D01*
G01X1365889Y668823D02*
X1365894Y670610D01*
G01X1377724Y653343D02*
Y654327D01*
G01Y671059D02*
Y672043D01*
G01X1377569Y675980D02*
Y674996D01*
G01X1376702D02*
Y675980D01*
G01X1376547Y654327D02*
Y653343D01*
G01Y672043D02*
Y671059D01*
G01X1373787Y654327D02*
Y653343D01*
G01Y672043D02*
Y671059D01*
G01X1373631Y658264D02*
Y657280D01*
G01Y668106D02*
Y667122D01*
G01X1372765Y658264D02*
Y657280D01*
G01Y667122D02*
Y668106D01*
G01X1372610Y653343D02*
Y654327D01*
G01Y671059D02*
Y672043D01*
G01X1369931Y682772D02*
Y677161D01*
G01X1369850Y653343D02*
Y654327D01*
G01Y672043D02*
Y671059D01*
G01X1369694Y675980D02*
Y674996D01*
G01X1368828D02*
Y675980D01*
G01X1368673Y654327D02*
Y653343D01*
G01Y671059D02*
Y672043D01*
G01X1365913Y654327D02*
Y653343D01*
G01Y672043D02*
Y671059D01*
G01X1365757Y658264D02*
Y657280D01*
G01Y668106D02*
Y667122D01*
G01X1377709Y674547D02*
X1377715Y672760D01*
G01X1377705Y672492D02*
X1377700Y674279D01*
G01X1373772Y656830D02*
X1373778Y655043D01*
G01X1373768Y654776D02*
X1373763Y656563D01*
G01X1372629Y670610D02*
X1372633Y668823D01*
G01X1372624Y668555D02*
X1372619Y670342D01*
G01X1369835Y674547D02*
X1369841Y672760D01*
G01X1369831Y672492D02*
X1369826Y674279D01*
G01X1365898Y656830D02*
X1365904Y655043D01*
G01X1365894Y654776D02*
X1365889Y656563D01*
G01X1377788Y659150D02*
X1377763Y660650D01*
G01X1377761Y659740D02*
X1377770Y659150D01*
G01X1376510Y665645D02*
X1376500Y666236D01*
G01X1376483D02*
X1376507Y664735D01*
G01X1373851Y659150D02*
X1373826Y660650D01*
G01X1373824Y659740D02*
X1373833Y659150D01*
G01X1372573Y665645D02*
X1372563Y666236D01*
G01X1372546D02*
X1372570Y664735D01*
G01X1369914Y659150D02*
X1369889Y660650D01*
G01X1369887Y659740D02*
X1369896Y659150D01*
G01X1368636Y665645D02*
X1368626Y666236D01*
G01X1368609D02*
X1368633Y664735D01*
G01X1365977Y659150D02*
X1365952Y660650D01*
G01X1365950Y659740D02*
X1365959Y659150D01*
G01X1377708Y666236D02*
X1377739Y664647D01*
G01X1376562Y659150D02*
X1376531Y660738D01*
G01X1376530Y659810D02*
X1376542Y659150D01*
G01X1373804Y665575D02*
X1373791Y666236D01*
G01X1373771D02*
X1373802Y664647D01*
G01X1372625Y659150D02*
X1372594Y660738D01*
G01X1372593Y659810D02*
X1372605Y659150D01*
G01X1369867Y665575D02*
X1369854Y666236D01*
G01X1369834D02*
X1369865Y664647D01*
G01X1368688Y659150D02*
X1368657Y660738D01*
G01X1368656Y659810D02*
X1368668Y659150D01*
G01X1365930Y665575D02*
X1365917Y666236D01*
G01X1365897D02*
X1365928Y664647D01*
G01X1364720D02*
X1364751Y666236D01*
G01X1364731D02*
X1364719Y665575D01*
G01X1361980Y659150D02*
X1361993Y659810D01*
G01X1361991Y660738D02*
X1361960Y659150D01*
G01X1360783Y664647D02*
X1360814Y666236D01*
G01X1360794D02*
X1360781Y665575D01*
G01X1358043Y659150D02*
X1358056Y659810D01*
G01X1358054Y660738D02*
X1358023Y659150D01*
G01X1356846Y664647D02*
X1356877Y666236D01*
G01X1356857D02*
X1356844Y665575D01*
G01X1354106Y659150D02*
X1354119Y659810D01*
G01X1354117Y660738D02*
X1354086Y659150D01*
G01X1352909Y664647D02*
X1352940Y666236D01*
G01X1352920D02*
X1352907Y665575D01*
G01X1364689Y659150D02*
X1364699Y659740D01*
G01X1364696Y660650D02*
X1364672Y659150D01*
G01X1362015Y664735D02*
X1362040Y666236D01*
G01X1362022D02*
X1362013Y665645D01*
G01X1360752Y659150D02*
X1360762Y659740D01*
G01X1360759Y660650D02*
X1360735Y659150D01*
G01X1358078Y664735D02*
X1358103Y666236D01*
G01X1358085D02*
X1358076Y665645D01*
G01X1356815Y659150D02*
X1356825Y659740D01*
G01X1356822Y660650D02*
X1356798Y659150D01*
G01X1354141Y664735D02*
X1354166Y666236D01*
G01X1354148D02*
X1354139Y665645D01*
G01X1352878Y659150D02*
X1352888Y659740D01*
G01X1352885Y660650D02*
X1352861Y659150D01*
G01X1364759Y656563D02*
X1364755Y654776D01*
G01X1364745Y655043D02*
X1364750Y656830D01*
G01X1360822Y674279D02*
X1360818Y672492D01*
G01X1360808Y672760D02*
X1360813Y674547D01*
G01X1358030Y670342D02*
X1358024Y668555D01*
G01X1358015Y668823D02*
X1358020Y670610D01*
G01X1356885Y656563D02*
X1356881Y654776D01*
G01X1356871Y655043D02*
X1356876Y656830D01*
G01X1352948Y674279D02*
X1352944Y672492D01*
G01X1352934Y672760D02*
X1352939Y674547D01*
G01X1364931Y682772D02*
Y677161D01*
G01X1364891Y658264D02*
Y657280D01*
G01Y667122D02*
Y668106D01*
G01X1364736Y653343D02*
Y654327D01*
G01Y671059D02*
Y672043D01*
G01X1361976Y653343D02*
Y654327D01*
G01Y671059D02*
Y672043D01*
G01X1361820Y675980D02*
Y674996D01*
G01X1360954D02*
Y675980D01*
G01X1360799Y654327D02*
Y653343D01*
G01Y672043D02*
Y671059D01*
G01X1358039Y654327D02*
Y653343D01*
G01Y671059D02*
Y672043D01*
G01X1357883Y658264D02*
Y657280D01*
G01Y668106D02*
Y667122D01*
G01X1357017Y658264D02*
Y657280D01*
G01Y667122D02*
Y668106D01*
G01X1356862Y653343D02*
Y654327D01*
G01Y672043D02*
Y671059D01*
G01X1354102Y653343D02*
Y654327D01*
G01Y671059D02*
Y672043D01*
G01X1353946Y675980D02*
Y674996D01*
G01X1353080D02*
Y675980D01*
G01X1352925Y654327D02*
Y653343D01*
G01Y672043D02*
Y671059D01*
G01X1364755Y670610D02*
X1364759Y668823D01*
G01X1364750Y668555D02*
X1364745Y670342D01*
G01X1361961Y674547D02*
X1361967Y672760D01*
G01X1361957Y672492D02*
X1361952Y674279D01*
G01X1358024Y656830D02*
X1358030Y655043D01*
G01X1358020Y654776D02*
X1358015Y656563D01*
G01X1356881Y670610D02*
X1356885Y668823D01*
G01X1356876Y668555D02*
X1356871Y670342D01*
G01X1354087Y674547D02*
X1354093Y672760D01*
G01X1354083Y672492D02*
X1354078Y674279D01*
G01X1364699Y665645D02*
X1364689Y666236D01*
G01X1364672D02*
X1364696Y664735D01*
G01X1362040Y659150D02*
X1362015Y660650D01*
G01X1362013Y659740D02*
X1362022Y659150D01*
G01X1360762Y665645D02*
X1360752Y666236D01*
G01X1360735D02*
X1360759Y664735D01*
G01X1358103Y659150D02*
X1358078Y660650D01*
G01X1358076Y659740D02*
X1358085Y659150D01*
G01X1356825Y665645D02*
X1356815Y666236D01*
G01X1356798D02*
X1356822Y664735D01*
G01X1354166Y659150D02*
X1354141Y660650D01*
G01X1354139Y659740D02*
X1354148Y659150D01*
G01X1352888Y665645D02*
X1352878Y666236D01*
G01X1352861D02*
X1352885Y664735D01*
G01X1364751Y659150D02*
X1364720Y660738D01*
G01X1364719Y659810D02*
X1364731Y659150D01*
G01X1361993Y665575D02*
X1361980Y666236D01*
G01X1361960D02*
X1361991Y664647D01*
G01X1360814Y659150D02*
X1360783Y660738D01*
G01X1360781Y659810D02*
X1360794Y659150D01*
G01X1358056Y665575D02*
X1358043Y666236D01*
G01X1358023D02*
X1358054Y664647D01*
G01X1356877Y659150D02*
X1356846Y660738D01*
G01X1356844Y659810D02*
X1356857Y659150D01*
G01X1354119Y665575D02*
X1354106Y666236D01*
G01X1354086D02*
X1354117Y664647D01*
G01X1352940Y659150D02*
X1352909Y660738D01*
G01X1352907Y659810D02*
X1352920Y659150D01*
G01X1350169D02*
X1350182Y659810D01*
G01X1350180Y660738D02*
X1350149Y659150D01*
G01X1348972Y664647D02*
X1349003Y666236D01*
G01X1348983D02*
X1348970Y665575D01*
G01X1346232Y659150D02*
X1346245Y659810D01*
G01X1346243Y660738D02*
X1346212Y659150D01*
G01X1345035Y664647D02*
X1345066Y666236D01*
G01X1345046D02*
X1345033Y665575D01*
G01X1342295Y659150D02*
X1342308Y659810D01*
G01X1342306Y660738D02*
X1342275Y659150D01*
G01X1341098Y664647D02*
X1341129Y666236D01*
G01X1341109D02*
X1341096Y665575D01*
G01X1350204Y664735D02*
X1350229Y666236D01*
G01X1350211D02*
X1350202Y665645D01*
G01X1348941Y659150D02*
X1348951Y659740D01*
G01X1348948Y660650D02*
X1348924Y659150D01*
G01X1346267Y664735D02*
X1346292Y666236D01*
G01X1346274D02*
X1346265Y665645D01*
G01X1345004Y659150D02*
X1345014Y659740D01*
G01X1345011Y660650D02*
X1344987Y659150D01*
G01X1342330Y664735D02*
X1342355Y666236D01*
G01X1342337D02*
X1342328Y665645D01*
G01X1341067Y659150D02*
X1341077Y659740D01*
G01X1341074Y660650D02*
X1341050Y659150D01*
G01X1350156Y670342D02*
X1350150Y668555D01*
G01X1350141Y668823D02*
X1350146Y670610D01*
G01X1349011Y656563D02*
X1349007Y654776D01*
G01X1348997Y655043D02*
X1349002Y656830D01*
G01X1345074Y674279D02*
X1345070Y672492D01*
G01X1345060Y672760D02*
X1345065Y674547D01*
G01X1342281Y670342D02*
X1342276Y668555D01*
G01X1342267Y668823D02*
X1342272Y670610D01*
G01X1341137Y656563D02*
X1341133Y654776D01*
G01X1341123Y655043D02*
X1341128Y656830D01*
G01X1350165Y654327D02*
Y653343D01*
G01Y672043D02*
Y671059D01*
G01X1350009Y658264D02*
Y657280D01*
G01Y668106D02*
Y667122D01*
G01X1349143Y658264D02*
Y657280D01*
G01Y667122D02*
Y668106D01*
G01X1349025Y682772D02*
Y677161D01*
G01X1348988Y653343D02*
Y654327D01*
G01Y671059D02*
Y672043D01*
G01X1346228Y653343D02*
Y654327D01*
G01Y671059D02*
Y672043D01*
G01X1346072Y675980D02*
Y674996D01*
G01X1345206D02*
Y675980D01*
G01X1345051Y654327D02*
Y653343D01*
G01Y672043D02*
Y671059D01*
G01X1344025Y682772D02*
Y677161D01*
G01X1342291Y654327D02*
Y653343D01*
G01Y672043D02*
Y671059D01*
G01X1342135Y658264D02*
Y657280D01*
G01Y668106D02*
Y667122D01*
G01X1341269Y658264D02*
Y657280D01*
G01Y667122D02*
Y668106D01*
G01X1341114Y653343D02*
Y654327D01*
G01Y671059D02*
Y672043D01*
G01X1350150Y656830D02*
X1350156Y655043D01*
G01X1350146Y654776D02*
X1350141Y656563D01*
G01X1349007Y670610D02*
X1349011Y668823D01*
G01X1349002Y668555D02*
X1348997Y670342D01*
G01X1346213Y674547D02*
X1346219Y672760D01*
G01X1346209Y672492D02*
X1346204Y674279D01*
G01X1342276Y656830D02*
X1342281Y655043D01*
G01X1342272Y654776D02*
X1342267Y656563D01*
G01X1341133Y670610D02*
X1341137Y668823D01*
G01X1341128Y668555D02*
X1341123Y670342D01*
G01X1350229Y659150D02*
X1350204Y660650D01*
G01X1350202Y659740D02*
X1350211Y659150D01*
G01X1348951Y665645D02*
X1348941Y666236D01*
G01X1348924D02*
X1348948Y664735D01*
G01X1346292Y659150D02*
X1346267Y660650D01*
G01X1346265Y659740D02*
X1346274Y659150D01*
G01X1345014Y665645D02*
X1345004Y666236D01*
G01X1344987D02*
X1345011Y664735D01*
G01X1342355Y659150D02*
X1342330Y660650D01*
G01X1342328Y659740D02*
X1342337Y659150D01*
G01X1341077Y665645D02*
X1341067Y666236D01*
G01X1341050D02*
X1341074Y664735D01*
G01X1350182Y665575D02*
X1350169Y666236D01*
G01X1350149D02*
X1350180Y664647D01*
G01X1349003Y659150D02*
X1348972Y660738D01*
G01X1348970Y659810D02*
X1348983Y659150D01*
G01X1346245Y665575D02*
X1346232Y666236D01*
G01X1346212D02*
X1346243Y664647D01*
G01X1345066Y659150D02*
X1345035Y660738D01*
G01X1345033Y659810D02*
X1345046Y659150D01*
G01X1342308Y665575D02*
X1342295Y666236D01*
G01X1342275D02*
X1342306Y664647D01*
G01X1341129Y659150D02*
X1341098Y660738D01*
G01X1341096Y659810D02*
X1341109Y659150D01*
G01X1338358D02*
X1338371Y659810D01*
G01X1338369Y660738D02*
X1338338Y659150D01*
G01X1337161Y664647D02*
X1337192Y666236D01*
G01X1337172D02*
X1337159Y665575D01*
G01X1334421Y659150D02*
X1334434Y659810D01*
G01X1334432Y660738D02*
X1334401Y659150D01*
G01X1333224Y664647D02*
X1333255Y666236D01*
G01X1333235D02*
X1333222Y665575D01*
G01X1330484Y659150D02*
X1330497Y659810D01*
G01X1330495Y660738D02*
X1330464Y659150D01*
G01X1329287Y664647D02*
X1329318Y666236D01*
G01X1329298D02*
X1329285Y665575D01*
G01X1338393Y664735D02*
X1338418Y666236D01*
G01X1338400D02*
X1338391Y665645D01*
G01X1337130Y659150D02*
X1337140Y659740D01*
G01X1337137Y660650D02*
X1337113Y659150D01*
G01X1334456Y664735D02*
X1334481Y666236D01*
G01X1334463D02*
X1334454Y665645D01*
G01X1333193Y659150D02*
X1333203Y659740D01*
G01X1333200Y660650D02*
X1333176Y659150D01*
G01X1330519Y664735D02*
X1330544Y666236D01*
G01X1330526D02*
X1330517Y665645D01*
G01X1329256Y659150D02*
X1329266Y659740D01*
G01X1329263Y660650D02*
X1329239Y659150D01*
G01X1337200Y674279D02*
X1337196Y672492D01*
G01X1337186Y672760D02*
X1337191Y674547D01*
G01X1334407Y670342D02*
X1334402Y668555D01*
G01X1334393Y668823D02*
X1334398Y670610D01*
G01X1333263Y656563D02*
X1333259Y654776D01*
G01X1333249Y655043D02*
X1333254Y656830D01*
G01X1329326Y674279D02*
X1329322Y672492D01*
G01X1329312Y672760D02*
X1329317Y674547D01*
G01X1338354Y653343D02*
Y654327D01*
G01Y671059D02*
Y672043D01*
G01X1338198Y675980D02*
Y674996D01*
G01X1337332D02*
Y675980D01*
G01X1337177Y654327D02*
Y653343D01*
G01Y672043D02*
Y671059D01*
G01X1334417Y653343D02*
Y654327D01*
G01Y672043D02*
Y671059D01*
G01X1334261Y658264D02*
Y657280D01*
G01Y668106D02*
Y667122D01*
G01X1333395Y658264D02*
Y657280D01*
G01Y667122D02*
Y668106D01*
G01X1333240Y654327D02*
Y653343D01*
G01Y671059D02*
Y672043D01*
G01X1330480Y653343D02*
Y654327D01*
G01Y671059D02*
Y672043D01*
G01X1330324Y675980D02*
Y674996D01*
G01X1329458D02*
Y675980D01*
G01X1329303Y654327D02*
Y653343D01*
G01Y672043D02*
Y671059D01*
G01X1338339Y674547D02*
X1338344Y672760D01*
G01X1338335Y672492D02*
X1338330Y674279D01*
G01X1334402Y656830D02*
X1334407Y655043D01*
G01X1334398Y654776D02*
X1334393Y656563D01*
G01X1333259Y670610D02*
X1333263Y668823D01*
G01X1333254Y668555D02*
X1333249Y670342D01*
G01X1330465Y674547D02*
X1330470Y672760D01*
G01X1330461Y672492D02*
X1330456Y674279D01*
G01X1338418Y659150D02*
X1338393Y660650D01*
G01X1338391Y659740D02*
X1338400Y659150D01*
G01X1337140Y665645D02*
X1337130Y666236D01*
G01X1337113D02*
X1337137Y664735D01*
G01X1334481Y659150D02*
X1334456Y660650D01*
G01X1334454Y659740D02*
X1334463Y659150D01*
G01X1333203Y665645D02*
X1333193Y666236D01*
G01X1333176D02*
X1333200Y664735D01*
G01X1330544Y659150D02*
X1330519Y660650D01*
G01X1330517Y659740D02*
X1330526Y659150D01*
G01X1329266Y665645D02*
X1329256Y666236D01*
G01X1329239D02*
X1329263Y664735D01*
G01X1338371Y665575D02*
X1338358Y666236D01*
G01X1338338D02*
X1338369Y664647D01*
G01X1337192Y659150D02*
X1337161Y660738D01*
G01X1337159Y659810D02*
X1337172Y659150D01*
G01X1334434Y665575D02*
X1334421Y666236D01*
G01X1334401D02*
X1334432Y664647D01*
G01X1333255Y659150D02*
X1333224Y660738D01*
G01X1333222Y659810D02*
X1333235Y659150D01*
G01X1330497Y665575D02*
X1330484Y666236D01*
G01X1330464D02*
X1330495Y664647D01*
G01X1329318Y659150D02*
X1329287Y660738D01*
G01X1329285Y659810D02*
X1329298Y659150D01*
G01X1364931Y682772D02*
X1349025D01*
G01X1385836D02*
X1369931D01*
G01X1330446Y675980D02*
X1329336D01*
G01X1338320D02*
X1337210D01*
G01X1346194D02*
X1345084D01*
G01X1354069D02*
X1352958D01*
G01X1361943D02*
X1360832D01*
G01X1369817D02*
X1368706D01*
G01X1377691D02*
X1376580D01*
G01X1385565D02*
X1384454D01*
G01X1387470Y675291D02*
X1378366D01*
G01X1398297D02*
X1389439D01*
G01X1330446Y674996D02*
X1329336D01*
G01X1338320D02*
X1337210D01*
G01X1346194D02*
X1345084D01*
G01X1354069D02*
X1352958D01*
G01X1361943D02*
X1360832D01*
G01X1369817D02*
X1368706D01*
G01X1377691D02*
X1376580D01*
G01X1385565D02*
X1384454D01*
G01X1384435Y674547D02*
X1385583D01*
G01X1376561D02*
X1377709D01*
G01X1368687D02*
X1369835D01*
G01X1360813D02*
X1361961D01*
G01X1352939D02*
X1354087D01*
G01X1345065D02*
X1346213D01*
G01X1337191D02*
X1338339D01*
G01X1329317D02*
X1330465D01*
G01X1330456Y674279D02*
X1329326D01*
G01X1338330D02*
X1337200D01*
G01X1346204D02*
X1345074D01*
G01X1354078D02*
X1352948D01*
G01X1361952D02*
X1360822D01*
G01X1369826D02*
X1368696D01*
G01X1377700D02*
X1376570D01*
G01X1385574D02*
X1384444D01*
G01X1330470Y672760D02*
X1329312D01*
G01X1338344D02*
X1337186D01*
G01X1346219D02*
X1345060D01*
G01X1354093D02*
X1352934D01*
G01X1361967D02*
X1360808D01*
G01X1369841D02*
X1368682D01*
G01X1377715D02*
X1376556D01*
G01X1385589D02*
X1384430D01*
G01X1384440Y672492D02*
X1385579D01*
G01X1376566D02*
X1377705D01*
G01X1368692D02*
X1369831D01*
G01X1360818D02*
X1361957D01*
G01X1352944D02*
X1354083D01*
G01X1345070D02*
X1346209D01*
G01X1337196D02*
X1338335D01*
G01X1329322D02*
X1330461D01*
G01X1330480Y672043D02*
X1329303D01*
G01X1334417D02*
X1333240D01*
G01X1338354D02*
X1337177D01*
G01X1342291D02*
X1341114D01*
G01X1346228D02*
X1345051D01*
G01X1350165D02*
X1348988D01*
G01X1354102D02*
X1352925D01*
G01X1358039D02*
X1356862D01*
G01X1361976D02*
X1360799D01*
G01X1365913D02*
X1364736D01*
G01X1369850D02*
X1368673D01*
G01X1373787D02*
X1372610D01*
G01X1377724D02*
X1376547D01*
G01X1381661D02*
X1380484D01*
G01X1385598D02*
X1384421D01*
G01X1330480Y671059D02*
X1329303D01*
G01X1334417D02*
X1333240D01*
G01X1338354D02*
X1337177D01*
G01X1342291D02*
X1341114D01*
G01X1346228D02*
X1345051D01*
G01X1350165D02*
X1348988D01*
G01X1354102D02*
X1352925D01*
G01X1358039D02*
X1356862D01*
G01X1361976D02*
X1360799D01*
G01X1365913D02*
X1364736D01*
G01X1369850D02*
X1368673D01*
G01X1373787D02*
X1372610D01*
G01X1377724D02*
X1376547D01*
G01X1381661D02*
X1380484D01*
G01X1385598D02*
X1384421D01*
G01X1334398Y670610D02*
X1333259D01*
G01X1342272D02*
X1341133D01*
G01X1350146D02*
X1349007D01*
G01X1358020D02*
X1356881D01*
G01X1365894D02*
X1364755D01*
G01X1373768D02*
X1372629D01*
G01X1381642D02*
X1380503D01*
G01X1380493Y670342D02*
X1381652D01*
G01X1372619D02*
X1373778D01*
G01X1364745D02*
X1365904D01*
G01X1356871D02*
X1358030D01*
G01X1348997D02*
X1350156D01*
G01X1341123D02*
X1342281D01*
G01X1333249D02*
X1334407D01*
G01X1380507Y668823D02*
X1381637D01*
G01X1372633D02*
X1373763D01*
G01X1364759D02*
X1365889D01*
G01X1356885D02*
X1358015D01*
G01X1349011D02*
X1350141D01*
G01X1341137D02*
X1342267D01*
G01X1333263D02*
X1334393D01*
G01X1334402Y668555D02*
X1333254D01*
G01X1342276D02*
X1341128D01*
G01X1350150D02*
X1349002D01*
G01X1358024D02*
X1356876D01*
G01X1365898D02*
X1364750D01*
G01X1373772D02*
X1372624D01*
G01X1381646D02*
X1380498D01*
G01X1334383Y668106D02*
X1333273D01*
G01X1342257D02*
X1341147D01*
G01X1350131D02*
X1349021D01*
G01X1358006D02*
X1356895D01*
G01X1365880D02*
X1364769D01*
G01X1373754D02*
X1372643D01*
G01X1381628D02*
X1380517D01*
G01X1334383Y667122D02*
X1333273D01*
G01X1342257D02*
X1341147D01*
G01X1350131D02*
X1349021D01*
G01X1358006D02*
X1356895D01*
G01X1365880D02*
X1364769D01*
G01X1373754D02*
X1372643D01*
G01X1381628D02*
X1380517D01*
G01X1330517Y665645D02*
X1329266D01*
G01X1334454D02*
X1333203D01*
G01X1338391D02*
X1337140D01*
G01X1342328D02*
X1341077D01*
G01X1346265D02*
X1345014D01*
G01X1350202D02*
X1348951D01*
G01X1354139D02*
X1352888D01*
G01X1358076D02*
X1356825D01*
G01X1362013D02*
X1360762D01*
G01X1365950D02*
X1364699D01*
G01X1369887D02*
X1368636D01*
G01X1373824D02*
X1372573D01*
G01X1377761D02*
X1376510D01*
G01X1381698D02*
X1380447D01*
G01X1385635D02*
X1384384D01*
G01X1384404Y665575D02*
X1385615D01*
G01X1380467D02*
X1381678D01*
G01X1376530D02*
X1377741D01*
G01X1372593D02*
X1373804D01*
G01X1368656D02*
X1369867D01*
G01X1364719D02*
X1365930D01*
G01X1360781D02*
X1361993D01*
G01X1356844D02*
X1358056D01*
G01X1352907D02*
X1354119D01*
G01X1348970D02*
X1350182D01*
G01X1345033D02*
X1346245D01*
G01X1341096D02*
X1342308D01*
G01X1337159D02*
X1338371D01*
G01X1333222D02*
X1334434D01*
G01X1329285D02*
X1330497D01*
G01X1330506Y665350D02*
X1329276D01*
G01X1334443D02*
X1333213D01*
G01X1338380D02*
X1337150D01*
G01X1342317D02*
X1341087D01*
G01X1346254D02*
X1345024D01*
G01X1350191D02*
X1348961D01*
G01X1354128D02*
X1352898D01*
G01X1358065D02*
X1356835D01*
G01X1362002D02*
X1360772D01*
G01X1365939D02*
X1364709D01*
G01X1369876D02*
X1368646D01*
G01X1373813D02*
X1372583D01*
G01X1377750D02*
X1376520D01*
G01X1381687D02*
X1380457D01*
G01X1385624D02*
X1384394D01*
G01X1384381Y664735D02*
X1385637D01*
G01X1380444D02*
X1381700D01*
G01X1376507D02*
X1377763D01*
G01X1372570D02*
X1373826D01*
G01X1368633D02*
X1369889D01*
G01X1364696D02*
X1365952D01*
G01X1360759D02*
X1362015D01*
G01X1356822D02*
X1358078D01*
G01X1352885D02*
X1354141D01*
G01X1348948D02*
X1350204D01*
G01X1345011D02*
X1346267D01*
G01X1341074D02*
X1342330D01*
G01X1337137D02*
X1338393D01*
G01X1333200D02*
X1334456D01*
G01X1329263D02*
X1330519D01*
G01X1330495Y664647D02*
X1329287D01*
G01X1334432D02*
X1333224D01*
G01X1338369D02*
X1337161D01*
G01X1342306D02*
X1341098D01*
G01X1346243D02*
X1345035D01*
G01X1350180D02*
X1348972D01*
G01X1354117D02*
X1352909D01*
G01X1358054D02*
X1356846D01*
G01X1361991D02*
X1360783D01*
G01X1365928D02*
X1364720D01*
G01X1369865D02*
X1368657D01*
G01X1373802D02*
X1372594D01*
G01X1377739D02*
X1376531D01*
G01X1381676D02*
X1380469D01*
G01X1385613D02*
X1384406D01*
G01X1330506Y664365D02*
X1329276D01*
G01X1334443D02*
X1333213D01*
G01X1338380D02*
X1337150D01*
G01X1342317D02*
X1341087D01*
G01X1346254D02*
X1345024D01*
G01X1350191D02*
X1348961D01*
G01X1354128D02*
X1352898D01*
G01X1358065D02*
X1356835D01*
G01X1362002D02*
X1360772D01*
G01X1365939D02*
X1364709D01*
G01X1369876D02*
X1368646D01*
G01X1373813D02*
X1372583D01*
G01X1377750D02*
X1376520D01*
G01X1381687D02*
X1380457D01*
G01X1385624D02*
X1384394D01*
G01Y661020D02*
X1385624D01*
G01X1380457D02*
X1381687D01*
G01X1376520D02*
X1377750D01*
G01X1372583D02*
X1373813D01*
G01X1368646D02*
X1369876D01*
G01X1364709D02*
X1365939D01*
G01X1360772D02*
X1362002D01*
G01X1356835D02*
X1358065D01*
G01X1352898D02*
X1354128D01*
G01X1348961D02*
X1350191D01*
G01X1345024D02*
X1346254D01*
G01X1341087D02*
X1342317D01*
G01X1337150D02*
X1338380D01*
G01X1333213D02*
X1334443D01*
G01X1329276D02*
X1330506D01*
G01X1384406Y660738D02*
X1385613D01*
G01X1380469D02*
X1381676D01*
G01X1376531D02*
X1377739D01*
G01X1372594D02*
X1373802D01*
G01X1368657D02*
X1369865D01*
G01X1364720D02*
X1365928D01*
G01X1360783D02*
X1361991D01*
G01X1356846D02*
X1358054D01*
G01X1352909D02*
X1354117D01*
G01X1348972D02*
X1350180D01*
G01X1345035D02*
X1346243D01*
G01X1341098D02*
X1342306D01*
G01X1337161D02*
X1338369D01*
G01X1333224D02*
X1334432D01*
G01X1329287D02*
X1330495D01*
G01X1330519Y660650D02*
X1329263D01*
G01X1334456D02*
X1333200D01*
G01X1338393D02*
X1337137D01*
G01X1342330D02*
X1341074D01*
G01X1346267D02*
X1345011D01*
G01X1350204D02*
X1348948D01*
G01X1354141D02*
X1352885D01*
G01X1358078D02*
X1356822D01*
G01X1362015D02*
X1360759D01*
G01X1365952D02*
X1364696D01*
G01X1369889D02*
X1368633D01*
G01X1373826D02*
X1372570D01*
G01X1377763D02*
X1376507D01*
G01X1381700D02*
X1380444D01*
G01X1385637D02*
X1384381D01*
G01X1384394Y660036D02*
X1385624D01*
G01X1380457D02*
X1381687D01*
G01X1376520D02*
X1377750D01*
G01X1372583D02*
X1373813D01*
G01X1368646D02*
X1369876D01*
G01X1364709D02*
X1365939D01*
G01X1360772D02*
X1362002D01*
G01X1356835D02*
X1358065D01*
G01X1352898D02*
X1354128D01*
G01X1348961D02*
X1350191D01*
G01X1345024D02*
X1346254D01*
G01X1341087D02*
X1342317D01*
G01X1337150D02*
X1338380D01*
G01X1333213D02*
X1334443D01*
G01X1329276D02*
X1330506D01*
G01X1330497Y659810D02*
X1329285D01*
G01X1334434D02*
X1333222D01*
G01X1338371D02*
X1337159D01*
G01X1342308D02*
X1341096D01*
G01X1346245D02*
X1345033D01*
G01X1350182D02*
X1348970D01*
G01X1354119D02*
X1352907D01*
G01X1358056D02*
X1356844D01*
G01X1361993D02*
X1360781D01*
G01X1365930D02*
X1364719D01*
G01X1369867D02*
X1368656D01*
G01X1373804D02*
X1372593D01*
G01X1377741D02*
X1376530D01*
G01X1381678D02*
X1380467D01*
G01X1385615D02*
X1384404D01*
G01X1384384Y659740D02*
X1385635D01*
G01X1380447D02*
X1381698D01*
G01X1376510D02*
X1377761D01*
G01X1372573D02*
X1373824D01*
G01X1368636D02*
X1369887D01*
G01X1364699D02*
X1365950D01*
G01X1360762D02*
X1362013D01*
G01X1356825D02*
X1358076D01*
G01X1352888D02*
X1354139D01*
G01X1348951D02*
X1350202D01*
G01X1345014D02*
X1346265D01*
G01X1341077D02*
X1342328D01*
G01X1337140D02*
X1338391D01*
G01X1333203D02*
X1334454D01*
G01X1329266D02*
X1330517D01*
G01X1380517Y658264D02*
X1381628D01*
G01X1372643D02*
X1373754D01*
G01X1364769D02*
X1365880D01*
G01X1356895D02*
X1358006D01*
G01X1349021D02*
X1350131D01*
G01X1341147D02*
X1342257D01*
G01X1333273D02*
X1334383D01*
G01X1380517Y657280D02*
X1381628D01*
G01X1372643D02*
X1373754D01*
G01X1364769D02*
X1365880D01*
G01X1356895D02*
X1358006D01*
G01X1349021D02*
X1350131D01*
G01X1341147D02*
X1342257D01*
G01X1333273D02*
X1334383D01*
G01X1380498Y656830D02*
X1381646D01*
G01X1372624D02*
X1373772D01*
G01X1364750D02*
X1365898D01*
G01X1356876D02*
X1358024D01*
G01X1349002D02*
X1350150D01*
G01X1341128D02*
X1342276D01*
G01X1333254D02*
X1334402D01*
G01X1334393Y656563D02*
X1333263D01*
G01X1342267D02*
X1341137D01*
G01X1350141D02*
X1349011D01*
G01X1358015D02*
X1356885D01*
G01X1365889D02*
X1364759D01*
G01X1373763D02*
X1372633D01*
G01X1381637D02*
X1380507D01*
G01X1334407Y655043D02*
X1333249D01*
G01X1342281D02*
X1341123D01*
G01X1350156D02*
X1348997D01*
G01X1358030D02*
X1356871D01*
G01X1365904D02*
X1364745D01*
G01X1373778D02*
X1372619D01*
G01X1381652D02*
X1380493D01*
G01X1380503Y654776D02*
X1381642D01*
G01X1372629D02*
X1373768D01*
G01X1364755D02*
X1365894D01*
G01X1356881D02*
X1358020D01*
G01X1349007D02*
X1350146D01*
G01X1341133D02*
X1342272D01*
G01X1333259D02*
X1334398D01*
G01X1384421Y654327D02*
X1385598D01*
G01X1380484D02*
X1381661D01*
G01X1376547D02*
X1377724D01*
G01X1372610D02*
X1373787D01*
G01X1368673D02*
X1369850D01*
G01X1364736D02*
X1365913D01*
G01X1360799D02*
X1361976D01*
G01X1356862D02*
X1358039D01*
G01X1352925D02*
X1354102D01*
G01X1348988D02*
X1350165D01*
G01X1345051D02*
X1346228D01*
G01X1341114D02*
X1342291D01*
G01X1337177D02*
X1338354D01*
G01X1333240D02*
X1334417D01*
G01X1329303D02*
X1330480D01*
G01Y653343D02*
X1329303D01*
G01X1334417D02*
X1333240D01*
G01X1338354D02*
X1337177D01*
G01X1342291D02*
X1341114D01*
G01X1346228D02*
X1345051D01*
G01X1350165D02*
X1348988D01*
G01X1354102D02*
X1352925D01*
G01X1358039D02*
X1356862D01*
G01X1361976D02*
X1360799D01*
G01X1365913D02*
X1364736D01*
G01X1369850D02*
X1368673D01*
G01X1373787D02*
X1372610D01*
G01X1377724D02*
X1376547D01*
G01X1381661D02*
X1380484D01*
G01X1385598D02*
X1384421D01*
G01X1330461Y652893D02*
X1329322D01*
G01X1338335D02*
X1337196D01*
G01X1346209D02*
X1345070D01*
G01X1354083D02*
X1352944D01*
G01X1361957D02*
X1360818D01*
G01X1369831D02*
X1368692D01*
G01X1377705D02*
X1376566D01*
G01X1385579D02*
X1384440D01*
G01X1384430Y652626D02*
X1385589D01*
G01X1376556D02*
X1377715D01*
G01X1368682D02*
X1369841D01*
G01X1360808D02*
X1361967D01*
G01X1352934D02*
X1354093D01*
G01X1345060D02*
X1346219D01*
G01X1337186D02*
X1338344D01*
G01X1329312D02*
X1330470D01*
G01X1398543Y-426126D02*
Y-443449D01*
G01X1407412Y279969D02*
G03X1399931I-3740J0D01*
G01X1407412D02*
G03X1399931I-3740J0D01*
G01X1448898Y264778D02*
X1448857Y264653D01*
G01X1448652Y264820D02*
X1448611Y264694D01*
G01X1448857Y265491D02*
X1448898Y265616D01*
G01X1448652Y265658D02*
X1448611Y265532D01*
G01X1450325Y256150D02*
Y272686D01*
G01X1450128Y264024D02*
Y265993D01*
G01X1449882Y264276D02*
Y264904D01*
G01Y265742D02*
Y265156D01*
G01X1448857Y265407D02*
Y265491D01*
G01Y264653D02*
Y264527D01*
G01X1448611Y264694D02*
Y264485D01*
G01Y265532D02*
Y265365D01*
G01X1448283D02*
Y265700D01*
G01X1448037Y264024D02*
Y265658D01*
G01X1447791Y265993D02*
Y264024D01*
G01X1447569Y272686D02*
Y256150D01*
G01X1446388D02*
Y272686D01*
G01X1443632D02*
Y256150D01*
G01X1449538Y250639D02*
X1451506Y252607D01*
G01X1448775Y264988D02*
X1448652Y264820D01*
G01X1448775Y265826D02*
X1448652Y265658D01*
G01X1442451Y256150D02*
Y272686D01*
G01X1439695D02*
Y256150D01*
G01X1438514D02*
Y272686D01*
G01X1435758D02*
Y256150D01*
G01X1434577D02*
Y272686D01*
G01X1431821D02*
Y256150D01*
G01X1430640D02*
Y272686D01*
G01X1448898Y265281D02*
X1448857Y265407D01*
G01X1448611Y265365D02*
X1448652Y265239D01*
G01X1448857Y264527D02*
X1448898Y264402D01*
G01X1448611Y264485D02*
X1448652Y264359D01*
G01X1448980Y264862D02*
X1448898Y264778D01*
G01Y265616D02*
X1448980Y265700D01*
G01X1427884Y272686D02*
Y256150D01*
G01X1426703D02*
Y272686D01*
G01X1423947D02*
Y256150D01*
G01X1422766D02*
Y272686D01*
G01X1420010D02*
Y256150D01*
G01X1418829D02*
Y272686D01*
G01X1448939Y265951D02*
X1448775Y265826D01*
G01X1410035Y265815D02*
X1409912Y265647D01*
G01X1410035Y266652D02*
X1409912Y266485D01*
G01X1408822Y255187D02*
X1409519Y256150D01*
G01X1408125Y254182D02*
X1408699Y254978D01*
G01X1409273Y256150D02*
X1408699Y255355D01*
G01X1408576Y255187D02*
X1407879Y254182D01*
G01X1403015Y259911D02*
X1403672Y260875D01*
G01X1403426D02*
X1402892Y260079D01*
G01X1410158Y265605D02*
X1410117Y265480D01*
G01X1409912Y265647D02*
X1409870Y265521D01*
G01X1410117Y266317D02*
X1410158Y266443D01*
G01X1409912Y266485D02*
X1409870Y266359D01*
G01X1398583Y265487D02*
X1398542Y265361D01*
G01X1398337Y265529D02*
X1398296Y265403D01*
G01X1398542Y266199D02*
X1398583Y266325D01*
G01X1398337Y266367D02*
X1398296Y266241D01*
G01X1416073Y272686D02*
Y256150D01*
G01X1414892D02*
Y272686D01*
G01X1412136D02*
Y256150D01*
G01X1411388Y264851D02*
Y266820D01*
G01X1411142Y265103D02*
Y265731D01*
G01Y266569D02*
Y265982D01*
G01X1410955Y256150D02*
Y272686D01*
G01X1410117Y266233D02*
Y266317D01*
G01Y265480D02*
Y265354D01*
G01X1409870Y265521D02*
Y265312D01*
G01Y266359D02*
Y266191D01*
G01X1409543D02*
Y266527D01*
G01X1409296Y264851D02*
Y266485D01*
G01X1409050Y266820D02*
Y264851D01*
G01X1408722Y266191D02*
Y266527D01*
G01X1408476Y264851D02*
Y266485D01*
G01X1408230Y266820D02*
Y264851D01*
G01X1408199Y272686D02*
Y256150D01*
G01X1407412Y250639D02*
Y279969D01*
G01Y252607D02*
Y279969D01*
G01X1410158Y266108D02*
X1410117Y266233D01*
G01X1409870Y266191D02*
X1409912Y266066D01*
G01X1410117Y265354D02*
X1410158Y265228D01*
G01X1409870Y265312D02*
X1409912Y265186D01*
G01X1448652Y265239D02*
X1448775Y265072D01*
G01X1448652Y264359D02*
X1448775Y264192D01*
G01X1448857Y265030D02*
X1448775Y264988D01*
G01X1397963Y250639D02*
X1399931Y252607D01*
G01X1410240Y265689D02*
X1410158Y265605D01*
G01Y266443D02*
X1410240Y266527D01*
G01X1398665Y265571D02*
X1398583Y265487D01*
G01Y266325D02*
X1398665Y266409D01*
G01X1398460Y265696D02*
X1398337Y265529D01*
G01X1398460Y266534D02*
X1398337Y266367D01*
G01X1395917Y266241D02*
X1395999Y266367D01*
G01X1395712Y266409D02*
X1395671Y266241D01*
G01X1403672Y258906D02*
Y253394D01*
G01X1403015Y258906D02*
Y259911D01*
G01X1402769D02*
Y258906D01*
G01X1399931Y250639D02*
Y279969D01*
G01Y252607D02*
Y279969D01*
G01X1399813Y264733D02*
Y266702D01*
G01X1399567Y264985D02*
Y265613D01*
G01Y266450D02*
Y265864D01*
G01X1399144Y272686D02*
Y256150D01*
G01X1398542Y266115D02*
Y266199D01*
G01Y265361D02*
Y265236D01*
G01X1398296Y265403D02*
Y265194D01*
G01Y266241D02*
Y266073D01*
G01X1397968D02*
Y266409D01*
G01X1397722Y264733D02*
Y266367D01*
G01X1397476Y266702D02*
Y264733D01*
G01X1397148D02*
Y264943D01*
G01X1396388Y256150D02*
Y272686D01*
G01X1395917Y266157D02*
Y266241D01*
G01X1395671Y264943D02*
Y264733D01*
G01Y266241D02*
Y266157D01*
G01X1395207Y272686D02*
Y256150D01*
G01X1392451D02*
Y272686D01*
G01X1391270D02*
Y256150D01*
G01X1397107Y266241D02*
X1397065Y266409D01*
G01X1395671Y266157D02*
X1395712Y265990D01*
G01X1398583D02*
X1398542Y266115D01*
G01X1398296Y266073D02*
X1398337Y265948D01*
G01X1398542Y265236D02*
X1398583Y265110D01*
G01X1398296Y265194D02*
X1398337Y265068D01*
G01X1448283Y265700D02*
X1448037Y265993D01*
G01Y265658D02*
X1448283Y265365D01*
G01X1395999Y266367D02*
X1396122Y266450D01*
G01X1410199Y266778D02*
X1410035Y266652D01*
G01X1398624Y266660D02*
X1398460Y266534D01*
G01X1395876Y266576D02*
X1395712Y266409D01*
G01X1395999Y265990D02*
X1395917Y266157D01*
G01X1448980Y265197D02*
X1448898Y265281D01*
G01Y264402D02*
X1448980Y264318D01*
G01X1449103Y264904D02*
X1448980Y264862D01*
G01Y265700D02*
X1449103Y265742D01*
G01X1410117Y265856D02*
X1410035Y265815D01*
G01X1398542Y265738D02*
X1398460Y265696D01*
G01X1396040Y266660D02*
X1395876Y266576D01*
G01X1396819Y266367D02*
X1396902Y266241D01*
G01X1395712Y265990D02*
X1395794Y265864D01*
G01X1402892Y260079D02*
X1402359Y260875D01*
G01X1402113D02*
X1402769Y259911D01*
G01X1409519Y254182D02*
X1408822Y255187D01*
G01X1408699Y255355D02*
X1408125Y256150D01*
G01X1408699Y254978D02*
X1409273Y254182D01*
G01X1407879Y256150D02*
X1408576Y255187D01*
G01X1409912Y266066D02*
X1410035Y265898D01*
G01X1409912Y265186D02*
X1410035Y265019D01*
G01X1398337Y265948D02*
X1398460Y265780D01*
G01X1398337Y265068D02*
X1398460Y264901D01*
G01X1409543Y266527D02*
X1409296Y266820D01*
G01Y266485D02*
X1409543Y266191D01*
G01X1408722Y266527D02*
X1408476Y266820D01*
G01Y266485D02*
X1408722Y266191D01*
G01X1448775Y264192D02*
X1448939Y264067D01*
G01X1410363Y265731D02*
X1410240Y265689D01*
G01Y266527D02*
X1410363Y266569D01*
G01X1398788Y265613D02*
X1398665Y265571D01*
G01Y266409D02*
X1398788Y266450D01*
G01X1397968Y266409D02*
X1397722Y266702D01*
G01Y266367D02*
X1397968Y266073D01*
G01X1410240Y266024D02*
X1410158Y266108D01*
G01Y265228D02*
X1410240Y265144D01*
G01X1398665Y265906D02*
X1398583Y265990D01*
G01Y265110D02*
X1398665Y265026D01*
G01X1397065Y266409D02*
X1396902Y266576D01*
G01X1407412Y252607D02*
X1409380Y250639D01*
G01X1397148Y264943D02*
X1395999Y265990D01*
G01X1395794Y265864D02*
X1396819Y264943D01*
G01X1410035Y265019D02*
X1410199Y264893D01*
G01X1398460Y264901D02*
X1398624Y264775D01*
G01X1396696Y266450D02*
X1396819Y266367D01*
G01X1448775Y265072D02*
X1448857Y265030D01*
G01X1410035Y265898D02*
X1410117Y265856D01*
G01X1396902Y266576D02*
X1396737Y266660D01*
G01X1398460Y265780D02*
X1398542Y265738D01*
G01X1449103Y265156D02*
X1448980Y265197D01*
G01Y264318D02*
X1449103Y264276D01*
G01X1410363Y265982D02*
X1410240Y266024D01*
G01Y265144D02*
X1410363Y265103D01*
G01X1398788Y265864D02*
X1398665Y265906D01*
G01Y265026D02*
X1398788Y264985D01*
G01X1448939Y264067D02*
X1449144Y264024D01*
G01X1410199Y264893D02*
X1410404Y264851D01*
G01X1396491Y266492D02*
X1396696Y266450D01*
G01X1398624Y264775D02*
X1398829Y264733D01*
G01X1396737Y266660D02*
X1396450Y266702D01*
G01X1396388Y272686D02*
X1399144D01*
G01X1392451D02*
X1395207D01*
G01X1410955D02*
X1408199D01*
G01X1414892D02*
X1412136D01*
G01X1418829D02*
X1416073D01*
G01X1422766D02*
X1420010D01*
G01X1426703D02*
X1423947D01*
G01X1430640D02*
X1427884D01*
G01X1434577D02*
X1431821D01*
G01X1438514D02*
X1435758D01*
G01X1442451D02*
X1439695D01*
G01X1446388D02*
X1443632D01*
G01X1450325D02*
X1447569D01*
G01X1408476Y266820D02*
X1408230D01*
G01X1409296D02*
X1409050D01*
G01X1411388D02*
X1410404D01*
G01X1396450Y266702D02*
X1396286D01*
G01X1397722D02*
X1397476D01*
G01X1399813D02*
X1398829D01*
G01X1410363Y266569D02*
X1411142D01*
G01X1396327Y266492D02*
X1396491D01*
G01X1398788Y266450D02*
X1399567D01*
G01X1396902Y266241D02*
X1397107D01*
G01X1448037Y265993D02*
X1447791D01*
G01X1450128D02*
X1449144D01*
G01X1411142Y265982D02*
X1410363D01*
G01X1399567Y265864D02*
X1398788D01*
G01X1449103Y265742D02*
X1449882D01*
G01X1411142Y265731D02*
X1410363D01*
G01X1399567Y265613D02*
X1398788D01*
G01X1449882Y265156D02*
X1449103D01*
G01X1410363Y265103D02*
X1411142D01*
G01X1398788Y264985D02*
X1399567D01*
G01X1396819Y264943D02*
X1395671D01*
G01X1449882Y264904D02*
X1449103D01*
G01X1410404Y264851D02*
X1411388D01*
G01X1409050D02*
X1409296D01*
G01X1408230D02*
X1408476D01*
G01X1398829Y264733D02*
X1399813D01*
G01X1397476D02*
X1397722D01*
G01X1395671D02*
X1397148D01*
G01X1449103Y264276D02*
X1449882D01*
G01X1449144Y264024D02*
X1450128D01*
G01X1447791D02*
X1448037D01*
G01X1402359Y260875D02*
X1402113D01*
G01X1403672D02*
X1403426D01*
G01X1402769Y258906D02*
X1403015D01*
G01X1447569Y256150D02*
X1450325D01*
G01X1443632D02*
X1446388D01*
G01X1439695D02*
X1442451D01*
G01X1435758D02*
X1438514D01*
G01X1431821D02*
X1434577D01*
G01X1427884D02*
X1430640D01*
G01X1423947D02*
X1426703D01*
G01X1420010D02*
X1422766D01*
G01X1416073D02*
X1418829D01*
G01X1412136D02*
X1414892D01*
G01X1408199D02*
X1410955D01*
G01X1407412D02*
X1451506D01*
G01X1395207D02*
X1392451D01*
G01X1399144D02*
X1396388D01*
G01X1406428D02*
X1400916D01*
G01X1408125D02*
X1407879D01*
G01X1409519D02*
X1409273D01*
G01Y254182D02*
X1409519D01*
G01X1407879D02*
X1408125D01*
G01X1449538Y250639D02*
X1409380D01*
G01X1396286Y266702D02*
X1396040Y266660D01*
G01X1396122Y266450D02*
X1396327Y266492D01*
G01X1398829Y266702D02*
X1398624Y266660D01*
G01X1410404Y266820D02*
X1410199Y266778D01*
G01X1449144Y265993D02*
X1448939Y265951D01*
G01X1421191Y290402D02*
G03X1425128Y294339I0J3937D01*
G01X1405443D02*
G03X1409380Y290402I3937J0D01*
G01Y310087D02*
G03X1405443Y306150I0J-3937D01*
G01X1425128D02*
G03X1421191Y310087I-3937J0D01*
G01X1399144Y306150D02*
G03X1395207Y310087I-3937J0D01*
G01Y290402D02*
G03X1399144Y294339I0J3937D01*
G01X1425128Y306150D02*
Y294339D01*
G01X1405443D02*
Y306150D01*
G01X1399144D02*
Y294339D01*
G01X1409380Y310087D02*
X1421191D01*
G01Y290402D02*
X1409380D01*
G01X1390915Y609740D02*
Y568992D01*
G01X1438750Y585921D02*
Y568992D01*
G01Y586315D02*
Y644287D01*
G01X1433631Y589858D02*
Y606394D01*
G01X1430876D02*
Y589858D01*
G01X1436781Y584346D02*
X1438750Y586315D01*
G01X1429694Y589858D02*
Y606394D01*
G01X1426939D02*
Y589858D01*
G01X1425757D02*
Y606394D01*
G01X1423002D02*
Y589858D01*
G01X1421820D02*
Y606394D01*
G01X1419065D02*
Y589858D01*
G01X1417883D02*
Y606394D01*
G01X1415128D02*
Y589858D01*
G01X1413946D02*
Y606394D01*
G01X1411191D02*
Y589858D01*
G01X1410009D02*
Y606394D01*
G01X1407254D02*
Y589858D01*
G01X1406072D02*
Y606394D01*
G01X1396065Y588895D02*
X1396763Y589858D01*
G01X1395368Y587890D02*
X1395942Y588685D01*
G01X1396517Y589858D02*
X1395942Y589062D01*
G01X1395819Y588895D02*
X1395122Y587890D01*
G01X1403317Y606394D02*
Y589858D01*
G01X1402135D02*
Y606394D01*
G01X1399380D02*
Y589858D01*
G01X1398198D02*
Y606394D01*
G01X1395443D02*
Y589858D01*
G01X1394655Y586315D02*
Y613677D01*
G01X1390915Y592614D02*
Y587102D01*
G01X1396763Y587890D02*
X1396065Y588895D01*
G01X1395942Y589062D02*
X1395368Y589858D01*
G01X1395942Y588685D02*
X1396517Y587890D01*
G01X1395122Y589858D02*
X1395819Y588895D01*
G01X1394655Y586315D02*
X1396624Y584346D01*
G01X1430876Y589858D02*
X1433631D01*
G01X1426939D02*
X1429694D01*
G01X1423002D02*
X1425757D01*
G01X1419065D02*
X1421820D01*
G01X1415128D02*
X1417883D01*
G01X1411191D02*
X1413946D01*
G01X1407254D02*
X1410009D01*
G01X1403317D02*
X1406072D01*
G01X1399380D02*
X1402135D01*
G01X1395443D02*
X1398198D01*
G01X1394655D02*
X1438750D01*
G01X1395368D02*
X1395122D01*
G01X1396763D02*
X1396517D01*
G01Y587890D02*
X1396763D01*
G01X1395122D02*
X1395368D01*
G01X1436781Y584346D02*
X1396624D01*
G01X1402529Y647732D02*
Y706394D01*
G01X1442687Y648224D02*
G03X1438750Y644287I0J-3937D01*
G01X1408435Y624110D02*
G03X1412372Y628047I0J3937D01*
G01X1392687D02*
G03X1396624Y624110I3937J0D01*
G01Y643795D02*
G03X1392687Y639858I0J-3937D01*
G01X1412372D02*
G03X1408435Y643795I-3937J0D01*
G01X1448002Y682772D02*
Y648224D01*
G01X1444458Y651374D02*
Y655705D01*
G01X1436256Y650882D02*
X1436387Y650480D01*
G01X1436420Y650346D02*
X1436715Y649441D01*
G01X1436059Y650882D02*
X1436584Y649307D01*
G01X1436466Y601394D02*
X1435810Y599425D01*
G01X1436056D02*
X1436220Y599928D01*
G01X1436630Y601226D02*
X1436261Y600095D01*
G01X1432833Y652626D02*
X1432828Y650839D01*
G01X1432818Y651106D02*
X1432823Y652893D01*
G01X1440128Y652161D02*
Y648224D01*
G01X1439655Y655705D02*
Y651374D01*
G01X1438750Y644287D02*
Y618205D01*
G01X1437569Y606394D02*
Y593795D01*
G01X1435797Y649809D02*
Y649541D01*
G01X1435600Y650882D02*
Y649575D01*
G01X1435482Y600765D02*
Y601100D01*
G01X1435403Y649307D02*
Y650882D01*
G01X1435236Y599425D02*
Y601058D01*
G01X1434990Y601394D02*
Y599425D01*
G01X1434813Y593795D02*
Y606394D01*
G01X1432687Y650390D02*
Y649406D01*
G01X1431820Y650390D02*
Y649406D01*
G01X1431023Y649701D02*
Y649898D01*
G01X1430531Y649701D02*
Y649898D01*
G01X1430285Y649701D02*
Y649898D01*
G01X1431684Y652893D02*
X1431689Y651106D01*
G01X1431680Y650839D02*
X1431674Y652626D01*
G01X1436999Y600095D02*
X1436630Y601226D01*
G01X1437040Y599928D02*
X1437204Y599425D01*
G01X1437372Y650882D02*
X1436846Y649307D01*
G01X1437011Y650346D02*
X1436715Y649441D01*
G01X1437175Y650882D02*
X1437043Y650480D01*
G01X1424959Y652626D02*
X1424954Y650839D01*
G01X1424944Y651106D02*
X1424949Y652893D01*
G01X1430039Y649701D02*
Y649898D01*
G01X1429547Y649701D02*
Y649898D01*
G01X1429301Y649701D02*
Y649898D01*
G01X1429055Y649701D02*
Y649898D01*
G01X1428809D02*
Y649701D01*
G01X1428563D02*
Y649898D01*
G01X1428317Y649701D02*
Y649898D01*
G01X1428070Y649701D02*
Y649898D01*
G01X1427332Y649701D02*
Y649898D01*
G01X1427086Y649701D02*
Y649898D01*
G01X1425856Y649701D02*
Y649898D01*
G01X1425364Y649701D02*
Y649898D01*
G01X1425118Y649701D02*
Y649898D01*
G01X1424872Y649701D02*
Y649898D01*
G01X1424813Y650390D02*
Y649406D01*
G01X1424380Y649701D02*
Y649898D01*
G01X1424133Y649701D02*
Y649898D01*
G01X1423946Y650390D02*
Y649406D01*
G01X1423887Y649701D02*
Y649898D01*
G01X1423641Y649701D02*
Y649898D01*
G01X1423395Y649701D02*
Y649898D01*
G01X1422903Y649701D02*
Y649898D01*
G01X1422657Y649701D02*
Y649898D01*
G01X1422165Y649701D02*
Y649898D01*
G01X1421919Y649701D02*
Y649898D01*
G01X1419950D02*
Y649701D01*
G01X1418966D02*
Y649898D01*
G01X1423810Y652893D02*
X1423815Y651106D01*
G01X1423806Y650839D02*
X1423800Y652626D01*
G01X1437450Y599425D02*
X1436794Y601394D01*
G01X1417085Y652626D02*
X1417080Y650839D01*
G01X1417070Y651106D02*
X1417075Y652893D01*
G01X1409211Y652626D02*
X1409206Y650839D01*
G01X1409196Y651106D02*
X1409201Y652893D01*
G01X1416939Y650390D02*
Y649406D01*
G01X1416072Y650390D02*
Y649406D01*
G01X1412569Y649701D02*
Y649898D01*
G01X1412372Y639858D02*
Y628047D01*
G01X1411092Y649701D02*
Y649898D01*
G01X1409124D02*
Y649701D01*
G01X1409065Y650390D02*
Y649406D01*
G01X1408198Y650390D02*
Y649406D01*
G01X1405187Y649701D02*
Y649898D01*
G01X1415936Y652893D02*
X1415941Y651106D01*
G01X1415931Y650839D02*
X1415926Y652626D01*
G01X1408062Y652893D02*
X1408067Y651106D01*
G01X1408057Y650839D02*
X1408052Y652626D01*
G01X1390259Y593619D02*
X1390915Y594583D01*
G01X1390669D02*
X1390136Y593787D01*
G01X1397411Y601591D02*
X1396755Y599622D01*
G01X1397001D02*
X1397165Y600124D01*
G01X1397575Y601423D02*
X1397206Y600292D01*
G01X1401337Y652626D02*
X1401331Y650839D01*
G01X1401322Y651106D02*
X1401327Y652893D01*
G01X1403710Y649701D02*
Y649898D01*
G01X1401191Y650390D02*
Y649406D01*
G01X1400324Y650390D02*
Y649406D01*
G01X1399773Y649701D02*
Y649898D01*
G01X1397805Y649701D02*
Y649898D01*
G01X1397559Y649701D02*
Y649898D01*
G01X1397067Y649701D02*
Y649898D01*
G01X1396427Y600962D02*
Y601297D01*
G01X1396328Y649898D02*
Y649701D01*
G01X1396181Y599622D02*
Y601255D01*
G01X1396082Y649898D02*
Y649701D01*
G01X1395935Y601591D02*
Y599622D01*
G01X1395606Y600962D02*
Y601297D01*
G01X1395590Y649898D02*
Y649701D01*
G01X1395360Y599622D02*
Y601255D01*
G01X1395114Y601591D02*
Y599622D01*
G01X1395098Y649701D02*
Y649898D01*
G01X1394852D02*
Y649701D01*
G01X1393868Y649898D02*
Y649701D01*
G01X1392687Y628047D02*
Y639858D01*
G01X1391899Y649898D02*
Y649701D01*
G01X1400188Y652893D02*
X1400193Y651106D01*
G01X1400183Y650839D02*
X1400178Y652626D01*
G01X1397944Y600292D02*
X1397575Y601423D01*
G01X1397985Y600124D02*
X1398149Y599622D01*
G01X1398395D02*
X1397739Y601591D01*
G01X1435797Y649541D02*
X1435600Y649307D01*
G01X1435797Y649809D02*
X1435600Y649575D01*
G01X1390915Y649898D02*
Y649701D01*
G01X1390669D02*
Y649898D01*
G01X1390259Y592614D02*
Y593619D01*
G01X1390177Y649898D02*
Y649701D01*
G01X1390013Y593619D02*
Y592614D01*
G01X1435482Y601100D02*
X1435236Y601394D01*
G01Y601058D02*
X1435482Y600765D01*
G01X1396427Y601297D02*
X1396181Y601591D01*
G01Y601255D02*
X1396427Y600962D01*
G01X1395606Y601297D02*
X1395360Y601591D01*
G01Y601255D02*
X1395606Y600962D01*
G01X1444458Y651374D02*
X1439655D01*
G01X1431689Y651106D02*
X1432818D01*
G01X1423815D02*
X1424944D01*
G01X1415941D02*
X1417070D01*
G01X1408067D02*
X1409196D01*
G01X1400193D02*
X1401322D01*
G01X1437175Y650882D02*
X1437372D01*
G01X1436059D02*
X1436256D01*
G01X1435403D02*
X1435600D01*
G01X1401331Y650839D02*
X1400183D01*
G01X1409206D02*
X1408057D01*
G01X1417080D02*
X1415931D01*
G01X1424954D02*
X1423806D01*
G01X1432828D02*
X1431680D01*
G01X1436387Y650480D02*
X1437043D01*
G01X1401313Y650390D02*
X1400202D01*
G01X1409187D02*
X1408076D01*
G01X1417061D02*
X1415950D01*
G01X1424935D02*
X1423824D01*
G01X1432809D02*
X1431698D01*
G01X1436420Y650346D02*
X1437011D01*
G01X1421919Y649701D02*
X1431023D01*
G01X1399773D02*
X1409124D01*
G01X1419950D02*
X1411092D01*
G01X1431698Y649406D02*
X1432809D01*
G01X1423824D02*
X1424935D01*
G01X1415950D02*
X1417061D01*
G01X1408076D02*
X1409187D01*
G01X1400202D02*
X1401313D01*
G01X1435600Y649307D02*
X1435403D01*
G01X1436846D02*
X1436584D01*
G01X1455876Y648224D02*
X1442687D01*
G01X1396624Y643795D02*
X1408435D01*
G01Y624110D02*
X1396624D01*
G01X1434813Y606394D02*
X1437569D01*
G01X1398198D02*
X1395443D01*
G01X1402135D02*
X1399380D01*
G01X1406072D02*
X1403317D01*
G01X1410009D02*
X1407254D01*
G01X1413946D02*
X1411191D01*
G01X1417883D02*
X1415128D01*
G01X1421820D02*
X1419065D01*
G01X1425757D02*
X1423002D01*
G01X1429694D02*
X1426939D01*
G01X1433631D02*
X1430876D01*
G01X1395360Y601591D02*
X1395114D01*
G01X1396181D02*
X1395935D01*
G01X1397739D02*
X1397411D01*
G01X1435236Y601394D02*
X1434990D01*
G01X1436794D02*
X1436466D01*
G01X1397206Y600292D02*
X1397944D01*
G01X1397165Y600124D02*
X1397985D01*
G01X1436261Y600095D02*
X1436999D01*
G01X1436220Y599928D02*
X1437040D01*
G01X1398149Y599622D02*
X1398395D01*
G01X1395935D02*
X1396181D01*
G01X1396755D02*
X1397001D01*
G01X1395114D02*
X1395360D01*
G01X1437204Y599425D02*
X1437450D01*
G01X1435810D02*
X1436056D01*
G01X1434990D02*
X1435236D01*
G01X1390915Y594583D02*
X1390669D01*
G01X1437569Y593795D02*
X1434813D01*
G01X1390013Y592614D02*
X1390259D01*
G01X1440324Y666236D02*
X1441899Y667811D01*
G01X1440324Y659150D02*
X1441899Y657575D01*
G01X1444458Y674012D02*
Y669681D01*
G01X1436783Y659150D02*
X1436796Y659810D01*
G01X1436794Y660738D02*
X1436763Y659150D01*
G01X1435587Y664647D02*
X1435617Y666236D01*
G01X1435597D02*
X1435585Y665575D01*
G01X1432846Y659150D02*
X1432859Y659810D01*
G01X1432857Y660738D02*
X1432826Y659150D01*
G01X1431650Y664647D02*
X1431680Y666236D01*
G01X1431660D02*
X1431648Y665575D01*
G01X1436818Y664735D02*
X1436843Y666236D01*
G01X1436826D02*
X1436816Y665645D01*
G01X1435556Y659150D02*
X1435565Y659740D01*
G01X1435563Y660650D02*
X1435538Y659150D01*
G01X1432881Y664735D02*
X1432906Y666236D01*
G01X1432889D02*
X1432879Y665645D01*
G01X1431619Y659150D02*
X1431628Y659740D01*
G01X1431626Y660650D02*
X1431601Y659150D01*
G01X1436770Y670342D02*
X1436765Y668555D01*
G01X1436755Y668823D02*
X1436760Y670610D01*
G01X1435626Y656563D02*
X1435621Y654776D01*
G01X1435611Y655043D02*
X1435617Y656830D01*
G01X1431689Y674279D02*
X1431684Y672492D01*
G01X1431674Y672760D02*
X1431679Y674547D01*
G01X1441899Y657575D02*
Y667811D01*
G01X1440521Y669681D02*
Y672043D01*
G01Y655705D02*
Y653343D01*
G01X1440324Y666236D02*
Y659150D01*
G01X1440128Y677181D02*
Y673224D01*
G01X1439655Y674012D02*
Y669681D01*
G01X1436779Y654327D02*
Y653343D01*
G01Y672043D02*
Y671059D01*
G01X1436624Y658264D02*
Y657280D01*
G01Y668106D02*
Y667122D01*
G01X1435757Y658264D02*
Y657280D01*
G01Y667122D02*
Y668106D01*
G01X1435602Y653343D02*
Y654327D01*
G01Y671059D02*
Y672043D01*
G01X1432842Y653343D02*
Y654327D01*
G01Y671059D02*
Y672043D01*
G01X1432687Y675980D02*
Y674996D01*
G01X1432647Y682772D02*
Y677161D01*
G01X1432254Y675488D02*
Y675291D01*
G01X1431820Y674996D02*
Y675980D01*
G01X1431665Y654327D02*
Y653343D01*
G01Y672043D02*
Y671059D01*
G01X1430777Y675291D02*
Y675488D01*
G01X1436765Y656830D02*
X1436770Y655043D01*
G01X1436760Y654776D02*
X1436755Y656563D01*
G01X1435621Y670610D02*
X1435626Y668823D01*
G01X1435616Y668555D02*
X1435611Y670342D01*
G01X1432828Y674547D02*
X1432833Y672760D01*
G01X1432823Y672492D02*
X1432818Y674279D01*
G01X1436843Y659150D02*
X1436818Y660650D01*
G01X1436816Y659740D02*
X1436826Y659150D01*
G01X1435565Y665645D02*
X1435556Y666236D01*
G01X1435538D02*
X1435563Y664735D01*
G01X1432906Y659150D02*
X1432881Y660650D01*
G01X1432879Y659740D02*
X1432889Y659150D01*
G01X1431628Y665645D02*
X1431619Y666236D01*
G01X1431601D02*
X1431626Y664735D01*
G01X1436796Y665575D02*
X1436783Y666236D01*
G01X1436763D02*
X1436794Y664647D01*
G01X1435617Y659150D02*
X1435587Y660738D01*
G01X1435585Y659810D02*
X1435597Y659150D01*
G01X1432859Y665575D02*
X1432846Y666236D01*
G01X1432826D02*
X1432857Y664647D01*
G01X1431680Y659150D02*
X1431650Y660738D01*
G01X1431648Y659810D02*
X1431660Y659150D01*
G01X1428909D02*
X1428922Y659810D01*
G01X1428920Y660738D02*
X1428889Y659150D01*
G01X1427713Y664647D02*
X1427743Y666236D01*
G01X1427723D02*
X1427711Y665575D01*
G01X1424972Y659150D02*
X1424985Y659810D01*
G01X1424983Y660738D02*
X1424952Y659150D01*
G01X1423776Y664647D02*
X1423806Y666236D01*
G01X1423786D02*
X1423774Y665575D01*
G01X1421035Y659150D02*
X1421048Y659810D01*
G01X1421046Y660738D02*
X1421015Y659150D01*
G01X1419839Y664647D02*
X1419869Y666236D01*
G01X1419849D02*
X1419837Y665575D01*
G01X1428944Y664735D02*
X1428969Y666236D01*
G01X1428952D02*
X1428942Y665645D01*
G01X1427681Y659150D02*
X1427691Y659740D01*
G01X1427689Y660650D02*
X1427664Y659150D01*
G01X1425007Y664735D02*
X1425032Y666236D01*
G01X1425015D02*
X1425005Y665645D01*
G01X1423744Y659150D02*
X1423754Y659740D01*
G01X1423752Y660650D02*
X1423727Y659150D01*
G01X1421070Y664735D02*
X1421095Y666236D01*
G01X1421078D02*
X1421068Y665645D01*
G01X1419807Y659150D02*
X1419817Y659740D01*
G01X1419815Y660650D02*
X1419790Y659150D01*
G01X1428896Y670342D02*
X1428891Y668555D01*
G01X1428881Y668823D02*
X1428886Y670610D01*
G01X1427752Y656563D02*
X1427747Y654776D01*
G01X1427737Y655043D02*
X1427743Y656830D01*
G01X1423815Y674279D02*
X1423810Y672492D01*
G01X1423800Y672760D02*
X1423805Y674547D01*
G01X1421022Y670342D02*
X1421017Y668555D01*
G01X1421007Y668823D02*
X1421012Y670610D01*
G01X1419878Y656563D02*
X1419873Y654776D01*
G01X1419863Y655043D02*
X1419869Y656830D01*
G01X1428905Y654327D02*
Y653343D01*
G01Y672043D02*
Y671059D01*
G01X1428750Y658264D02*
Y657280D01*
G01Y668106D02*
Y667122D01*
G01X1427883Y658264D02*
Y657280D01*
G01Y667122D02*
Y668106D01*
G01X1427728Y653343D02*
Y654327D01*
G01Y671059D02*
Y672043D01*
G01X1427647Y682772D02*
Y677161D01*
G01X1424968Y653343D02*
Y654327D01*
G01Y671059D02*
Y672043D01*
G01X1424813Y675980D02*
Y674996D01*
G01X1423946D02*
Y675980D01*
G01X1423791Y654327D02*
Y653343D01*
G01Y672043D02*
Y671059D01*
G01X1423395Y675291D02*
Y675488D01*
G01X1421427Y675291D02*
Y675488D01*
G01X1421181Y675291D02*
Y675488D01*
G01X1421031Y654327D02*
Y653343D01*
G01Y672043D02*
Y671059D01*
G01X1420876Y658264D02*
Y657280D01*
G01Y668106D02*
Y667122D01*
G01X1420689Y675291D02*
Y675488D01*
G01X1420009Y658264D02*
Y657280D01*
G01Y667122D02*
Y668106D01*
G01X1419950Y675488D02*
Y675291D01*
G01X1419854Y653343D02*
Y654327D01*
G01Y671059D02*
Y672043D01*
G01X1419704Y675488D02*
Y675291D01*
G01X1419212Y675488D02*
Y675291D01*
G01X1418720D02*
Y675488D01*
G01X1418474D02*
Y675291D01*
G01X1417490Y675488D02*
Y675291D01*
G01X1428891Y656830D02*
X1428896Y655043D01*
G01X1428886Y654776D02*
X1428881Y656563D01*
G01X1427747Y670610D02*
X1427752Y668823D01*
G01X1427742Y668555D02*
X1427737Y670342D01*
G01X1424954Y674547D02*
X1424959Y672760D01*
G01X1424949Y672492D02*
X1424944Y674279D01*
G01X1421017Y656830D02*
X1421022Y655043D01*
G01X1421012Y654776D02*
X1421007Y656563D01*
G01X1419873Y670610D02*
X1419878Y668823D01*
G01X1419868Y668555D02*
X1419863Y670342D01*
G01X1417080Y674547D02*
X1417085Y672760D01*
G01X1417075Y672492D02*
X1417070Y674279D01*
G01X1428969Y659150D02*
X1428944Y660650D01*
G01X1428942Y659740D02*
X1428952Y659150D01*
G01X1427691Y665645D02*
X1427681Y666236D01*
G01X1427664D02*
X1427689Y664735D01*
G01X1425032Y659150D02*
X1425007Y660650D01*
G01X1425005Y659740D02*
X1425015Y659150D01*
G01X1423754Y665645D02*
X1423744Y666236D01*
G01X1423727D02*
X1423752Y664735D01*
G01X1421095Y659150D02*
X1421070Y660650D01*
G01X1421068Y659740D02*
X1421078Y659150D01*
G01X1419817Y665645D02*
X1419807Y666236D01*
G01X1419790D02*
X1419815Y664735D01*
G01X1417158Y659150D02*
X1417133Y660650D01*
G01X1417131Y659740D02*
X1417141Y659150D01*
G01X1428922Y665575D02*
X1428909Y666236D01*
G01X1428889D02*
X1428920Y664647D01*
G01X1427743Y659150D02*
X1427713Y660738D01*
G01X1427711Y659810D02*
X1427723Y659150D01*
G01X1424985Y665575D02*
X1424972Y666236D01*
G01X1424952D02*
X1424983Y664647D01*
G01X1423806Y659150D02*
X1423776Y660738D01*
G01X1423774Y659810D02*
X1423786Y659150D01*
G01X1421048Y665575D02*
X1421035Y666236D01*
G01X1421015D02*
X1421046Y664647D01*
G01X1419869Y659150D02*
X1419839Y660738D01*
G01X1419837Y659810D02*
X1419849Y659150D01*
G01X1417111Y665575D02*
X1417098Y666236D01*
G01X1417078D02*
X1417109Y664647D01*
G01X1417098Y659150D02*
X1417111Y659810D01*
G01X1417109Y660738D02*
X1417078Y659150D01*
G01X1415902Y664647D02*
X1415932Y666236D01*
G01X1415912D02*
X1415900Y665575D01*
G01X1413161Y659150D02*
X1413174Y659810D01*
G01X1413172Y660738D02*
X1413141Y659150D01*
G01X1411965Y664647D02*
X1411995Y666236D01*
G01X1411975D02*
X1411963Y665575D01*
G01X1409224Y659150D02*
X1409237Y659810D01*
G01X1409235Y660738D02*
X1409204Y659150D01*
G01X1408028Y664647D02*
X1408058Y666236D01*
G01X1408038D02*
X1408026Y665575D01*
G01X1405287Y659150D02*
X1405300Y659810D01*
G01X1405298Y660738D02*
X1405267Y659150D01*
G01X1417133Y664735D02*
X1417158Y666236D01*
G01X1417141D02*
X1417131Y665645D01*
G01X1415870Y659150D02*
X1415880Y659740D01*
G01X1415878Y660650D02*
X1415853Y659150D01*
G01X1413196Y664735D02*
X1413221Y666236D01*
G01X1413204D02*
X1413194Y665645D01*
G01X1411933Y659150D02*
X1411943Y659740D01*
G01X1411941Y660650D02*
X1411916Y659150D01*
G01X1409259Y664735D02*
X1409284Y666236D01*
G01X1409267D02*
X1409257Y665645D01*
G01X1407996Y659150D02*
X1408006Y659740D01*
G01X1408004Y660650D02*
X1407979Y659150D01*
G01X1405322Y664735D02*
X1405347Y666236D01*
G01X1405330D02*
X1405320Y665645D01*
G01X1415941Y674279D02*
X1415936Y672492D01*
G01X1415926Y672760D02*
X1415931Y674547D01*
G01X1413148Y670342D02*
X1413143Y668555D01*
G01X1413133Y668823D02*
X1413138Y670610D01*
G01X1412004Y656563D02*
X1411999Y654776D01*
G01X1411989Y655043D02*
X1411994Y656830D01*
G01X1408067Y674279D02*
X1408062Y672492D01*
G01X1408052Y672760D02*
X1408057Y674547D01*
G01X1405274Y670342D02*
X1405269Y668555D01*
G01X1405259Y668823D02*
X1405264Y670610D01*
G01X1417094Y653343D02*
Y654327D01*
G01Y671059D02*
Y672043D01*
G01X1416939Y675980D02*
Y674996D01*
G01X1416072D02*
Y675980D01*
G01X1415917Y654327D02*
Y653343D01*
G01Y672043D02*
Y671059D01*
G01X1415521Y675488D02*
Y675291D01*
G01X1414537Y675488D02*
Y675291D01*
G01X1414291D02*
Y675488D01*
G01X1413799D02*
Y675291D01*
G01X1413307Y675488D02*
Y675291D01*
G01X1413157Y654327D02*
Y653343D01*
G01Y671059D02*
Y672043D01*
G01X1413061Y675488D02*
Y675291D01*
G01X1413002Y658264D02*
Y657280D01*
G01Y668106D02*
Y667122D01*
G01X1412322Y675291D02*
Y675488D01*
G01X1412135Y658264D02*
Y657280D01*
G01Y667122D02*
Y668106D01*
G01X1411980Y653343D02*
Y654327D01*
G01Y672043D02*
Y671059D01*
G01X1411830Y675291D02*
Y675488D01*
G01X1411742Y682772D02*
Y677161D01*
G01X1411584Y675291D02*
Y675488D01*
G01X1409616Y675291D02*
Y675488D01*
G01X1409220Y653343D02*
Y654327D01*
G01Y671059D02*
Y672043D01*
G01X1409065Y675980D02*
Y674996D01*
G01X1408198D02*
Y675980D01*
G01X1408043Y654327D02*
Y653343D01*
G01Y672043D02*
Y671059D01*
G01X1406742Y682772D02*
Y677161D01*
G01X1405679Y675291D02*
Y675488D01*
G01X1405283Y654327D02*
Y653343D01*
G01Y672043D02*
Y671059D01*
G01X1405128Y658264D02*
Y657280D01*
G01Y668106D02*
Y667122D01*
G01X1404261Y658264D02*
Y657280D01*
G01Y667122D02*
Y668106D01*
G01X1404202Y675291D02*
Y675488D01*
G01X1413143Y656830D02*
X1413148Y655043D01*
G01X1413138Y654776D02*
X1413133Y656563D01*
G01X1411999Y670610D02*
X1412004Y668823D01*
G01X1411994Y668555D02*
X1411989Y670342D01*
G01X1409206Y674547D02*
X1409211Y672760D01*
G01X1409201Y672492D02*
X1409196Y674279D01*
G01X1405269Y656830D02*
X1405274Y655043D01*
G01X1405264Y654776D02*
X1405259Y656563D01*
G01X1404125Y670610D02*
X1404130Y668823D01*
G01X1404120Y668555D02*
X1404115Y670342D01*
G01X1415880Y665645D02*
X1415870Y666236D01*
G01X1415853D02*
X1415878Y664735D01*
G01X1413221Y659150D02*
X1413196Y660650D01*
G01X1413194Y659740D02*
X1413204Y659150D01*
G01X1411943Y665645D02*
X1411933Y666236D01*
G01X1411916D02*
X1411941Y664735D01*
G01X1409284Y659150D02*
X1409259Y660650D01*
G01X1409257Y659740D02*
X1409267Y659150D01*
G01X1408006Y665645D02*
X1407996Y666236D01*
G01X1407979D02*
X1408004Y664735D01*
G01X1405347Y659150D02*
X1405322Y660650D01*
G01X1405320Y659740D02*
X1405330Y659150D01*
G01X1404069Y665645D02*
X1404059Y666236D01*
G01X1404042D02*
X1404067Y664735D01*
G01X1415932Y659150D02*
X1415902Y660738D01*
G01X1415900Y659810D02*
X1415912Y659150D01*
G01X1413174Y665575D02*
X1413161Y666236D01*
G01X1413141D02*
X1413172Y664647D01*
G01X1411995Y659150D02*
X1411965Y660738D01*
G01X1411963Y659810D02*
X1411975Y659150D01*
G01X1409237Y665575D02*
X1409224Y666236D01*
G01X1409204D02*
X1409235Y664647D01*
G01X1408058Y659150D02*
X1408028Y660738D01*
G01X1408026Y659810D02*
X1408038Y659150D01*
G01X1405300Y665575D02*
X1405287Y666236D01*
G01X1405267D02*
X1405298Y664647D01*
G01X1404121Y659150D02*
X1404091Y660738D01*
G01X1404089Y659810D02*
X1404101Y659150D01*
G01X1404091Y664647D02*
X1404121Y666236D01*
G01X1404101D02*
X1404089Y665575D01*
G01X1401350Y659150D02*
X1401363Y659810D01*
G01X1401361Y660738D02*
X1401330Y659150D01*
G01X1400154Y664647D02*
X1400184Y666236D01*
G01X1400164D02*
X1400152Y665575D01*
G01X1397413Y659150D02*
X1397426Y659810D01*
G01X1397424Y660738D02*
X1397393Y659150D01*
G01X1396217Y664647D02*
X1396247Y666236D01*
G01X1396227D02*
X1396215Y665575D01*
G01X1404059Y659150D02*
X1404069Y659740D01*
G01X1404067Y660650D02*
X1404042Y659150D01*
G01X1401385Y664735D02*
X1401410Y666236D01*
G01X1401393D02*
X1401383Y665645D01*
G01X1400122Y659150D02*
X1400132Y659740D01*
G01X1400130Y660650D02*
X1400105Y659150D01*
G01X1397448Y664735D02*
X1397473Y666236D01*
G01X1397456D02*
X1397446Y665645D01*
G01X1396185Y659150D02*
X1396195Y659740D01*
G01X1396193Y660650D02*
X1396168Y659150D01*
G01X1404130Y656563D02*
X1404125Y654776D01*
G01X1404115Y655043D02*
X1404120Y656830D01*
G01X1400193Y674279D02*
X1400188Y672492D01*
G01X1400178Y672760D02*
X1400183Y674547D01*
G01X1397400Y670342D02*
X1397394Y668555D01*
G01X1397385Y668823D02*
X1397390Y670610D01*
G01X1396256Y656563D02*
X1396251Y654776D01*
G01X1396241Y655043D02*
X1396246Y656830D01*
G01X1404106Y653343D02*
Y654327D01*
G01Y671059D02*
Y672043D01*
G01X1401346Y654327D02*
Y653343D01*
G01Y671059D02*
Y672043D01*
G01X1401191Y675980D02*
Y674996D01*
G01X1400324D02*
Y675980D01*
G01X1400265Y675488D02*
Y675291D01*
G01X1400169Y653343D02*
Y654327D01*
G01Y672043D02*
Y671059D01*
G01X1398297Y675291D02*
Y675488D01*
G01X1397409Y654327D02*
Y653343D01*
G01Y672043D02*
Y671059D01*
G01X1397254Y658264D02*
Y657280D01*
G01Y668106D02*
Y667122D01*
G01X1396820Y675291D02*
Y675488D01*
G01X1396387Y658264D02*
Y657280D01*
G01Y667122D02*
Y668106D01*
G01X1396232Y653343D02*
Y654327D01*
G01Y671059D02*
Y672043D01*
G01X1394458Y659150D02*
Y666236D01*
G01X1394065Y665065D02*
Y660320D01*
G01X1393861Y666236D02*
Y667811D01*
G01Y657575D02*
Y659150D01*
G01X1401331Y674547D02*
X1401337Y672760D01*
G01X1401327Y672492D02*
X1401322Y674279D01*
G01X1397394Y656830D02*
X1397400Y655043D01*
G01X1397390Y654776D02*
X1397385Y656563D01*
G01X1396251Y670610D02*
X1396256Y668823D01*
G01X1396246Y668555D02*
X1396241Y670342D01*
G01X1401410Y659150D02*
X1401385Y660650D01*
G01X1401383Y659740D02*
X1401393Y659150D01*
G01X1400132Y665645D02*
X1400122Y666236D01*
G01X1400105D02*
X1400130Y664735D01*
G01X1397473Y659150D02*
X1397448Y660650D01*
G01X1397446Y659740D02*
X1397456Y659150D01*
G01X1396195Y665645D02*
X1396185Y666236D01*
G01X1396168D02*
X1396193Y664735D01*
G01X1401363Y665575D02*
X1401350Y666236D01*
G01X1401330D02*
X1401361Y664647D01*
G01X1400184Y659150D02*
X1400154Y660738D01*
G01X1400152Y659810D02*
X1400164Y659150D01*
G01X1397426Y665575D02*
X1397413Y666236D01*
G01X1397393D02*
X1397424Y664647D01*
G01X1396247Y659150D02*
X1396217Y660738D01*
G01X1396215Y659810D02*
X1396227Y659150D01*
G01X1390836Y682772D02*
Y677161D01*
G01X1390423Y675291D02*
Y675488D01*
G01X1406742Y682772D02*
X1390836D01*
G01X1427647D02*
X1411742D01*
G01X1448002D02*
X1432647D01*
G01X1448002Y677181D02*
X1440128D01*
G01X1401313Y675980D02*
X1400202D01*
G01X1409187D02*
X1408076D01*
G01X1417061D02*
X1415950D01*
G01X1424935D02*
X1423824D01*
G01X1432809D02*
X1431698D01*
G01X1423395Y675291D02*
X1432254D01*
G01X1409616D02*
X1400265D01*
G01X1421427D02*
X1411584D01*
G01X1401313Y674996D02*
X1400202D01*
G01X1409187D02*
X1408076D01*
G01X1417061D02*
X1415950D01*
G01X1424935D02*
X1423824D01*
G01X1432809D02*
X1431698D01*
G01X1431679Y674547D02*
X1432828D01*
G01X1423805D02*
X1424954D01*
G01X1415931D02*
X1417080D01*
G01X1408057D02*
X1409206D01*
G01X1400183D02*
X1401331D01*
G01X1401322Y674279D02*
X1400193D01*
G01X1409196D02*
X1408067D01*
G01X1417070D02*
X1415941D01*
G01X1424944D02*
X1423815D01*
G01X1432818D02*
X1431689D01*
G01X1444458Y674012D02*
X1439655D01*
G01X1440128Y673224D02*
X1448002D01*
G01X1401337Y672760D02*
X1400178D01*
G01X1409211D02*
X1408052D01*
G01X1417085D02*
X1415926D01*
G01X1424959D02*
X1423800D01*
G01X1432833D02*
X1431674D01*
G01X1431684Y672492D02*
X1432823D01*
G01X1423810D02*
X1424949D01*
G01X1415936D02*
X1417075D01*
G01X1408062D02*
X1409201D01*
G01X1400188D02*
X1401327D01*
G01X1397409Y672043D02*
X1396232D01*
G01X1401346D02*
X1400169D01*
G01X1405283D02*
X1404106D01*
G01X1409220D02*
X1408043D01*
G01X1413157D02*
X1411980D01*
G01X1417094D02*
X1415917D01*
G01X1421031D02*
X1419854D01*
G01X1424968D02*
X1423791D01*
G01X1428905D02*
X1427728D01*
G01X1432842D02*
X1431665D01*
G01X1436779D02*
X1435602D01*
G01X1444458D02*
X1440521D01*
G01X1397409Y671059D02*
X1396232D01*
G01X1401346D02*
X1400169D01*
G01X1405283D02*
X1404106D01*
G01X1409220D02*
X1408043D01*
G01X1413157D02*
X1411980D01*
G01X1417094D02*
X1415917D01*
G01X1421031D02*
X1419854D01*
G01X1424968D02*
X1423791D01*
G01X1428905D02*
X1427728D01*
G01X1432842D02*
X1431665D01*
G01X1436779D02*
X1435602D01*
G01X1397390Y670610D02*
X1396251D01*
G01X1405264D02*
X1404125D01*
G01X1413138D02*
X1411999D01*
G01X1421012D02*
X1419873D01*
G01X1428886D02*
X1427747D01*
G01X1436760D02*
X1435621D01*
G01X1435611Y670342D02*
X1436770D01*
G01X1427737D02*
X1428896D01*
G01X1419863D02*
X1421022D01*
G01X1411989D02*
X1413148D01*
G01X1404115D02*
X1405274D01*
G01X1396241D02*
X1397400D01*
G01X1444458Y669681D02*
X1439655D01*
G01X1435626Y668823D02*
X1436755D01*
G01X1427752D02*
X1428881D01*
G01X1419878D02*
X1421007D01*
G01X1412004D02*
X1413133D01*
G01X1404130D02*
X1405259D01*
G01X1396256D02*
X1397385D01*
G01X1397394Y668555D02*
X1396246D01*
G01X1405269D02*
X1404120D01*
G01X1413143D02*
X1411994D01*
G01X1421017D02*
X1419868D01*
G01X1428891D02*
X1427742D01*
G01X1436765D02*
X1435616D01*
G01X1397376Y668106D02*
X1396265D01*
G01X1405250D02*
X1404139D01*
G01X1413124D02*
X1412013D01*
G01X1420998D02*
X1419887D01*
G01X1428872D02*
X1427761D01*
G01X1436746D02*
X1435635D01*
G01X1441899Y667811D02*
X1393861D01*
G01X1397376Y667122D02*
X1396265D01*
G01X1405250D02*
X1404139D01*
G01X1413124D02*
X1412013D01*
G01X1420998D02*
X1419887D01*
G01X1428872D02*
X1427761D01*
G01X1436746D02*
X1435635D01*
G01X1397446Y665645D02*
X1396195D01*
G01X1401383D02*
X1400132D01*
G01X1405320D02*
X1404069D01*
G01X1409257D02*
X1408006D01*
G01X1413194D02*
X1411943D01*
G01X1417131D02*
X1415880D01*
G01X1421068D02*
X1419817D01*
G01X1425005D02*
X1423754D01*
G01X1428942D02*
X1427691D01*
G01X1432879D02*
X1431628D01*
G01X1436816D02*
X1435565D01*
G01X1435585Y665575D02*
X1436796D01*
G01X1431648D02*
X1432859D01*
G01X1427711D02*
X1428922D01*
G01X1423774D02*
X1424985D01*
G01X1419837D02*
X1421048D01*
G01X1415900D02*
X1417111D01*
G01X1411963D02*
X1413174D01*
G01X1408026D02*
X1409237D01*
G01X1404089D02*
X1405300D01*
G01X1400152D02*
X1401363D01*
G01X1396215D02*
X1397426D01*
G01X1397435Y665350D02*
X1396206D01*
G01X1401372D02*
X1400143D01*
G01X1405309D02*
X1404080D01*
G01X1409246D02*
X1408017D01*
G01X1413183D02*
X1411954D01*
G01X1417120D02*
X1415891D01*
G01X1421057D02*
X1419828D01*
G01X1424994D02*
X1423765D01*
G01X1428931D02*
X1427702D01*
G01X1432869D02*
X1431639D01*
G01X1436806D02*
X1435576D01*
G01X1435563Y664735D02*
X1436818D01*
G01X1431626D02*
X1432881D01*
G01X1427689D02*
X1428944D01*
G01X1423752D02*
X1425007D01*
G01X1419815D02*
X1421070D01*
G01X1415878D02*
X1417133D01*
G01X1411941D02*
X1413196D01*
G01X1408004D02*
X1409259D01*
G01X1404067D02*
X1405322D01*
G01X1400130D02*
X1401385D01*
G01X1396193D02*
X1397448D01*
G01X1397424Y664647D02*
X1396217D01*
G01X1401361D02*
X1400154D01*
G01X1405298D02*
X1404091D01*
G01X1409235D02*
X1408028D01*
G01X1413172D02*
X1411965D01*
G01X1417109D02*
X1415902D01*
G01X1421046D02*
X1419839D01*
G01X1424983D02*
X1423776D01*
G01X1428920D02*
X1427713D01*
G01X1432857D02*
X1431650D01*
G01X1436794D02*
X1435587D01*
G01X1397435Y664365D02*
X1396206D01*
G01X1401372D02*
X1400143D01*
G01X1405309D02*
X1404080D01*
G01X1409246D02*
X1408017D01*
G01X1413183D02*
X1411954D01*
G01X1417120D02*
X1415891D01*
G01X1421057D02*
X1419828D01*
G01X1424994D02*
X1423765D01*
G01X1428931D02*
X1427702D01*
G01X1432869D02*
X1431639D01*
G01X1436806D02*
X1435576D01*
G01Y661020D02*
X1436806D01*
G01X1431639D02*
X1432869D01*
G01X1427702D02*
X1428931D01*
G01X1423765D02*
X1424994D01*
G01X1419828D02*
X1421057D01*
G01X1415891D02*
X1417120D01*
G01X1411954D02*
X1413183D01*
G01X1408017D02*
X1409246D01*
G01X1404080D02*
X1405309D01*
G01X1400143D02*
X1401372D01*
G01X1396206D02*
X1397435D01*
G01X1435587Y660738D02*
X1436794D01*
G01X1431650D02*
X1432857D01*
G01X1427713D02*
X1428920D01*
G01X1423776D02*
X1424983D01*
G01X1419839D02*
X1421046D01*
G01X1415902D02*
X1417109D01*
G01X1411965D02*
X1413172D01*
G01X1408028D02*
X1409235D01*
G01X1404091D02*
X1405298D01*
G01X1400154D02*
X1401361D01*
G01X1396217D02*
X1397424D01*
G01X1397448Y660650D02*
X1396193D01*
G01X1401385D02*
X1400130D01*
G01X1405322D02*
X1404067D01*
G01X1409259D02*
X1408004D01*
G01X1413196D02*
X1411941D01*
G01X1417133D02*
X1415878D01*
G01X1421070D02*
X1419815D01*
G01X1425007D02*
X1423752D01*
G01X1428944D02*
X1427689D01*
G01X1432881D02*
X1431626D01*
G01X1436818D02*
X1435563D01*
G01X1435576Y660036D02*
X1436806D01*
G01X1431639D02*
X1432869D01*
G01X1427702D02*
X1428931D01*
G01X1423765D02*
X1424994D01*
G01X1419828D02*
X1421057D01*
G01X1415891D02*
X1417120D01*
G01X1411954D02*
X1413183D01*
G01X1408017D02*
X1409246D01*
G01X1404080D02*
X1405309D01*
G01X1400143D02*
X1401372D01*
G01X1396206D02*
X1397435D01*
G01X1397426Y659810D02*
X1396215D01*
G01X1401363D02*
X1400152D01*
G01X1405300D02*
X1404089D01*
G01X1409237D02*
X1408026D01*
G01X1413174D02*
X1411963D01*
G01X1417111D02*
X1415900D01*
G01X1421048D02*
X1419837D01*
G01X1424985D02*
X1423774D01*
G01X1428922D02*
X1427711D01*
G01X1432859D02*
X1431648D01*
G01X1436796D02*
X1435585D01*
G01X1435565Y659740D02*
X1436816D01*
G01X1431628D02*
X1432879D01*
G01X1427691D02*
X1428942D01*
G01X1423754D02*
X1425005D01*
G01X1419817D02*
X1421068D01*
G01X1415880D02*
X1417131D01*
G01X1411943D02*
X1413194D01*
G01X1408006D02*
X1409257D01*
G01X1404069D02*
X1405320D01*
G01X1400132D02*
X1401383D01*
G01X1396195D02*
X1397446D01*
G01X1435635Y658264D02*
X1436746D01*
G01X1427761D02*
X1428872D01*
G01X1419887D02*
X1420998D01*
G01X1412013D02*
X1413124D01*
G01X1404139D02*
X1405250D01*
G01X1396265D02*
X1397376D01*
G01X1393861Y657575D02*
X1441899D01*
G01X1435635Y657280D02*
X1436746D01*
G01X1427761D02*
X1428872D01*
G01X1419887D02*
X1420998D01*
G01X1412013D02*
X1413124D01*
G01X1404139D02*
X1405250D01*
G01X1396265D02*
X1397376D01*
G01X1435617Y656830D02*
X1436765D01*
G01X1427743D02*
X1428891D01*
G01X1419869D02*
X1421017D01*
G01X1411994D02*
X1413143D01*
G01X1404120D02*
X1405269D01*
G01X1396246D02*
X1397394D01*
G01X1397385Y656563D02*
X1396256D01*
G01X1405259D02*
X1404130D01*
G01X1413133D02*
X1412004D01*
G01X1421007D02*
X1419878D01*
G01X1428881D02*
X1427752D01*
G01X1436755D02*
X1435626D01*
G01X1439655Y655705D02*
X1444458D01*
G01X1397400Y655043D02*
X1396241D01*
G01X1405274D02*
X1404115D01*
G01X1413148D02*
X1411989D01*
G01X1421022D02*
X1419863D01*
G01X1428896D02*
X1427737D01*
G01X1436770D02*
X1435611D01*
G01X1435621Y654776D02*
X1436760D01*
G01X1427747D02*
X1428886D01*
G01X1419873D02*
X1421012D01*
G01X1411999D02*
X1413138D01*
G01X1404125D02*
X1405264D01*
G01X1396251D02*
X1397390D01*
G01X1435602Y654327D02*
X1436779D01*
G01X1431665D02*
X1432842D01*
G01X1427728D02*
X1428905D01*
G01X1423791D02*
X1424968D01*
G01X1419854D02*
X1421031D01*
G01X1415917D02*
X1417094D01*
G01X1411980D02*
X1413157D01*
G01X1408043D02*
X1409220D01*
G01X1404106D02*
X1405283D01*
G01X1400169D02*
X1401346D01*
G01X1396232D02*
X1397409D01*
G01X1440521Y653343D02*
X1444458D01*
G01X1397409D02*
X1396232D01*
G01X1401346D02*
X1400169D01*
G01X1405283D02*
X1404106D01*
G01X1409220D02*
X1408043D01*
G01X1413157D02*
X1411980D01*
G01X1417094D02*
X1415917D01*
G01X1421031D02*
X1419854D01*
G01X1424968D02*
X1423791D01*
G01X1428905D02*
X1427728D01*
G01X1432842D02*
X1431665D01*
G01X1436779D02*
X1435602D01*
G01X1401327Y652893D02*
X1400188D01*
G01X1409201D02*
X1408062D01*
G01X1417075D02*
X1415936D01*
G01X1424949D02*
X1423810D01*
G01X1432823D02*
X1431684D01*
G01X1431674Y652626D02*
X1432833D01*
G01X1423800D02*
X1424959D01*
G01X1415926D02*
X1417085D01*
G01X1408052D02*
X1409211D01*
G01X1400178D02*
X1401337D01*
G01X1448002Y652161D02*
X1440128D01*
G01X1398543Y934504D02*
Y917181D01*
G01X1451506Y252607D02*
Y310580D01*
G01D02*
Y284497D01*
G01Y310580D02*
Y284497D01*
G01X1468632Y314517D02*
G03X1472569Y318454I0J3937D01*
G01X1455443Y314517D02*
G03X1451506Y310580I0J-3937D01*
G01X1472569Y353394D02*
Y318454D01*
G01X1468632Y314517D02*
X1455443D01*
G01X1472569Y353394D02*
G03X1468632Y357331I-3937J0D01*
G01X1459813Y618205D02*
Y568992D01*
G01X1455876Y648224D02*
G03X1459813Y652161I0J3937D01*
G01Y687102D02*
G03X1455876Y691039I-3937J0D01*
G01X1459813Y687102D02*
Y652161D01*
G01X1559393Y-410378D02*
X1596998D01*
G01D02*
Y-213060D01*
G01X1617441Y917181D02*
Y-426126D01*
G01X1596998Y-213060D02*
Y-154689D01*
G01X1617441Y-246599D02*
X1634763D01*
G01X1617441Y-10378D02*
X1634763D01*
G01X1617441Y225842D02*
X1634763D01*
G01X1617441Y462063D02*
X1634763D01*
G01X1617441Y698283D02*
X1634763D01*
G01Y934504D02*
Y-443449D01*
M02*
